G04 ================== begin FILE IDENTIFICATION RECORD ==================*
G04 Layout Name:  15126-1b.brd*
G04 Film Name:    DP_REF_L10*
G04 File Format:  Gerber RS274X*
G04 File Origin:  Cadence Allegro 16.6-2015-S079*
G04 Origin Date:  Fri Feb 10 17:23:35 2017*
G04 *
G04 Layer:  BOARD GEOMETRY/PANEL_OUTLINE*
G04 Layer:  BOARD GEOMETRY/DP_REF_L10_TBL*
G04 Layer:  BOARD GEOMETRY/DP_REF_L10_L10*
G04 *
G04 Offset:    (0.00 0.00)*
G04 Mirror:    No*
G04 Mode:      Positive*
G04 Rotation:  0*
G04 FullContactRelief:  No*
G04 UndefLineWidth:     6.00*
G04 ================== end FILE IDENTIFICATION RECORD ====================*
%FSLAX35Y35*MOIN*%
%IR0*IPPOS*OFA0.00000B0.00000*MIA0B0*SFA1.00000B1.00000*%
%ADD10C,.02*%
%ADD11C,.006*%
%ADD12C,.0045*%
%ADD13C,.0056*%
%ADD14C,.00399*%
G75*
%LPD*%
G75*
G54D10*
G01X2026678Y631398D02*
Y458148D01*
G01D02*
X2884178D01*
G01X2026678Y492798D02*
X2884178D01*
G01X2026678Y527448D02*
X2884178D01*
G01X2026678Y562098D02*
X2884178D01*
G01X2026678Y596748D02*
X2884178D01*
G01X2026678Y631398D02*
X2884178D01*
G01X2201678D02*
Y458148D01*
G01X2569178Y631398D02*
Y458148D01*
G01X2674178Y631398D02*
Y458148D01*
G01X2884178Y631398D02*
Y458148D01*
G54D11*
G01X-17372Y-95792D02*
Y-113292D01*
G01X-22394Y-95792D02*
X-12350D01*
G01X-3584Y-113292D02*
Y-95792D01*
G01Y-104250D02*
X-2492Y-102792D01*
X-1400Y-101917D01*
X346Y-101626D01*
X1656Y-101917D01*
X3185Y-103084D01*
X3840Y-104834D01*
Y-113292D01*
G01X17628Y-101626D02*
Y-113292D01*
G01Y-96959D02*
X17191Y-96667D01*
Y-96084D01*
X17628Y-95792D01*
X18065Y-96084D01*
Y-96667D01*
X17628Y-96959D01*
G01X31853Y-111251D02*
X32945Y-112417D01*
X34473Y-113292D01*
X35783D01*
X37093Y-112709D01*
X37966Y-111834D01*
X38403Y-110668D01*
X38185Y-108917D01*
X37311Y-108042D01*
X33381Y-106292D01*
X32508Y-104250D01*
X32945Y-102792D01*
X33818Y-101917D01*
X35128Y-101626D01*
X36438Y-101917D01*
X37748Y-102792D01*
G01X67071Y-117667D02*
X68600Y-118834D01*
X70346Y-119125D01*
X71874Y-118834D01*
X73185Y-117376D01*
X74058Y-115334D01*
Y-101626D01*
G01Y-103959D02*
X73185Y-102792D01*
X71874Y-101917D01*
X70346Y-101626D01*
X68600Y-102209D01*
X67508Y-103375D01*
X66634Y-105417D01*
X66198Y-107459D01*
X66416Y-109209D01*
X67290Y-111251D01*
X68600Y-112709D01*
X70346Y-113292D01*
X71656Y-113000D01*
X73185Y-111834D01*
X74058Y-110668D01*
G01X84353Y-105417D02*
X91340D01*
X90685Y-103375D01*
X89593Y-102209D01*
X88065Y-101626D01*
X86536Y-101917D01*
X85226Y-102792D01*
X84353Y-104834D01*
X83916Y-106584D01*
Y-108334D01*
X84353Y-110084D01*
X85445Y-111834D01*
X86755Y-113000D01*
X88283Y-113292D01*
X89811Y-112709D01*
X91340Y-110959D01*
G01X102071Y-113292D02*
Y-101626D01*
G01Y-103959D02*
X103163Y-102792D01*
X104255Y-101917D01*
X105783Y-101626D01*
X106874Y-101917D01*
X108185Y-102792D01*
G01X118698Y-113292D02*
Y-95792D01*
G01Y-104542D02*
X119790Y-102792D01*
X121100Y-101917D01*
X122410Y-101626D01*
X124374Y-102209D01*
X125685Y-103375D01*
X126558Y-105417D01*
Y-107750D01*
X126121Y-110084D01*
X125248Y-111834D01*
X123720Y-113000D01*
X122410Y-113292D01*
X121100Y-113000D01*
X119790Y-112126D01*
X118698Y-110668D01*
G01X136853Y-105417D02*
X143840D01*
X143185Y-103375D01*
X142093Y-102209D01*
X140565Y-101626D01*
X139036Y-101917D01*
X137726Y-102792D01*
X136853Y-104834D01*
X136416Y-106584D01*
Y-108334D01*
X136853Y-110084D01*
X137945Y-111834D01*
X139255Y-113000D01*
X140783Y-113292D01*
X142311Y-112709D01*
X143840Y-110959D01*
G01X154571Y-113292D02*
Y-101626D01*
G01Y-103959D02*
X155663Y-102792D01*
X156755Y-101917D01*
X158283Y-101626D01*
X159374Y-101917D01*
X160685Y-102792D01*
G01X192628Y-101626D02*
Y-113292D01*
G01Y-96959D02*
X192191Y-96667D01*
Y-96084D01*
X192628Y-95792D01*
X193065Y-96084D01*
Y-96667D01*
X192628Y-96959D01*
G01X206853Y-111251D02*
X207945Y-112417D01*
X209473Y-113292D01*
X210783D01*
X212093Y-112709D01*
X212966Y-111834D01*
X213403Y-110668D01*
X213185Y-108917D01*
X212311Y-108042D01*
X208381Y-106292D01*
X207508Y-104250D01*
X207945Y-102792D01*
X208818Y-101917D01*
X210128Y-101626D01*
X211438Y-101917D01*
X212748Y-102792D01*
G01X241634Y-117667D02*
X243163Y-118834D01*
X244473Y-119125D01*
X246220Y-118542D01*
X247530Y-117084D01*
X248185Y-114458D01*
Y-101626D01*
G01Y-96959D02*
X247748Y-96667D01*
Y-96084D01*
X248185Y-95792D01*
X248621Y-96084D01*
Y-96667D01*
X248185Y-96959D01*
G01X258916Y-101626D02*
Y-109792D01*
X259790Y-111834D01*
X261100Y-113000D01*
X262628Y-113292D01*
X264156Y-113000D01*
X265466Y-111834D01*
X266340Y-109792D01*
G01Y-113292D02*
Y-101626D01*
G01X276853Y-111251D02*
X277945Y-112417D01*
X279473Y-113292D01*
X280783D01*
X282093Y-112709D01*
X282966Y-111834D01*
X283403Y-110668D01*
X283185Y-108917D01*
X282311Y-108042D01*
X278381Y-106292D01*
X277508Y-104250D01*
X277945Y-102792D01*
X278818Y-101917D01*
X280128Y-101626D01*
X281438Y-101917D01*
X282748Y-102792D01*
G01X297628Y-95792D02*
Y-113292D01*
G01X294571Y-101626D02*
X300685D01*
G01X331318Y-113292D02*
Y-98417D01*
X331755Y-96959D01*
X332628Y-96084D01*
X333938Y-95792D01*
X335248Y-96375D01*
X335903Y-97834D01*
G01X333283Y-102792D02*
X328916D01*
G01X350128Y-113292D02*
X348818Y-113000D01*
X347508Y-111834D01*
X346634Y-109792D01*
X346198Y-107459D01*
X346634Y-105125D01*
X347508Y-103084D01*
X348818Y-101917D01*
X350128Y-101626D01*
X351438Y-101917D01*
X352748Y-103084D01*
X353621Y-105125D01*
X353840Y-107459D01*
X353621Y-109792D01*
X352748Y-111834D01*
X351438Y-113000D01*
X350128Y-113292D01*
G01X364571D02*
Y-101626D01*
G01Y-103959D02*
X365663Y-102792D01*
X366755Y-101917D01*
X368283Y-101626D01*
X369374Y-101917D01*
X370685Y-102792D01*
G01X398043Y-118542D02*
X399353Y-119125D01*
X401100Y-118542D01*
X402191Y-117376D01*
X403065Y-115917D01*
X404374Y-111251D01*
X407213Y-101626D01*
G01X400226D02*
X404374Y-111251D01*
G01X420128Y-113292D02*
X418818Y-113000D01*
X417508Y-111834D01*
X416634Y-109792D01*
X416198Y-107459D01*
X416634Y-105125D01*
X417508Y-103084D01*
X418818Y-101917D01*
X420128Y-101626D01*
X421438Y-101917D01*
X422748Y-103084D01*
X423621Y-105125D01*
X423840Y-107459D01*
X423621Y-109792D01*
X422748Y-111834D01*
X421438Y-113000D01*
X420128Y-113292D01*
G01X433916Y-101626D02*
Y-109792D01*
X434790Y-111834D01*
X436100Y-113000D01*
X437628Y-113292D01*
X439156Y-113000D01*
X440466Y-111834D01*
X441340Y-109792D01*
G01Y-113292D02*
Y-101626D01*
G01X452071Y-113292D02*
Y-101626D01*
G01Y-103959D02*
X453163Y-102792D01*
X454255Y-101917D01*
X455783Y-101626D01*
X456874Y-101917D01*
X458185Y-102792D01*
G01X487071Y-113292D02*
Y-101626D01*
G01Y-103959D02*
X488163Y-102792D01*
X489255Y-101917D01*
X490783Y-101626D01*
X491874Y-101917D01*
X493185Y-102792D01*
G01X504353Y-105417D02*
X511340D01*
X510685Y-103375D01*
X509593Y-102209D01*
X508065Y-101626D01*
X506536Y-101917D01*
X505226Y-102792D01*
X504353Y-104834D01*
X503916Y-106584D01*
Y-108334D01*
X504353Y-110084D01*
X505445Y-111834D01*
X506755Y-113000D01*
X508283Y-113292D01*
X509811Y-112709D01*
X511340Y-110959D01*
G01X523818Y-113292D02*
Y-98417D01*
X524255Y-96959D01*
X525128Y-96084D01*
X526438Y-95792D01*
X527748Y-96375D01*
X528403Y-97834D01*
G01X525783Y-102792D02*
X521416D01*
G01X539353Y-105417D02*
X546340D01*
X545685Y-103375D01*
X544593Y-102209D01*
X543065Y-101626D01*
X541536Y-101917D01*
X540226Y-102792D01*
X539353Y-104834D01*
X538916Y-106584D01*
Y-108334D01*
X539353Y-110084D01*
X540445Y-111834D01*
X541755Y-113000D01*
X543283Y-113292D01*
X544811Y-112709D01*
X546340Y-110959D01*
G01X557071Y-113292D02*
Y-101626D01*
G01Y-103959D02*
X558163Y-102792D01*
X559255Y-101917D01*
X560783Y-101626D01*
X561874Y-101917D01*
X563185Y-102792D01*
G01X574353Y-105417D02*
X581340D01*
X580685Y-103375D01*
X579593Y-102209D01*
X578065Y-101626D01*
X576536Y-101917D01*
X575226Y-102792D01*
X574353Y-104834D01*
X573916Y-106584D01*
Y-108334D01*
X574353Y-110084D01*
X575445Y-111834D01*
X576755Y-113000D01*
X578283Y-113292D01*
X579811Y-112709D01*
X581340Y-110959D01*
G01X591416Y-113292D02*
Y-101626D01*
G01Y-104542D02*
X592290Y-103084D01*
X593600Y-101917D01*
X595346Y-101626D01*
X596874Y-101917D01*
X598185Y-103084D01*
X598840Y-105125D01*
Y-113292D01*
G01X616121Y-103084D02*
X614593Y-101917D01*
X613283Y-101626D01*
X611536Y-102209D01*
X610226Y-103375D01*
X609353Y-105417D01*
X609134Y-107459D01*
X609353Y-109501D01*
X610226Y-111251D01*
X611536Y-112709D01*
X613283Y-113292D01*
X614811Y-112709D01*
X616121Y-111542D01*
G01X626853Y-105417D02*
X633840D01*
X633185Y-103375D01*
X632093Y-102209D01*
X630565Y-101626D01*
X629036Y-101917D01*
X627726Y-102792D01*
X626853Y-104834D01*
X626416Y-106584D01*
Y-108334D01*
X626853Y-110084D01*
X627945Y-111834D01*
X629255Y-113000D01*
X630783Y-113292D01*
X632311Y-112709D01*
X633840Y-110959D01*
G01X665128Y-95792D02*
Y-113292D01*
G01X662071Y-101626D02*
X668185D01*
G01X682628Y-113292D02*
X681318Y-113000D01*
X680008Y-111834D01*
X679134Y-109792D01*
X678698Y-107459D01*
X679134Y-105125D01*
X680008Y-103084D01*
X681318Y-101917D01*
X682628Y-101626D01*
X683938Y-101917D01*
X685248Y-103084D01*
X686121Y-105125D01*
X686340Y-107459D01*
X686121Y-109792D01*
X685248Y-111834D01*
X683938Y-113000D01*
X682628Y-113292D01*
G01X716318D02*
Y-98417D01*
X716755Y-96959D01*
X717628Y-96084D01*
X718938Y-95792D01*
X720248Y-96375D01*
X720903Y-97834D01*
G01X718283Y-102792D02*
X713916D01*
G01X735128Y-101626D02*
Y-113292D01*
G01Y-96959D02*
X734691Y-96667D01*
Y-96084D01*
X735128Y-95792D01*
X735565Y-96084D01*
Y-96667D01*
X735128Y-96959D01*
G01X748916Y-113292D02*
Y-101626D01*
G01Y-104542D02*
X749790Y-103084D01*
X751100Y-101917D01*
X752846Y-101626D01*
X754374Y-101917D01*
X755685Y-103084D01*
X756340Y-105125D01*
Y-113292D01*
G01X774058Y-95792D02*
Y-113292D01*
G01Y-110668D02*
X773185Y-112126D01*
X771874Y-113000D01*
X770346Y-113292D01*
X768600Y-112709D01*
X767290Y-111251D01*
X766416Y-109501D01*
X766198Y-107459D01*
X766416Y-105417D01*
X767290Y-103667D01*
X768600Y-102209D01*
X770346Y-101626D01*
X771874Y-101917D01*
X772966Y-102501D01*
X774058Y-103667D01*
G01X805128Y-95792D02*
Y-113292D01*
G01X802071Y-101626D02*
X808185D01*
G01X818916Y-113292D02*
Y-95792D01*
G01Y-104250D02*
X820008Y-102792D01*
X821100Y-101917D01*
X822846Y-101626D01*
X824156Y-101917D01*
X825685Y-103084D01*
X826340Y-104834D01*
Y-113292D01*
G01X836853Y-105417D02*
X843840D01*
X843185Y-103375D01*
X842093Y-102209D01*
X840565Y-101626D01*
X839036Y-101917D01*
X837726Y-102792D01*
X836853Y-104834D01*
X836416Y-106584D01*
Y-108334D01*
X836853Y-110084D01*
X837945Y-111834D01*
X839255Y-113000D01*
X840783Y-113292D01*
X842311Y-112709D01*
X843840Y-110959D01*
G01X870325Y-113292D02*
Y-95792D01*
X874691D01*
X876438Y-96667D01*
X877748Y-97834D01*
X878840Y-99583D01*
X879713Y-101626D01*
X879931Y-104542D01*
X879713Y-107459D01*
X878840Y-109501D01*
X877748Y-111251D01*
X876438Y-112417D01*
X874691Y-113292D01*
X870325D01*
G01X888261D02*
Y-95792D01*
X893501D01*
X895248Y-96667D01*
X896558Y-98709D01*
X896995Y-101042D01*
X896558Y-103375D01*
X895466Y-105125D01*
X893501Y-106001D01*
X888261D01*
G01X927628Y-101626D02*
Y-113292D01*
G01Y-96959D02*
X927191Y-96667D01*
Y-96084D01*
X927628Y-95792D01*
X928065Y-96084D01*
Y-96667D01*
X927628Y-96959D01*
G01X938578Y-113292D02*
Y-101626D01*
G01Y-104834D02*
X939233Y-103375D01*
X940325Y-102209D01*
X941853Y-101626D01*
X943381Y-102209D01*
X944473Y-103375D01*
X945128Y-104834D01*
Y-113292D01*
G01Y-104834D02*
X945783Y-103375D01*
X946874Y-102209D01*
X948403Y-101626D01*
X949931Y-102209D01*
X951023Y-103375D01*
X951678Y-105125D01*
Y-113292D01*
G01X958698Y-119125D02*
Y-101626D01*
G01Y-104250D02*
X959790Y-102792D01*
X960881Y-101917D01*
X962628Y-101626D01*
X964156Y-101917D01*
X965685Y-103375D01*
X966340Y-105417D01*
X966558Y-107459D01*
X966340Y-109501D01*
X965685Y-111542D01*
X964374Y-112709D01*
X962628Y-113292D01*
X961100Y-113000D01*
X959571Y-112126D01*
X958698Y-110959D01*
G01X976853Y-105417D02*
X983840D01*
X983185Y-103375D01*
X982093Y-102209D01*
X980565Y-101626D01*
X979036Y-101917D01*
X977726Y-102792D01*
X976853Y-104834D01*
X976416Y-106584D01*
Y-108334D01*
X976853Y-110084D01*
X977945Y-111834D01*
X979255Y-113000D01*
X980783Y-113292D01*
X982311Y-112709D01*
X983840Y-110959D01*
G01X1001558Y-95792D02*
Y-113292D01*
G01Y-110668D02*
X1000685Y-112126D01*
X999374Y-113000D01*
X997846Y-113292D01*
X996100Y-112709D01*
X994790Y-111251D01*
X993916Y-109501D01*
X993698Y-107459D01*
X993916Y-105417D01*
X994790Y-103667D01*
X996100Y-102209D01*
X997846Y-101626D01*
X999374Y-101917D01*
X1000466Y-102501D01*
X1001558Y-103667D01*
G01X1019058Y-113292D02*
Y-101626D01*
G01Y-103667D02*
X1018185Y-102501D01*
X1016874Y-101917D01*
X1015346Y-101626D01*
X1013818Y-102209D01*
X1012508Y-103375D01*
X1011634Y-105125D01*
X1011198Y-107459D01*
X1011634Y-109792D01*
X1012508Y-111542D01*
X1013818Y-112709D01*
X1015346Y-113292D01*
X1016874Y-113000D01*
X1018185Y-112126D01*
X1019058Y-110959D01*
G01X1028916Y-113292D02*
Y-101626D01*
G01Y-104542D02*
X1029790Y-103084D01*
X1031100Y-101917D01*
X1032846Y-101626D01*
X1034374Y-101917D01*
X1035685Y-103084D01*
X1036340Y-105125D01*
Y-113292D01*
G01X1053621Y-103084D02*
X1052093Y-101917D01*
X1050783Y-101626D01*
X1049036Y-102209D01*
X1047726Y-103375D01*
X1046853Y-105417D01*
X1046634Y-107459D01*
X1046853Y-109501D01*
X1047726Y-111251D01*
X1049036Y-112709D01*
X1050783Y-113292D01*
X1052311Y-112709D01*
X1053621Y-111542D01*
G01X1064353Y-105417D02*
X1071340D01*
X1070685Y-103375D01*
X1069593Y-102209D01*
X1068065Y-101626D01*
X1066536Y-101917D01*
X1065226Y-102792D01*
X1064353Y-104834D01*
X1063916Y-106584D01*
Y-108334D01*
X1064353Y-110084D01*
X1065445Y-111834D01*
X1066755Y-113000D01*
X1068283Y-113292D01*
X1069811Y-112709D01*
X1071340Y-110959D01*
G01X1102628Y-95792D02*
Y-113292D01*
G01X1099571Y-101626D02*
X1105685D01*
G01X1117071Y-113292D02*
Y-101626D01*
G01Y-103959D02*
X1118163Y-102792D01*
X1119255Y-101917D01*
X1120783Y-101626D01*
X1121874Y-101917D01*
X1123185Y-102792D01*
G01X1141558Y-113292D02*
Y-101626D01*
G01Y-103667D02*
X1140685Y-102501D01*
X1139374Y-101917D01*
X1137846Y-101626D01*
X1136318Y-102209D01*
X1135008Y-103375D01*
X1134134Y-105125D01*
X1133698Y-107459D01*
X1134134Y-109792D01*
X1135008Y-111542D01*
X1136318Y-112709D01*
X1137846Y-113292D01*
X1139374Y-113000D01*
X1140685Y-112126D01*
X1141558Y-110959D01*
G01X1158621Y-103084D02*
X1157093Y-101917D01*
X1155783Y-101626D01*
X1154036Y-102209D01*
X1152726Y-103375D01*
X1151853Y-105417D01*
X1151634Y-107459D01*
X1151853Y-109501D01*
X1152726Y-111251D01*
X1154036Y-112709D01*
X1155783Y-113292D01*
X1157311Y-112709D01*
X1158621Y-111542D01*
G01X1169353Y-105417D02*
X1176340D01*
X1175685Y-103375D01*
X1174593Y-102209D01*
X1173065Y-101626D01*
X1171536Y-101917D01*
X1170226Y-102792D01*
X1169353Y-104834D01*
X1168916Y-106584D01*
Y-108334D01*
X1169353Y-110084D01*
X1170445Y-111834D01*
X1171755Y-113000D01*
X1173283Y-113292D01*
X1174811Y-112709D01*
X1176340Y-110959D01*
G01X1186853Y-111251D02*
X1187945Y-112417D01*
X1189473Y-113292D01*
X1190783D01*
X1192093Y-112709D01*
X1192966Y-111834D01*
X1193403Y-110668D01*
X1193185Y-108917D01*
X1192311Y-108042D01*
X1188381Y-106292D01*
X1187508Y-104250D01*
X1187945Y-102792D01*
X1188818Y-101917D01*
X1190128Y-101626D01*
X1191438Y-101917D01*
X1192748Y-102792D01*
G01X1225128Y-101626D02*
Y-113292D01*
G01Y-96959D02*
X1224691Y-96667D01*
Y-96084D01*
X1225128Y-95792D01*
X1225565Y-96084D01*
Y-96667D01*
X1225128Y-96959D01*
G01X1238916Y-113292D02*
Y-101626D01*
G01Y-104542D02*
X1239790Y-103084D01*
X1241100Y-101917D01*
X1242846Y-101626D01*
X1244374Y-101917D01*
X1245685Y-103084D01*
X1246340Y-105125D01*
Y-113292D01*
G01X1277628D02*
Y-95792D01*
G01X1299058Y-113292D02*
Y-101626D01*
G01Y-103667D02*
X1298185Y-102501D01*
X1296874Y-101917D01*
X1295346Y-101626D01*
X1293818Y-102209D01*
X1292508Y-103375D01*
X1291634Y-105125D01*
X1291198Y-107459D01*
X1291634Y-109792D01*
X1292508Y-111542D01*
X1293818Y-112709D01*
X1295346Y-113292D01*
X1296874Y-113000D01*
X1298185Y-112126D01*
X1299058Y-110959D01*
G01X1308043Y-118542D02*
X1309353Y-119125D01*
X1311100Y-118542D01*
X1312191Y-117376D01*
X1313065Y-115917D01*
X1314374Y-111251D01*
X1317213Y-101626D01*
G01X1310226D02*
X1314374Y-111251D01*
G01X1326853Y-105417D02*
X1333840D01*
X1333185Y-103375D01*
X1332093Y-102209D01*
X1330565Y-101626D01*
X1329036Y-101917D01*
X1327726Y-102792D01*
X1326853Y-104834D01*
X1326416Y-106584D01*
Y-108334D01*
X1326853Y-110084D01*
X1327945Y-111834D01*
X1329255Y-113000D01*
X1330783Y-113292D01*
X1332311Y-112709D01*
X1333840Y-110959D01*
G01X1344571Y-113292D02*
Y-101626D01*
G01Y-103959D02*
X1345663Y-102792D01*
X1346755Y-101917D01*
X1348283Y-101626D01*
X1349374Y-101917D01*
X1350685Y-102792D01*
G01X1378261Y-95792D02*
Y-113292D01*
X1386995D01*
G01X1400128D02*
Y-95792D01*
X1397508Y-99292D01*
G01Y-113292D02*
X1402748D01*
G01X1417628Y-95792D02*
X1415881Y-96375D01*
X1414571Y-97834D01*
X1413698Y-99583D01*
X1413043Y-101917D01*
X1412825Y-104542D01*
X1413043Y-107167D01*
X1413698Y-109501D01*
X1414571Y-111251D01*
X1415881Y-112709D01*
X1417628Y-113292D01*
X1419374Y-112709D01*
X1420685Y-111251D01*
X1421558Y-109501D01*
X1422213Y-107167D01*
X1422431Y-104542D01*
X1422213Y-101917D01*
X1421558Y-99583D01*
X1420685Y-97834D01*
X1419374Y-96375D01*
X1417628Y-95792D01*
G01X1435128Y-113875D02*
X1434691Y-113584D01*
Y-113000D01*
X1435128Y-112709D01*
X1435565Y-113000D01*
Y-113584D01*
X1435128Y-113875D01*
G01X2079178Y467898D02*
Y485398D01*
X2076558Y481898D01*
G01Y467898D02*
X2081798D01*
G01X2096678Y485398D02*
X2094931Y484815D01*
X2093621Y483356D01*
X2092748Y481607D01*
X2092093Y479273D01*
X2091875Y476648D01*
X2092093Y474023D01*
X2092748Y471689D01*
X2093621Y469939D01*
X2094931Y468481D01*
X2096678Y467898D01*
X2098424Y468481D01*
X2099735Y469939D01*
X2100608Y471689D01*
X2101263Y474023D01*
X2101481Y476648D01*
X2101263Y479273D01*
X2100608Y481607D01*
X2099735Y483356D01*
X2098424Y484815D01*
X2096678Y485398D01*
G01X2114178D02*
X2112431Y484815D01*
X2111121Y483356D01*
X2110248Y481607D01*
X2109593Y479273D01*
X2109375Y476648D01*
X2109593Y474023D01*
X2110248Y471689D01*
X2111121Y469939D01*
X2112431Y468481D01*
X2114178Y467898D01*
X2115924Y468481D01*
X2117235Y469939D01*
X2118108Y471689D01*
X2118763Y474023D01*
X2118981Y476648D01*
X2118763Y479273D01*
X2118108Y481607D01*
X2117235Y483356D01*
X2115924Y484815D01*
X2114178Y485398D01*
G01X2131678Y467315D02*
X2131241Y467606D01*
Y468190D01*
X2131678Y468481D01*
X2132115Y468190D01*
Y467606D01*
X2131678Y467315D01*
G01X2149178Y485398D02*
X2147431Y484815D01*
X2146121Y483356D01*
X2145248Y481607D01*
X2144593Y479273D01*
X2144375Y476648D01*
X2144593Y474023D01*
X2145248Y471689D01*
X2146121Y469939D01*
X2147431Y468481D01*
X2149178Y467898D01*
X2150924Y468481D01*
X2152235Y469939D01*
X2153108Y471689D01*
X2153763Y474023D01*
X2153981Y476648D01*
X2153763Y479273D01*
X2153108Y481607D01*
X2152235Y483356D01*
X2150924Y484815D01*
X2149178Y485398D01*
G01X2084216Y504589D02*
X2085745Y503131D01*
X2087491Y502548D01*
X2089238Y503131D01*
X2090766Y504881D01*
X2091858Y507506D01*
X2092295Y510131D01*
Y513339D01*
X2091858Y515964D01*
X2090766Y518298D01*
X2089456Y519465D01*
X2087928Y520048D01*
X2086181Y519465D01*
X2084871Y518298D01*
X2083998Y516548D01*
X2083561Y514214D01*
X2083998Y512173D01*
X2085090Y510131D01*
X2086400Y508964D01*
X2087928Y508673D01*
X2089674Y509256D01*
X2090985Y510715D01*
X2092295Y513339D01*
G01X2100625Y505172D02*
X2101934Y503714D01*
X2103463Y502840D01*
X2105428Y502548D01*
X2107393Y503131D01*
X2108921Y504298D01*
X2110013Y506339D01*
X2110231Y508673D01*
X2109795Y511006D01*
X2108703Y512465D01*
X2107174Y513631D01*
X2105646Y513923D01*
X2104118Y513631D01*
X2102153Y512465D01*
X2102808Y520048D01*
X2108703D01*
G01X2122928Y501965D02*
X2122491Y502256D01*
Y502840D01*
X2122928Y503131D01*
X2123365Y502840D01*
Y502256D01*
X2122928Y501965D01*
G01X2140428Y520048D02*
X2138681Y519465D01*
X2137371Y518006D01*
X2136498Y516257D01*
X2135843Y513923D01*
X2135625Y511298D01*
X2135843Y508673D01*
X2136498Y506339D01*
X2137371Y504589D01*
X2138681Y503131D01*
X2140428Y502548D01*
X2142174Y503131D01*
X2143485Y504589D01*
X2144358Y506339D01*
X2145013Y508673D01*
X2145231Y511298D01*
X2145013Y513923D01*
X2144358Y516257D01*
X2143485Y518006D01*
X2142174Y519465D01*
X2140428Y520048D01*
G01X2087928Y537198D02*
X2089456Y537490D01*
X2091203Y538364D01*
X2092295Y539822D01*
X2092731Y541865D01*
X2092295Y543906D01*
X2090985Y545656D01*
X2089020Y546531D01*
X2086836D01*
X2085526Y547115D01*
X2084434Y548573D01*
X2083998Y550614D01*
X2084653Y552656D01*
X2086181Y554115D01*
X2087928Y554698D01*
X2089674Y554115D01*
X2091203Y552656D01*
X2091858Y550614D01*
X2091421Y548573D01*
X2090330Y547115D01*
X2089020Y546531D01*
X2086836D01*
X2084871Y545656D01*
X2083561Y543906D01*
X2083125Y541865D01*
X2083561Y539822D01*
X2084653Y538364D01*
X2086400Y537490D01*
X2087928Y537198D01*
G01X2100625Y539822D02*
X2101934Y538364D01*
X2103463Y537490D01*
X2105428Y537198D01*
X2107393Y537781D01*
X2108921Y538948D01*
X2110013Y540989D01*
X2110231Y543323D01*
X2109795Y545656D01*
X2108703Y547115D01*
X2107174Y548281D01*
X2105646Y548573D01*
X2104118Y548281D01*
X2102153Y547115D01*
X2102808Y554698D01*
X2108703D01*
G01X2122928Y536615D02*
X2122491Y536906D01*
Y537490D01*
X2122928Y537781D01*
X2123365Y537490D01*
Y536906D01*
X2122928Y536615D01*
G01X2140428Y554698D02*
X2138681Y554115D01*
X2137371Y552656D01*
X2136498Y550907D01*
X2135843Y548573D01*
X2135625Y545948D01*
X2135843Y543323D01*
X2136498Y540989D01*
X2137371Y539239D01*
X2138681Y537781D01*
X2140428Y537198D01*
X2142174Y537781D01*
X2143485Y539239D01*
X2144358Y540989D01*
X2145013Y543323D01*
X2145231Y545948D01*
X2145013Y548573D01*
X2144358Y550907D01*
X2143485Y552656D01*
X2142174Y554115D01*
X2140428Y554698D01*
G01X2087491Y571848D02*
X2087928Y575639D01*
X2088583Y578848D01*
X2089456Y581765D01*
X2090548Y584973D01*
X2092295Y589348D01*
X2083561D01*
G01X2100625Y575348D02*
X2101934Y573306D01*
X2103681Y572140D01*
X2105646Y571848D01*
X2107393Y572140D01*
X2109140Y573598D01*
X2110231Y575348D01*
X2110450Y577098D01*
X2110013Y579139D01*
X2108485Y580598D01*
X2106956Y581181D01*
X2104991D01*
G01X2106956D02*
X2108266Y582056D01*
X2109358Y583514D01*
X2109795Y585264D01*
X2109358Y587015D01*
X2108266Y588473D01*
X2106301Y589348D01*
X2104336Y589056D01*
X2102371Y587889D01*
G01X2122928Y571265D02*
X2122491Y571556D01*
Y572140D01*
X2122928Y572431D01*
X2123365Y572140D01*
Y571556D01*
X2122928Y571265D01*
G01X2140428Y589348D02*
X2138681Y588765D01*
X2137371Y587306D01*
X2136498Y585557D01*
X2135843Y583223D01*
X2135625Y580598D01*
X2135843Y577973D01*
X2136498Y575639D01*
X2137371Y573889D01*
X2138681Y572431D01*
X2140428Y571848D01*
X2142174Y572431D01*
X2143485Y573889D01*
X2144358Y575639D01*
X2145013Y577973D01*
X2145231Y580598D01*
X2145013Y583223D01*
X2144358Y585557D01*
X2143485Y587306D01*
X2142174Y588765D01*
X2140428Y589348D01*
G01X2050308Y623998D02*
X2055548D01*
G01X2052928D02*
Y606498D01*
G01X2050308D02*
X2055548D01*
G01X2064751D02*
Y623998D01*
X2070428Y609415D01*
X2076105Y623998D01*
Y606498D01*
G01X2083561D02*
Y623998D01*
X2088801D01*
X2090548Y623123D01*
X2091858Y621081D01*
X2092295Y618748D01*
X2091858Y616415D01*
X2090766Y614665D01*
X2088801Y613789D01*
X2083561D01*
G01X2104336Y600665D02*
X2102153Y603581D01*
X2101061Y606498D01*
Y618164D01*
X2102153Y621081D01*
X2104336Y623998D01*
G01X2122928Y606498D02*
X2121181Y606790D01*
X2119653Y607956D01*
X2118343Y609706D01*
X2117469Y611748D01*
X2117033Y614081D01*
Y616415D01*
X2117469Y618748D01*
X2118343Y620790D01*
X2119653Y622539D01*
X2121181Y623706D01*
X2122928Y623998D01*
X2124674Y623706D01*
X2126203Y622539D01*
X2127513Y620790D01*
X2128387Y618748D01*
X2128823Y616415D01*
Y614081D01*
X2128387Y611748D01*
X2127513Y609706D01*
X2126203Y607956D01*
X2124674Y606790D01*
X2122928Y606498D01*
G01X2136716D02*
Y623998D01*
G01Y615540D02*
X2137808Y616998D01*
X2138900Y617873D01*
X2140646Y618164D01*
X2141956Y617873D01*
X2143485Y616706D01*
X2144140Y614956D01*
Y606498D01*
G01X2151378D02*
Y618164D01*
G01Y614956D02*
X2152033Y616415D01*
X2153125Y617581D01*
X2154653Y618164D01*
X2156181Y617581D01*
X2157273Y616415D01*
X2157928Y614956D01*
Y606498D01*
G01Y614956D02*
X2158583Y616415D01*
X2159674Y617581D01*
X2161203Y618164D01*
X2162731Y617581D01*
X2163823Y616415D01*
X2164478Y614665D01*
Y606498D01*
G01X2176520Y600665D02*
X2178703Y603581D01*
X2179795Y606498D01*
Y618164D01*
X2178703Y621081D01*
X2176520Y623998D01*
G01X2028425Y641148D02*
Y658648D01*
X2032791D01*
X2034538Y657773D01*
X2035848Y656606D01*
X2036940Y654857D01*
X2037813Y652814D01*
X2038031Y649898D01*
X2037813Y646981D01*
X2036940Y644939D01*
X2035848Y643189D01*
X2034538Y642023D01*
X2032791Y641148D01*
X2028425D01*
G01X2046361D02*
Y658648D01*
X2051601D01*
X2053348Y657773D01*
X2054658Y655731D01*
X2055095Y653398D01*
X2054658Y651065D01*
X2053566Y649315D01*
X2051601Y648439D01*
X2046361D01*
G01X2083108Y658648D02*
X2088348D01*
G01X2085728D02*
Y641148D01*
G01X2083108D02*
X2088348D01*
G01X2097551D02*
Y658648D01*
X2103228Y644065D01*
X2108905Y658648D01*
Y641148D01*
G01X2116361D02*
Y658648D01*
X2121601D01*
X2123348Y657773D01*
X2124658Y655731D01*
X2125095Y653398D01*
X2124658Y651065D01*
X2123566Y649315D01*
X2121601Y648439D01*
X2116361D01*
G01X2142595Y641148D02*
X2133861D01*
Y658648D01*
X2142595D01*
G01X2139101Y650190D02*
X2133861D01*
G01X2150925Y641148D02*
Y658648D01*
X2155291D01*
X2157038Y657773D01*
X2158348Y656606D01*
X2159440Y654857D01*
X2160313Y652814D01*
X2160531Y649898D01*
X2160313Y646981D01*
X2159440Y644939D01*
X2158348Y643189D01*
X2157038Y642023D01*
X2155291Y641148D01*
X2150925D01*
G01X2167769D02*
X2173228Y658648D01*
X2178687Y641148D01*
G01X2176721Y647273D02*
X2169734D01*
G01X2185706Y641148D02*
Y658648D01*
X2195750Y641148D01*
Y658648D01*
G01X2213031Y657189D02*
X2211721Y658065D01*
X2210193Y658648D01*
X2208446D01*
X2206481Y657773D01*
X2204953Y656315D01*
X2203861Y654564D01*
X2202988Y651648D01*
X2202769Y649023D01*
X2203206Y646398D01*
X2203861Y644648D01*
X2205171Y642898D01*
X2206700Y641731D01*
X2208228Y641148D01*
X2209756D01*
X2211285Y641731D01*
X2212595Y642606D01*
X2213687Y643772D01*
G01X2230095Y641148D02*
X2221361D01*
Y658648D01*
X2230095D01*
G01X2226601Y650190D02*
X2221361D01*
G01X2260728Y658648D02*
Y641148D01*
G01X2255706Y658648D02*
X2265750D01*
G01X2272769Y641148D02*
X2278228Y658648D01*
X2283687Y641148D01*
G01X2281721Y647273D02*
X2274734D01*
G01X2297474Y650481D02*
X2298348Y651356D01*
X2299003Y652814D01*
X2299440Y654857D01*
X2299003Y656606D01*
X2298130Y657773D01*
X2296601Y658648D01*
X2290706D01*
Y641148D01*
X2297911D01*
X2299440Y642314D01*
X2300313Y644065D01*
X2300750Y646106D01*
X2300313Y648148D01*
X2299003Y649898D01*
X2297474Y650481D01*
X2290706D01*
G01X2308861Y658648D02*
Y641148D01*
X2317595D01*
G01X2335095D02*
X2326361D01*
Y658648D01*
X2335095D01*
G01X2331601Y650190D02*
X2326361D01*
G01X2348228Y640565D02*
X2347791Y640856D01*
Y641440D01*
X2348228Y641731D01*
X2348665Y641440D01*
Y640856D01*
X2348228Y640565D01*
G01Y648439D02*
X2347791Y648731D01*
Y649315D01*
X2348228Y649606D01*
X2348665Y649315D01*
Y648731D01*
X2348228Y648439D01*
G01X2378861Y658648D02*
Y641148D01*
X2387595D01*
G01X2400728D02*
Y658648D01*
X2398108Y655148D01*
G01Y641148D02*
X2403348D01*
G01X2418228Y658648D02*
X2416481Y658065D01*
X2415171Y656606D01*
X2414298Y654857D01*
X2413643Y652523D01*
X2413425Y649898D01*
X2413643Y647273D01*
X2414298Y644939D01*
X2415171Y643189D01*
X2416481Y641731D01*
X2418228Y641148D01*
X2419974Y641731D01*
X2421285Y643189D01*
X2422158Y644939D01*
X2422813Y647273D01*
X2423031Y649898D01*
X2422813Y652523D01*
X2422158Y654857D01*
X2421285Y656606D01*
X2419974Y658065D01*
X2418228Y658648D01*
G01X2301875Y471398D02*
X2303184Y469356D01*
X2304931Y468190D01*
X2306896Y467898D01*
X2308643Y468190D01*
X2310390Y469648D01*
X2311481Y471398D01*
X2311700Y473148D01*
X2311263Y475189D01*
X2309735Y476648D01*
X2308206Y477231D01*
X2306241D01*
G01X2308206D02*
X2309516Y478106D01*
X2310608Y479564D01*
X2311045Y481314D01*
X2310608Y483065D01*
X2309516Y484523D01*
X2307551Y485398D01*
X2305586Y485106D01*
X2303621Y483939D01*
G01X2324178Y467315D02*
X2323741Y467606D01*
Y468190D01*
X2324178Y468481D01*
X2324615Y468190D01*
Y467606D01*
X2324178Y467315D01*
G01X2337966Y469939D02*
X2339495Y468481D01*
X2341241Y467898D01*
X2342988Y468481D01*
X2344516Y470231D01*
X2345608Y472856D01*
X2346045Y475481D01*
Y478689D01*
X2345608Y481314D01*
X2344516Y483648D01*
X2343206Y484815D01*
X2341678Y485398D01*
X2339931Y484815D01*
X2338621Y483648D01*
X2337748Y481898D01*
X2337311Y479564D01*
X2337748Y477523D01*
X2338840Y475481D01*
X2340150Y474314D01*
X2341678Y474023D01*
X2343424Y474606D01*
X2344735Y476065D01*
X2346045Y478689D01*
G01X2355466Y469939D02*
X2356995Y468481D01*
X2358741Y467898D01*
X2360488Y468481D01*
X2362016Y470231D01*
X2363108Y472856D01*
X2363545Y475481D01*
Y478689D01*
X2363108Y481314D01*
X2362016Y483648D01*
X2360706Y484815D01*
X2359178Y485398D01*
X2357431Y484815D01*
X2356121Y483648D01*
X2355248Y481898D01*
X2354811Y479564D01*
X2355248Y477523D01*
X2356340Y475481D01*
X2357650Y474314D01*
X2359178Y474023D01*
X2360924Y474606D01*
X2362235Y476065D01*
X2363545Y478689D01*
G01X2372748Y467315D02*
X2380608Y485398D01*
G01X2394178Y467898D02*
Y485398D01*
X2391558Y481898D01*
G01Y467898D02*
X2396798D01*
G01X2407530Y482481D02*
X2408840Y484231D01*
X2410368Y485106D01*
X2412115Y485398D01*
X2414298Y484815D01*
X2415826Y483356D01*
X2416263Y481607D01*
X2416045Y479856D01*
X2415171Y478398D01*
X2410805Y475481D01*
X2408840Y473440D01*
X2407530Y470522D01*
X2407093Y467898D01*
X2416263D01*
G01X2429178Y467315D02*
X2428741Y467606D01*
Y468190D01*
X2429178Y468481D01*
X2429615Y468190D01*
Y467606D01*
X2429178Y467315D01*
G01X2441875Y470522D02*
X2443184Y469064D01*
X2444713Y468190D01*
X2446678Y467898D01*
X2448643Y468481D01*
X2450171Y469648D01*
X2451263Y471689D01*
X2451481Y474023D01*
X2451045Y476356D01*
X2449953Y477815D01*
X2448424Y478981D01*
X2446896Y479273D01*
X2445368Y478981D01*
X2443403Y477815D01*
X2444058Y485398D01*
X2449953D01*
G01X2460030Y482481D02*
X2461340Y484231D01*
X2462868Y485106D01*
X2464615Y485398D01*
X2466798Y484815D01*
X2468326Y483356D01*
X2468763Y481607D01*
X2468545Y479856D01*
X2467671Y478398D01*
X2463305Y475481D01*
X2461340Y473440D01*
X2460030Y470522D01*
X2459593Y467898D01*
X2468763D01*
G01X2293125Y501965D02*
X2302731Y514798D01*
G01X2297928Y517131D02*
Y499631D01*
G01X2302731Y501965D02*
X2293125Y514798D01*
G01X2291378Y508381D02*
X2304478D01*
G01X2318048Y502548D02*
Y520048D01*
X2309969Y507506D01*
X2320887D01*
G01X2332928Y501965D02*
X2332491Y502256D01*
Y502840D01*
X2332928Y503131D01*
X2333365Y502840D01*
Y502256D01*
X2332928Y501965D01*
G01X2350428Y520048D02*
X2348681Y519465D01*
X2347371Y518006D01*
X2346498Y516257D01*
X2345843Y513923D01*
X2345625Y511298D01*
X2345843Y508673D01*
X2346498Y506339D01*
X2347371Y504589D01*
X2348681Y503131D01*
X2350428Y502548D01*
X2352174Y503131D01*
X2353485Y504589D01*
X2354358Y506339D01*
X2355013Y508673D01*
X2355231Y511298D01*
X2355013Y513923D01*
X2354358Y516257D01*
X2353485Y518006D01*
X2352174Y519465D01*
X2350428Y520048D01*
G01X2363780Y517131D02*
X2365090Y518881D01*
X2366618Y519756D01*
X2368365Y520048D01*
X2370548Y519465D01*
X2372076Y518006D01*
X2372513Y516257D01*
X2372295Y514506D01*
X2371421Y513048D01*
X2367055Y510131D01*
X2365090Y508090D01*
X2363780Y505172D01*
X2363343Y502548D01*
X2372513D01*
G01X2381498Y501965D02*
X2389358Y520048D01*
G01X2402928Y502548D02*
Y520048D01*
X2400308Y516548D01*
G01Y502548D02*
X2405548D01*
G01X2420428D02*
Y520048D01*
X2417808Y516548D01*
G01Y502548D02*
X2423048D01*
G01X2437928Y501965D02*
X2437491Y502256D01*
Y502840D01*
X2437928Y503131D01*
X2438365Y502840D01*
Y502256D01*
X2437928Y501965D01*
G01X2451716Y504589D02*
X2453245Y503131D01*
X2454991Y502548D01*
X2456738Y503131D01*
X2458266Y504881D01*
X2459358Y507506D01*
X2459795Y510131D01*
Y513339D01*
X2459358Y515964D01*
X2458266Y518298D01*
X2456956Y519465D01*
X2455428Y520048D01*
X2453681Y519465D01*
X2452371Y518298D01*
X2451498Y516548D01*
X2451061Y514214D01*
X2451498Y512173D01*
X2452590Y510131D01*
X2453900Y508964D01*
X2455428Y508673D01*
X2457174Y509256D01*
X2458485Y510715D01*
X2459795Y513339D01*
G01X2472928Y502548D02*
X2474456Y502840D01*
X2476203Y503714D01*
X2477295Y505172D01*
X2477731Y507215D01*
X2477295Y509256D01*
X2475985Y511006D01*
X2474020Y511881D01*
X2471836D01*
X2470526Y512465D01*
X2469434Y513923D01*
X2468998Y515964D01*
X2469653Y518006D01*
X2471181Y519465D01*
X2472928Y520048D01*
X2474674Y519465D01*
X2476203Y518006D01*
X2476858Y515964D01*
X2476421Y513923D01*
X2475330Y512465D01*
X2474020Y511881D01*
X2471836D01*
X2469871Y511006D01*
X2468561Y509256D01*
X2468125Y507215D01*
X2468561Y505172D01*
X2469653Y503714D01*
X2471400Y502840D01*
X2472928Y502548D01*
G01X2335548Y537198D02*
Y554698D01*
X2327469Y542156D01*
X2338387D01*
G01X2350428Y536615D02*
X2349991Y536906D01*
Y537490D01*
X2350428Y537781D01*
X2350865Y537490D01*
Y536906D01*
X2350428Y536615D01*
G01X2363125Y539822D02*
X2364434Y538364D01*
X2365963Y537490D01*
X2367928Y537198D01*
X2369893Y537781D01*
X2371421Y538948D01*
X2372513Y540989D01*
X2372731Y543323D01*
X2372295Y545656D01*
X2371203Y547115D01*
X2369674Y548281D01*
X2368146Y548573D01*
X2366618Y548281D01*
X2364653Y547115D01*
X2365308Y554698D01*
X2371203D01*
G01X2381498Y536615D02*
X2389358Y554698D01*
G01X2402491Y537198D02*
X2402928Y540989D01*
X2403583Y544198D01*
X2404456Y547115D01*
X2405548Y550323D01*
X2407295Y554698D01*
X2398561D01*
G01X2420428Y536615D02*
X2419991Y536906D01*
Y537490D01*
X2420428Y537781D01*
X2420865Y537490D01*
Y536906D01*
X2420428Y536615D01*
G01X2437928Y554698D02*
X2436181Y554115D01*
X2434871Y552656D01*
X2433998Y550907D01*
X2433343Y548573D01*
X2433125Y545948D01*
X2433343Y543323D01*
X2433998Y540989D01*
X2434871Y539239D01*
X2436181Y537781D01*
X2437928Y537198D01*
X2439674Y537781D01*
X2440985Y539239D01*
X2441858Y540989D01*
X2442513Y543323D01*
X2442731Y545948D01*
X2442513Y548573D01*
X2441858Y550907D01*
X2440985Y552656D01*
X2439674Y554115D01*
X2437928Y554698D01*
G01X2328125Y574472D02*
X2329434Y573014D01*
X2330963Y572140D01*
X2332928Y571848D01*
X2334893Y572431D01*
X2336421Y573598D01*
X2337513Y575639D01*
X2337731Y577973D01*
X2337295Y580306D01*
X2336203Y581765D01*
X2334674Y582931D01*
X2333146Y583223D01*
X2331618Y582931D01*
X2329653Y581765D01*
X2330308Y589348D01*
X2336203D01*
G01X2350428Y571265D02*
X2349991Y571556D01*
Y572140D01*
X2350428Y572431D01*
X2350865Y572140D01*
Y571556D01*
X2350428Y571265D01*
G01X2363780Y579139D02*
X2365308Y581181D01*
X2366618Y582348D01*
X2368365Y582931D01*
X2369893Y582348D01*
X2370985Y581181D01*
X2371858Y579431D01*
X2372076Y577390D01*
X2371858Y575639D01*
X2370985Y573889D01*
X2369674Y572431D01*
X2368146Y571848D01*
X2366400Y572431D01*
X2364871Y574181D01*
X2363998Y576806D01*
X2363780Y579723D01*
X2364216Y583514D01*
X2364871Y585557D01*
X2365963Y587598D01*
X2367491Y589056D01*
X2369020Y589348D01*
X2370548Y588765D01*
X2371640Y587306D01*
G01X2381498Y571265D02*
X2389358Y589348D01*
G01X2398125Y574472D02*
X2399434Y573014D01*
X2400963Y572140D01*
X2402928Y571848D01*
X2404893Y572431D01*
X2406421Y573598D01*
X2407513Y575639D01*
X2407731Y577973D01*
X2407295Y580306D01*
X2406203Y581765D01*
X2404674Y582931D01*
X2403146Y583223D01*
X2401618Y582931D01*
X2399653Y581765D01*
X2400308Y589348D01*
X2406203D01*
G01X2420428Y571265D02*
X2419991Y571556D01*
Y572140D01*
X2420428Y572431D01*
X2420865Y572140D01*
Y571556D01*
X2420428Y571265D01*
G01X2437928Y589348D02*
X2436181Y588765D01*
X2434871Y587306D01*
X2433998Y585557D01*
X2433343Y583223D01*
X2433125Y580598D01*
X2433343Y577973D01*
X2433998Y575639D01*
X2434871Y573889D01*
X2436181Y572431D01*
X2437928Y571848D01*
X2439674Y572431D01*
X2440985Y573889D01*
X2441858Y575639D01*
X2442513Y577973D01*
X2442731Y580598D01*
X2442513Y583223D01*
X2441858Y585557D01*
X2440985Y587306D01*
X2439674Y588765D01*
X2437928Y589348D01*
G01X2291378Y623998D02*
X2294434Y606498D01*
X2297928Y623998D01*
X2301421Y606498D01*
X2304478Y623998D01*
G01X2312808D02*
X2318048D01*
G01X2315428D02*
Y606498D01*
G01X2312808D02*
X2318048D01*
G01X2328125D02*
Y623998D01*
X2332491D01*
X2334238Y623123D01*
X2335548Y621956D01*
X2336640Y620207D01*
X2337513Y618164D01*
X2337731Y615248D01*
X2337513Y612331D01*
X2336640Y610289D01*
X2335548Y608539D01*
X2334238Y607373D01*
X2332491Y606498D01*
X2328125D01*
G01X2350428Y623998D02*
Y606498D01*
G01X2345406Y623998D02*
X2355450D01*
G01X2363343Y606498D02*
Y623998D01*
G01X2372513D02*
Y606498D01*
G01Y615248D02*
X2363343D01*
G01X2384336Y600665D02*
X2382153Y603581D01*
X2381061Y606498D01*
Y618164D01*
X2382153Y621081D01*
X2384336Y623998D01*
G01X2396378Y606498D02*
Y618164D01*
G01Y614956D02*
X2397033Y616415D01*
X2398125Y617581D01*
X2399653Y618164D01*
X2401181Y617581D01*
X2402273Y616415D01*
X2402928Y614956D01*
Y606498D01*
G01Y614956D02*
X2403583Y616415D01*
X2404674Y617581D01*
X2406203Y618164D01*
X2407731Y617581D01*
X2408823Y616415D01*
X2409478Y614665D01*
Y606498D01*
G01X2420428Y618164D02*
Y606498D01*
G01Y622831D02*
X2419991Y623123D01*
Y623706D01*
X2420428Y623998D01*
X2420865Y623706D01*
Y623123D01*
X2420428Y622831D01*
G01X2437928Y606498D02*
Y623998D01*
G01X2452153Y608539D02*
X2453245Y607373D01*
X2454773Y606498D01*
X2456083D01*
X2457393Y607081D01*
X2458266Y607956D01*
X2458703Y609122D01*
X2458485Y610873D01*
X2457611Y611748D01*
X2453681Y613498D01*
X2452808Y615540D01*
X2453245Y616998D01*
X2454118Y617873D01*
X2455428Y618164D01*
X2456738Y617873D01*
X2458048Y616998D01*
G01X2474020Y600665D02*
X2476203Y603581D01*
X2477295Y606498D01*
Y618164D01*
X2476203Y621081D01*
X2474020Y623998D01*
G01X2608125Y467898D02*
Y485398D01*
X2612491D01*
X2614238Y484523D01*
X2615548Y483356D01*
X2616640Y481607D01*
X2617513Y479564D01*
X2617731Y476648D01*
X2617513Y473731D01*
X2616640Y471689D01*
X2615548Y469939D01*
X2614238Y468773D01*
X2612491Y467898D01*
X2608125D01*
G01X2626061D02*
Y485398D01*
X2631301D01*
X2633048Y484523D01*
X2634358Y482481D01*
X2634795Y480148D01*
X2634358Y477815D01*
X2633266Y476065D01*
X2631301Y475189D01*
X2626061D01*
G01X2608125Y502548D02*
Y520048D01*
X2612491D01*
X2614238Y519173D01*
X2615548Y518006D01*
X2616640Y516257D01*
X2617513Y514214D01*
X2617731Y511298D01*
X2617513Y508381D01*
X2616640Y506339D01*
X2615548Y504589D01*
X2614238Y503423D01*
X2612491Y502548D01*
X2608125D01*
G01X2626061D02*
Y520048D01*
X2631301D01*
X2633048Y519173D01*
X2634358Y517131D01*
X2634795Y514798D01*
X2634358Y512465D01*
X2633266Y510715D01*
X2631301Y509839D01*
X2626061D01*
G01X2608125Y537198D02*
Y554698D01*
X2612491D01*
X2614238Y553823D01*
X2615548Y552656D01*
X2616640Y550907D01*
X2617513Y548864D01*
X2617731Y545948D01*
X2617513Y543031D01*
X2616640Y540989D01*
X2615548Y539239D01*
X2614238Y538073D01*
X2612491Y537198D01*
X2608125D01*
G01X2626061D02*
Y554698D01*
X2631301D01*
X2633048Y553823D01*
X2634358Y551781D01*
X2634795Y549448D01*
X2634358Y547115D01*
X2633266Y545365D01*
X2631301Y544489D01*
X2626061D01*
G01X2608125Y571848D02*
Y589348D01*
X2612491D01*
X2614238Y588473D01*
X2615548Y587306D01*
X2616640Y585557D01*
X2617513Y583514D01*
X2617731Y580598D01*
X2617513Y577681D01*
X2616640Y575639D01*
X2615548Y573889D01*
X2614238Y572723D01*
X2612491Y571848D01*
X2608125D01*
G01X2626061D02*
Y589348D01*
X2631301D01*
X2633048Y588473D01*
X2634358Y586431D01*
X2634795Y584098D01*
X2634358Y581765D01*
X2633266Y580015D01*
X2631301Y579139D01*
X2626061D01*
G01X2595428Y623998D02*
Y606498D01*
G01X2590406Y623998D02*
X2600450D01*
G01X2612928Y606498D02*
Y614373D01*
X2608561Y623998D01*
G01X2617295D02*
X2612928Y614373D01*
G01X2626061Y606498D02*
Y623998D01*
X2631301D01*
X2633048Y623123D01*
X2634358Y621081D01*
X2634795Y618748D01*
X2634358Y616415D01*
X2633266Y614665D01*
X2631301Y613789D01*
X2626061D01*
G01X2652295Y606498D02*
X2643561D01*
Y623998D01*
X2652295D01*
G01X2648801Y615540D02*
X2643561D01*
G01X2696061Y606498D02*
Y623998D01*
X2701520D01*
X2703266Y623123D01*
X2704358Y621956D01*
X2704795Y619623D01*
X2704358Y617289D01*
X2703048Y615831D01*
X2701520Y614956D01*
X2696061D01*
G01X2701520D02*
X2704795Y606498D01*
G01X2714653Y614373D02*
X2721640D01*
X2720985Y616415D01*
X2719893Y617581D01*
X2718365Y618164D01*
X2716836Y617873D01*
X2715526Y616998D01*
X2714653Y614956D01*
X2714216Y613206D01*
Y611456D01*
X2714653Y609706D01*
X2715745Y607956D01*
X2717055Y606790D01*
X2718583Y606498D01*
X2720111Y607081D01*
X2721640Y608831D01*
G01X2734118Y606498D02*
Y621373D01*
X2734555Y622831D01*
X2735428Y623706D01*
X2736738Y623998D01*
X2738048Y623415D01*
X2738703Y621956D01*
G01X2736083Y616998D02*
X2731716D01*
G01X2752928Y605915D02*
X2752491Y606206D01*
Y606790D01*
X2752928Y607081D01*
X2753365Y606790D01*
Y606206D01*
X2752928Y605915D01*
G01X2783561Y606498D02*
Y623998D01*
X2788801D01*
X2790548Y623123D01*
X2791858Y621081D01*
X2792295Y618748D01*
X2791858Y616415D01*
X2790766Y614665D01*
X2788801Y613789D01*
X2783561D01*
G01X2805428Y606498D02*
Y623998D01*
G01X2826858Y606498D02*
Y618164D01*
G01Y616123D02*
X2825985Y617289D01*
X2824674Y617873D01*
X2823146Y618164D01*
X2821618Y617581D01*
X2820308Y616415D01*
X2819434Y614665D01*
X2818998Y612331D01*
X2819434Y609998D01*
X2820308Y608248D01*
X2821618Y607081D01*
X2823146Y606498D01*
X2824674Y606790D01*
X2825985Y607664D01*
X2826858Y608831D01*
G01X2836716Y606498D02*
Y618164D01*
G01Y615248D02*
X2837590Y616706D01*
X2838900Y617873D01*
X2840646Y618164D01*
X2842174Y617873D01*
X2843485Y616706D01*
X2844140Y614665D01*
Y606498D01*
G01X2854653Y614373D02*
X2861640D01*
X2860985Y616415D01*
X2859893Y617581D01*
X2858365Y618164D01*
X2856836Y617873D01*
X2855526Y616998D01*
X2854653Y614956D01*
X2854216Y613206D01*
Y611456D01*
X2854653Y609706D01*
X2855745Y607956D01*
X2857055Y606790D01*
X2858583Y606498D01*
X2860111Y607081D01*
X2861640Y608831D01*
G01X2731061Y485398D02*
Y467898D01*
X2739795D01*
G01X2749216Y469939D02*
X2750745Y468481D01*
X2752491Y467898D01*
X2754238Y468481D01*
X2755766Y470231D01*
X2756858Y472856D01*
X2757295Y475481D01*
Y478689D01*
X2756858Y481314D01*
X2755766Y483648D01*
X2754456Y484815D01*
X2752928Y485398D01*
X2751181Y484815D01*
X2749871Y483648D01*
X2748998Y481898D01*
X2748561Y479564D01*
X2748998Y477523D01*
X2750090Y475481D01*
X2751400Y474314D01*
X2752928Y474023D01*
X2754674Y474606D01*
X2755985Y476065D01*
X2757295Y478689D01*
G01X2766498Y467315D02*
X2774358Y485398D01*
G01X2783561D02*
Y467898D01*
X2792295D01*
G01X2805428D02*
Y485398D01*
X2802808Y481898D01*
G01Y467898D02*
X2808048D01*
G01X2822928D02*
Y485398D01*
X2820308Y481898D01*
G01Y467898D02*
X2825548D01*
G01X2731061Y520048D02*
Y502548D01*
X2739795D01*
G01X2749216Y504589D02*
X2750745Y503131D01*
X2752491Y502548D01*
X2754238Y503131D01*
X2755766Y504881D01*
X2756858Y507506D01*
X2757295Y510131D01*
Y513339D01*
X2756858Y515964D01*
X2755766Y518298D01*
X2754456Y519465D01*
X2752928Y520048D01*
X2751181Y519465D01*
X2749871Y518298D01*
X2748998Y516548D01*
X2748561Y514214D01*
X2748998Y512173D01*
X2750090Y510131D01*
X2751400Y508964D01*
X2752928Y508673D01*
X2754674Y509256D01*
X2755985Y510715D01*
X2757295Y513339D01*
G01X2766498Y501965D02*
X2774358Y520048D01*
G01X2783561D02*
Y502548D01*
X2792295D01*
G01X2805428D02*
Y520048D01*
X2802808Y516548D01*
G01Y502548D02*
X2808048D01*
G01X2822928D02*
Y520048D01*
X2820308Y516548D01*
G01Y502548D02*
X2825548D01*
G01X2731061Y554698D02*
Y537198D01*
X2739795D01*
G01X2749216Y539239D02*
X2750745Y537781D01*
X2752491Y537198D01*
X2754238Y537781D01*
X2755766Y539531D01*
X2756858Y542156D01*
X2757295Y544781D01*
Y547989D01*
X2756858Y550614D01*
X2755766Y552948D01*
X2754456Y554115D01*
X2752928Y554698D01*
X2751181Y554115D01*
X2749871Y552948D01*
X2748998Y551198D01*
X2748561Y548864D01*
X2748998Y546823D01*
X2750090Y544781D01*
X2751400Y543614D01*
X2752928Y543323D01*
X2754674Y543906D01*
X2755985Y545365D01*
X2757295Y547989D01*
G01X2766498Y536615D02*
X2774358Y554698D01*
G01X2783561D02*
Y537198D01*
X2792295D01*
G01X2805428D02*
Y554698D01*
X2802808Y551198D01*
G01Y537198D02*
X2808048D01*
G01X2822928D02*
Y554698D01*
X2820308Y551198D01*
G01Y537198D02*
X2825548D01*
G01X2731061Y589348D02*
Y571848D01*
X2739795D01*
G01X2749216Y573889D02*
X2750745Y572431D01*
X2752491Y571848D01*
X2754238Y572431D01*
X2755766Y574181D01*
X2756858Y576806D01*
X2757295Y579431D01*
Y582639D01*
X2756858Y585264D01*
X2755766Y587598D01*
X2754456Y588765D01*
X2752928Y589348D01*
X2751181Y588765D01*
X2749871Y587598D01*
X2748998Y585848D01*
X2748561Y583514D01*
X2748998Y581473D01*
X2750090Y579431D01*
X2751400Y578264D01*
X2752928Y577973D01*
X2754674Y578556D01*
X2755985Y580015D01*
X2757295Y582639D01*
G01X2766498Y571265D02*
X2774358Y589348D01*
G01X2783561D02*
Y571848D01*
X2792295D01*
G01X2805428D02*
Y589348D01*
X2802808Y585848D01*
G01Y571848D02*
X2808048D01*
G01X2822928D02*
Y589348D01*
X2820308Y585848D01*
G01Y571848D02*
X2825548D01*
G01X2975728Y548864D02*
Y537198D01*
G01Y553531D02*
X2975291Y553823D01*
Y554406D01*
X2975728Y554698D01*
X2976165Y554406D01*
Y553823D01*
X2975728Y553531D01*
G01X2989516Y537198D02*
Y548864D01*
G01Y545948D02*
X2990390Y547406D01*
X2991700Y548573D01*
X2993446Y548864D01*
X2994974Y548573D01*
X2996285Y547406D01*
X2996940Y545365D01*
Y537198D01*
G01X3007453Y539239D02*
X3008545Y538073D01*
X3010073Y537198D01*
X3011383D01*
X3012693Y537781D01*
X3013566Y538656D01*
X3014003Y539822D01*
X3013785Y541573D01*
X3012911Y542448D01*
X3008981Y544198D01*
X3008108Y546240D01*
X3008545Y547698D01*
X3009418Y548573D01*
X3010728Y548864D01*
X3012038Y548573D01*
X3013348Y547698D01*
G01X3028228Y548864D02*
Y537198D01*
G01Y553531D02*
X3027791Y553823D01*
Y554406D01*
X3028228Y554698D01*
X3028665Y554406D01*
Y553823D01*
X3028228Y553531D01*
G01X3049658Y554698D02*
Y537198D01*
G01Y539822D02*
X3048785Y538364D01*
X3047474Y537490D01*
X3045946Y537198D01*
X3044200Y537781D01*
X3042890Y539239D01*
X3042016Y540989D01*
X3041798Y543031D01*
X3042016Y545073D01*
X3042890Y546823D01*
X3044200Y548281D01*
X3045946Y548864D01*
X3047474Y548573D01*
X3048566Y547989D01*
X3049658Y546823D01*
G01X3059953Y545073D02*
X3066940D01*
X3066285Y547115D01*
X3065193Y548281D01*
X3063665Y548864D01*
X3062136Y548573D01*
X3060826Y547698D01*
X3059953Y545656D01*
X3059516Y543906D01*
Y542156D01*
X3059953Y540406D01*
X3061045Y538656D01*
X3062355Y537490D01*
X3063883Y537198D01*
X3065411Y537781D01*
X3066940Y539531D01*
G01X3094298Y537198D02*
Y554698D01*
G01Y545948D02*
X3095390Y547698D01*
X3096700Y548573D01*
X3098010Y548864D01*
X3099974Y548281D01*
X3101285Y547115D01*
X3102158Y545073D01*
Y542740D01*
X3101721Y540406D01*
X3100848Y538656D01*
X3099320Y537490D01*
X3098010Y537198D01*
X3096700Y537490D01*
X3095390Y538364D01*
X3094298Y539822D01*
G01X3115728Y537198D02*
X3114418Y537490D01*
X3113108Y538656D01*
X3112234Y540698D01*
X3111798Y543031D01*
X3112234Y545365D01*
X3113108Y547406D01*
X3114418Y548573D01*
X3115728Y548864D01*
X3117038Y548573D01*
X3118348Y547406D01*
X3119221Y545365D01*
X3119440Y543031D01*
X3119221Y540698D01*
X3118348Y538656D01*
X3117038Y537490D01*
X3115728Y537198D01*
G01X3137158D02*
Y548864D01*
G01Y546823D02*
X3136285Y547989D01*
X3134974Y548573D01*
X3133446Y548864D01*
X3131918Y548281D01*
X3130608Y547115D01*
X3129734Y545365D01*
X3129298Y543031D01*
X3129734Y540698D01*
X3130608Y538948D01*
X3131918Y537781D01*
X3133446Y537198D01*
X3134974Y537490D01*
X3136285Y538364D01*
X3137158Y539531D01*
G01X3147671Y537198D02*
Y548864D01*
G01Y546531D02*
X3148763Y547698D01*
X3149855Y548573D01*
X3151383Y548864D01*
X3152474Y548573D01*
X3153785Y547698D01*
G01X3172158Y554698D02*
Y537198D01*
G01Y539822D02*
X3171285Y538364D01*
X3169974Y537490D01*
X3168446Y537198D01*
X3166700Y537781D01*
X3165390Y539239D01*
X3164516Y540989D01*
X3164298Y543031D01*
X3164516Y545073D01*
X3165390Y546823D01*
X3166700Y548281D01*
X3168446Y548864D01*
X3169974Y548573D01*
X3171066Y547989D01*
X3172158Y546823D01*
G01X3203228Y537198D02*
X3201918Y537490D01*
X3200608Y538656D01*
X3199734Y540698D01*
X3199298Y543031D01*
X3199734Y545365D01*
X3200608Y547406D01*
X3201918Y548573D01*
X3203228Y548864D01*
X3204538Y548573D01*
X3205848Y547406D01*
X3206721Y545365D01*
X3206940Y543031D01*
X3206721Y540698D01*
X3205848Y538656D01*
X3204538Y537490D01*
X3203228Y537198D01*
G01X3217016Y548864D02*
Y540698D01*
X3217890Y538656D01*
X3219200Y537490D01*
X3220728Y537198D01*
X3222256Y537490D01*
X3223566Y538656D01*
X3224440Y540698D01*
G01Y537198D02*
Y548864D01*
G01X3238228Y554698D02*
Y537198D01*
G01X3235171Y548864D02*
X3241285D01*
G01X3255728Y537198D02*
Y554698D01*
G01X3273228Y548864D02*
Y537198D01*
G01Y553531D02*
X3272791Y553823D01*
Y554406D01*
X3273228Y554698D01*
X3273665Y554406D01*
Y553823D01*
X3273228Y553531D01*
G01X3287016Y537198D02*
Y548864D01*
G01Y545948D02*
X3287890Y547406D01*
X3289200Y548573D01*
X3290946Y548864D01*
X3292474Y548573D01*
X3293785Y547406D01*
X3294440Y545365D01*
Y537198D01*
G01X3304953Y545073D02*
X3311940D01*
X3311285Y547115D01*
X3310193Y548281D01*
X3308665Y548864D01*
X3307136Y548573D01*
X3305826Y547698D01*
X3304953Y545656D01*
X3304516Y543906D01*
Y542156D01*
X3304953Y540406D01*
X3306045Y538656D01*
X3307355Y537490D01*
X3308883Y537198D01*
X3310411Y537781D01*
X3311940Y539531D01*
G01X3325728Y536615D02*
X3325291Y536906D01*
Y537490D01*
X3325728Y537781D01*
X3326165Y537490D01*
Y536906D01*
X3325728Y536615D01*
G01X2975728Y583514D02*
Y571848D01*
G01Y588181D02*
X2975291Y588473D01*
Y589056D01*
X2975728Y589348D01*
X2976165Y589056D01*
Y588473D01*
X2975728Y588181D01*
G01X2989953Y573889D02*
X2991045Y572723D01*
X2992573Y571848D01*
X2993883D01*
X2995193Y572431D01*
X2996066Y573306D01*
X2996503Y574472D01*
X2996285Y576223D01*
X2995411Y577098D01*
X2991481Y578848D01*
X2990608Y580890D01*
X2991045Y582348D01*
X2991918Y583223D01*
X2993228Y583514D01*
X2994538Y583223D01*
X2995848Y582348D01*
G01X3023206Y571848D02*
Y589348D01*
X3033250Y571848D01*
Y589348D01*
G01X3045728Y571848D02*
X3043981Y572140D01*
X3042453Y573306D01*
X3041143Y575056D01*
X3040269Y577098D01*
X3039833Y579431D01*
Y581765D01*
X3040269Y584098D01*
X3041143Y586140D01*
X3042453Y587889D01*
X3043981Y589056D01*
X3045728Y589348D01*
X3047474Y589056D01*
X3049003Y587889D01*
X3050313Y586140D01*
X3051187Y584098D01*
X3051623Y581765D01*
Y579431D01*
X3051187Y577098D01*
X3050313Y575056D01*
X3049003Y573306D01*
X3047474Y572140D01*
X3045728Y571848D01*
G01X3063228Y589348D02*
Y571848D01*
G01X3058206Y589348D02*
X3068250D01*
G01X3094516Y583514D02*
Y575348D01*
X3095390Y573306D01*
X3096700Y572140D01*
X3098228Y571848D01*
X3099756Y572140D01*
X3101066Y573306D01*
X3101940Y575348D01*
G01Y571848D02*
Y583514D01*
G01X3112453Y573889D02*
X3113545Y572723D01*
X3115073Y571848D01*
X3116383D01*
X3117693Y572431D01*
X3118566Y573306D01*
X3119003Y574472D01*
X3118785Y576223D01*
X3117911Y577098D01*
X3113981Y578848D01*
X3113108Y580890D01*
X3113545Y582348D01*
X3114418Y583223D01*
X3115728Y583514D01*
X3117038Y583223D01*
X3118348Y582348D01*
G01X3129953Y579723D02*
X3136940D01*
X3136285Y581765D01*
X3135193Y582931D01*
X3133665Y583514D01*
X3132136Y583223D01*
X3130826Y582348D01*
X3129953Y580306D01*
X3129516Y578556D01*
Y576806D01*
X3129953Y575056D01*
X3131045Y573306D01*
X3132355Y572140D01*
X3133883Y571848D01*
X3135411Y572431D01*
X3136940Y574181D01*
G01X3154658Y589348D02*
Y571848D01*
G01Y574472D02*
X3153785Y573014D01*
X3152474Y572140D01*
X3150946Y571848D01*
X3149200Y572431D01*
X3147890Y573889D01*
X3147016Y575639D01*
X3146798Y577681D01*
X3147016Y579723D01*
X3147890Y581473D01*
X3149200Y582931D01*
X3150946Y583514D01*
X3152474Y583223D01*
X3153566Y582639D01*
X3154658Y581473D01*
G01X3185728Y583514D02*
Y571848D01*
G01Y588181D02*
X3185291Y588473D01*
Y589056D01*
X3185728Y589348D01*
X3186165Y589056D01*
Y588473D01*
X3185728Y588181D01*
G01X3199516Y571848D02*
Y583514D01*
G01Y580598D02*
X3200390Y582056D01*
X3201700Y583223D01*
X3203446Y583514D01*
X3204974Y583223D01*
X3206285Y582056D01*
X3206940Y580015D01*
Y571848D01*
G01X3238228Y589348D02*
Y571848D01*
G01X3235171Y583514D02*
X3241285D01*
G01X3252016Y571848D02*
Y589348D01*
G01Y580890D02*
X3253108Y582348D01*
X3254200Y583223D01*
X3255946Y583514D01*
X3257256Y583223D01*
X3258785Y582056D01*
X3259440Y580306D01*
Y571848D01*
G01X3273228Y583514D02*
Y571848D01*
G01Y588181D02*
X3272791Y588473D01*
Y589056D01*
X3273228Y589348D01*
X3273665Y589056D01*
Y588473D01*
X3273228Y588181D01*
G01X3287453Y573889D02*
X3288545Y572723D01*
X3290073Y571848D01*
X3291383D01*
X3292693Y572431D01*
X3293566Y573306D01*
X3294003Y574472D01*
X3293785Y576223D01*
X3292911Y577098D01*
X3288981Y578848D01*
X3288108Y580890D01*
X3288545Y582348D01*
X3289418Y583223D01*
X3290728Y583514D01*
X3292038Y583223D01*
X3293348Y582348D01*
G01X3325728Y571848D02*
Y589348D01*
G01X3347158Y571848D02*
Y583514D01*
G01Y581473D02*
X3346285Y582639D01*
X3344974Y583223D01*
X3343446Y583514D01*
X3341918Y582931D01*
X3340608Y581765D01*
X3339734Y580015D01*
X3339298Y577681D01*
X3339734Y575348D01*
X3340608Y573598D01*
X3341918Y572431D01*
X3343446Y571848D01*
X3344974Y572140D01*
X3346285Y573014D01*
X3347158Y574181D01*
G01X3356143Y566598D02*
X3357453Y566015D01*
X3359200Y566598D01*
X3360291Y567764D01*
X3361165Y569223D01*
X3362474Y573889D01*
X3365313Y583514D01*
G01X3358326D02*
X3362474Y573889D01*
G01X3374953Y579723D02*
X3381940D01*
X3381285Y581765D01*
X3380193Y582931D01*
X3378665Y583514D01*
X3377136Y583223D01*
X3375826Y582348D01*
X3374953Y580306D01*
X3374516Y578556D01*
Y576806D01*
X3374953Y575056D01*
X3376045Y573306D01*
X3377355Y572140D01*
X3378883Y571848D01*
X3380411Y572431D01*
X3381940Y574181D01*
G01X3392671Y571848D02*
Y583514D01*
G01Y581181D02*
X3393763Y582348D01*
X3394855Y583223D01*
X3396383Y583514D01*
X3397474Y583223D01*
X3398785Y582348D01*
G01X2900925Y605915D02*
X2910531Y618748D01*
G01X2905728Y621081D02*
Y603581D01*
G01X2910531Y605915D02*
X2900925Y618748D01*
G01X2899178Y612331D02*
X2912278D01*
G01X2937890D02*
X2943566D01*
G01X2970925Y606498D02*
Y623998D01*
X2975291D01*
X2977038Y623123D01*
X2978348Y621956D01*
X2979440Y620207D01*
X2980313Y618164D01*
X2980531Y615248D01*
X2980313Y612331D01*
X2979440Y610289D01*
X2978348Y608539D01*
X2977038Y607373D01*
X2975291Y606498D01*
X2970925D01*
G01X2989953Y614373D02*
X2996940D01*
X2996285Y616415D01*
X2995193Y617581D01*
X2993665Y618164D01*
X2992136Y617873D01*
X2990826Y616998D01*
X2989953Y614956D01*
X2989516Y613206D01*
Y611456D01*
X2989953Y609706D01*
X2991045Y607956D01*
X2992355Y606790D01*
X2993883Y606498D01*
X2995411Y607081D01*
X2996940Y608831D01*
G01X3007016Y606498D02*
Y618164D01*
G01Y615248D02*
X3007890Y616706D01*
X3009200Y617873D01*
X3010946Y618164D01*
X3012474Y617873D01*
X3013785Y616706D01*
X3014440Y614665D01*
Y606498D01*
G01X3028228D02*
X3026918Y606790D01*
X3025608Y607956D01*
X3024734Y609998D01*
X3024298Y612331D01*
X3024734Y614665D01*
X3025608Y616706D01*
X3026918Y617873D01*
X3028228Y618164D01*
X3029538Y617873D01*
X3030848Y616706D01*
X3031721Y614665D01*
X3031940Y612331D01*
X3031721Y609998D01*
X3030848Y607956D01*
X3029538Y606790D01*
X3028228Y606498D01*
G01X3045728Y623998D02*
Y606498D01*
G01X3042671Y618164D02*
X3048785D01*
G01X3059953Y614373D02*
X3066940D01*
X3066285Y616415D01*
X3065193Y617581D01*
X3063665Y618164D01*
X3062136Y617873D01*
X3060826Y616998D01*
X3059953Y614956D01*
X3059516Y613206D01*
Y611456D01*
X3059953Y609706D01*
X3061045Y607956D01*
X3062355Y606790D01*
X3063883Y606498D01*
X3065411Y607081D01*
X3066940Y608831D01*
G01X3077453Y608539D02*
X3078545Y607373D01*
X3080073Y606498D01*
X3081383D01*
X3082693Y607081D01*
X3083566Y607956D01*
X3084003Y609122D01*
X3083785Y610873D01*
X3082911Y611748D01*
X3078981Y613498D01*
X3078108Y615540D01*
X3078545Y616998D01*
X3079418Y617873D01*
X3080728Y618164D01*
X3082038Y617873D01*
X3083348Y616998D01*
G01X3115728Y623998D02*
Y606498D01*
G01X3112671Y618164D02*
X3118785D01*
G01X3129516Y606498D02*
Y623998D01*
G01Y615540D02*
X3130608Y616998D01*
X3131700Y617873D01*
X3133446Y618164D01*
X3134756Y617873D01*
X3136285Y616706D01*
X3136940Y614956D01*
Y606498D01*
G01X3154658D02*
Y618164D01*
G01Y616123D02*
X3153785Y617289D01*
X3152474Y617873D01*
X3150946Y618164D01*
X3149418Y617581D01*
X3148108Y616415D01*
X3147234Y614665D01*
X3146798Y612331D01*
X3147234Y609998D01*
X3148108Y608248D01*
X3149418Y607081D01*
X3150946Y606498D01*
X3152474Y606790D01*
X3153785Y607664D01*
X3154658Y608831D01*
G01X3168228Y623998D02*
Y606498D01*
G01X3165171Y618164D02*
X3171285D01*
G01X3196678Y623998D02*
X3199734Y606498D01*
X3203228Y623998D01*
X3206721Y606498D01*
X3209778Y623998D01*
G01X3218108D02*
X3223348D01*
G01X3220728D02*
Y606498D01*
G01X3218108D02*
X3223348D01*
G01X3233425D02*
Y623998D01*
X3237791D01*
X3239538Y623123D01*
X3240848Y621956D01*
X3241940Y620207D01*
X3242813Y618164D01*
X3243031Y615248D01*
X3242813Y612331D01*
X3241940Y610289D01*
X3240848Y608539D01*
X3239538Y607373D01*
X3237791Y606498D01*
X3233425D01*
G01X3255728Y623998D02*
Y606498D01*
G01X3250706Y623998D02*
X3260750D01*
G01X3268643Y606498D02*
Y623998D01*
G01X3277813D02*
Y606498D01*
G01Y615248D02*
X3268643D01*
G01X-7874Y-31496D02*
X-19685D01*
G01X-7874D02*
X-19685D01*
G01D02*
G03X-23622Y-35433I0J-3937D01*
G01D02*
Y-59055D01*
G01Y-35433D02*
Y-59055D01*
G01X-19685Y-31496D02*
G03X-23622Y-35433I0J-3937D01*
G01Y-59055D02*
G03X-19685Y-62992I3937J0D01*
G01D02*
X1972441D01*
G01X-19685D02*
X1972441D01*
G01X-23622Y-59055D02*
G03X-19685Y-62992I3937J0D01*
G01Y-23622D02*
X1972441D01*
G01X-19685D02*
X1972441D01*
G01X-19685D02*
X1972441D01*
G01X-19685D02*
X1972441D01*
G01X-23622Y622441D02*
Y-19685D01*
G01Y622441D02*
Y-19685D01*
G01Y622441D02*
Y-19685D01*
G01Y622441D02*
Y-19685D01*
G01D02*
G03X-19685Y-23622I3937J0D01*
G01X-23622Y-19685D02*
G03X-19685Y-23622I3937J0D01*
G01X-23622Y-19685D02*
G03X-19685Y-23622I3937J0D01*
G01X-23622Y-19685D02*
G03X-19685Y-23622I3937J0D01*
G01X1972441Y626378D02*
X-19685D01*
G01X1972441D02*
X-19685D01*
G01X1972441D02*
X-19685D01*
G01X1972441D02*
X-19685D01*
G01D02*
G03X-23622Y622441I0J-3937D01*
G01X-19685Y626378D02*
G03X-23622Y622441I0J-3937D01*
G01X-19685Y626378D02*
G03X-23622Y622441I0J-3937D01*
G01X-19685Y626378D02*
G03X-23622Y622441I0J-3937D01*
G01X-19685Y634252D02*
X-7874D01*
G01X-19685D02*
X-7874D01*
G01X-23622Y661811D02*
Y638189D01*
G01Y661811D02*
Y638189D01*
G01D02*
G03X-19685Y634252I3937J0D01*
G01X-23622Y638189D02*
G03X-19685Y634252I3937J0D01*
G01X1972441Y665748D02*
X-19685D01*
G01X1972441D02*
X-19685D01*
G01D02*
G03X-23622Y661811I0J-3937D01*
G01X-19685Y665748D02*
G03X-23622Y661811I0J-3937D01*
G01X-7874Y-31496D02*
G03Y-23622I0J3937D01*
G01Y-31496D02*
G03Y-23622I0J3937D01*
G01X22835D02*
G03Y-31496I0J-3937D01*
G01X137795D02*
X22835D01*
G01X137795D02*
X22835D01*
G01Y-23622D02*
G03Y-31496I0J-3937D01*
G01X0Y616535D02*
G03Y604724I0J-5905D01*
G01Y616535D02*
G03Y604724I0J-5905D01*
G01Y616535D02*
X2646D01*
G01X2644D02*
X0D01*
G01Y604724D02*
X2644D01*
G01X2646D02*
X0D01*
G01X2646D02*
X0D01*
G01D02*
X2644D01*
G01Y616535D02*
X0D01*
G01D02*
X2646D01*
G01X0D02*
G03Y604724I0J-5905D01*
G01Y616535D02*
G03Y604724I0J-5905D01*
G01X2646Y616535D02*
G03X7595Y618285I0J7874D01*
G01X2644Y616535D02*
G03X7593Y618285I0J7874D01*
G01X2644Y616535D02*
G03X7593Y618285I0J7874D01*
G01X7595Y602975D02*
G03X2646Y604724I-4948J-6125D01*
G01X7593Y602975D02*
G03X2644Y604724I-4948J-6125D01*
G01X7593Y602975D02*
G03X2644Y604724I-4948J-6125D01*
G01X7593Y602975D02*
G03X2644Y604724I-4948J-6125D01*
G01X7593Y602975D02*
G03X2644Y604724I-4948J-6125D01*
G01X7595Y602975D02*
G03X2646Y604724I-4948J-6125D01*
G01X2644Y616535D02*
G03X7593Y618285I0J7874D01*
G01X2644Y616535D02*
G03X7593Y618285I0J7874D01*
G01X2646Y616535D02*
G03X7595Y618285I0J7874D01*
G01Y602975D02*
G03Y618285I6186J7655D01*
G01X7593Y602975D02*
G03Y618285I6187J7655D01*
G01Y602975D02*
G03Y618285I6187J7655D01*
G01Y602975D02*
G03Y618285I6187J7655D01*
G01Y602975D02*
G03Y618285I6187J7655D01*
G01X7595Y602975D02*
G03Y618285I6186J7655D01*
G01X-7874Y626378D02*
G03Y634252I0J3937D01*
G01Y626378D02*
G03Y634252I0J3937D01*
G01X22835D02*
G03Y626378I0J-3937D01*
G01Y634252D02*
X137795D01*
G01X22835D02*
X137795D01*
G01X22835D02*
G03Y626378I0J-3937D01*
G01X168504Y-23622D02*
G03Y-31496I0J-3937D01*
G01X137795D02*
G03Y-23622I0J3937D01*
G01X341732Y-31496D02*
X168504D01*
G01X341732D02*
X168504D01*
G01X137795D02*
G03Y-23622I0J3937D01*
G01X168504D02*
G03Y-31496I0J-3937D01*
G01Y634252D02*
G03Y626378I0J-3937D01*
G01X137795D02*
G03Y634252I0J3937D01*
G01X168504D02*
X341732D01*
G01X168504D02*
X341732D01*
G01X137795Y626378D02*
G03Y634252I0J3937D01*
G01X168504D02*
G03Y626378I0J-3937D01*
G01X341732Y-31496D02*
G03Y-23622I0J3937D01*
G01Y-31496D02*
G03Y-23622I0J3937D01*
G01Y626378D02*
G03Y634252I0J3937D01*
G01Y626378D02*
G03Y634252I0J3937D01*
G01X372441Y-23622D02*
G03Y-31496I0J-3937D01*
G01X529921D02*
X372441D01*
G01X529921D02*
X372441D01*
G01Y-23622D02*
G03Y-31496I0J-3937D01*
G01Y634252D02*
G03Y626378I0J-3937D01*
G01Y634252D02*
X529921D01*
G01X372441D02*
X529921D01*
G01X372441D02*
G03Y626378I0J-3937D01*
G01X529921Y-31496D02*
G03Y-23622I0J3937D01*
G01Y-31496D02*
G03Y-23622I0J3937D01*
G01Y626378D02*
G03Y634252I0J3937D01*
G01Y626378D02*
G03Y634252I0J3937D01*
G01X560630Y-23622D02*
G03Y-31496I0J-3937D01*
G01X788976D02*
X560630D01*
G01X788976D02*
X560630D01*
G01Y-23622D02*
G03Y-31496I0J-3937D01*
G01Y634252D02*
G03Y626378I0J-3937D01*
G01Y634252D02*
X788976D01*
G01X560630D02*
X788976D01*
G01X560630D02*
G03Y626378I0J-3937D01*
G01X684760Y-15529D02*
G03Y-219I6187J7655D01*
G01X684759Y-15529D02*
G03X679809Y-13780I-4948J-6125D01*
G01X679811Y-1969D02*
G03X684760Y-219I0J7874D01*
G01X677165Y-1969D02*
X679811D01*
G01X677165D02*
G03Y-13780I0J-5906D01*
G01D02*
X679809D01*
G01X684760Y602975D02*
G03Y618285I6187J7655D01*
G01X684759Y602975D02*
G03Y618285I6186J7655D01*
G01Y602975D02*
G03Y618285I6186J7655D01*
G01Y602975D02*
G03Y618285I6186J7655D01*
G01Y602975D02*
G03Y618285I6186J7655D01*
G01X684760Y602975D02*
G03Y618285I6187J7655D01*
G01X679811Y616535D02*
G03X684760Y618285I0J7874D01*
G01X679809Y616535D02*
G03X684759Y618285I0J7874D01*
G01X679809Y616535D02*
G03X684759Y618285I0J7874D01*
G01X684760Y602975D02*
G03X679811Y604724I-4948J-6125D01*
G01X684759Y602975D02*
G03X679809Y604724I-4948J-6125D01*
G01X684759Y602975D02*
G03X679809Y604724I-4948J-6125D01*
G01X684759Y602975D02*
G03X679809Y604724I-4948J-6125D01*
G01X684759Y602975D02*
G03X679809Y604724I-4948J-6125D01*
G01X684760Y602975D02*
G03X679811Y604724I-4948J-6125D01*
G01X679809Y616535D02*
G03X684759Y618285I0J7874D01*
G01X679809Y616535D02*
G03X684759Y618285I0J7874D01*
G01X679811Y616535D02*
G03X684760Y618285I0J7874D01*
G01X677165Y616535D02*
X679811D01*
G01X677165D02*
G03Y604724I0J-5905D01*
G01D02*
X679809D01*
G01X788976Y-31496D02*
G03Y-23622I0J3937D01*
G01Y-31496D02*
G03Y-23622I0J3937D01*
G01X819685D02*
G03Y-31496I0J-3937D01*
G01X975591D02*
X819685D01*
G01X975591D02*
X819685D01*
G01Y-23622D02*
G03Y-31496I0J-3937D01*
G01X788976Y626378D02*
G03Y634252I0J3937D01*
G01Y626378D02*
G03Y634252I0J3937D01*
G01X819685D02*
G03Y626378I0J-3937D01*
G01Y634252D02*
X975591D01*
G01X819685D02*
X975591D01*
G01X819685D02*
G03Y626378I0J-3937D01*
G01X975591Y-31496D02*
G03Y-23622I0J3937D01*
G01Y-31496D02*
G03Y-23622I0J3937D01*
G01X1006299D02*
G03Y-31496I0J-3937D01*
G01X1162205D02*
X1006299D01*
G01X1162205D02*
X1006299D01*
G01Y-23622D02*
G03Y-31496I0J-3937D01*
G01Y634252D02*
X1162205D01*
G01X1006299D02*
X1162205D01*
G01X975591Y626378D02*
G03Y634252I0J3937D01*
G01Y626378D02*
G03Y634252I0J3937D01*
G01X1006299D02*
G03Y626378I0J-3937D01*
G01Y634252D02*
G03Y626378I0J-3937D01*
G01X1162205Y-31496D02*
G03Y-23622I0J3937D01*
G01Y-31496D02*
G03Y-23622I0J3937D01*
G01X1192913D02*
G03Y-31496I0J-3937D01*
G01X1398425D02*
X1192913D01*
G01X1398425D02*
X1192913D01*
G01Y-23622D02*
G03Y-31496I0J-3937D01*
G01Y634252D02*
X1394488D01*
G01X1192913D02*
X1394488D01*
G01X1162205Y626378D02*
G03Y634252I0J3937D01*
G01Y626378D02*
G03Y634252I0J3937D01*
G01X1192913D02*
G03Y626378I0J-3937D01*
G01Y634252D02*
G03Y626378I0J-3937D01*
G01X1398425Y-31496D02*
G03Y-23622I0J3937D01*
G01Y-31496D02*
G03Y-23622I0J3937D01*
G01X1405512Y-1968D02*
G03Y-13779I0J-5906D01*
G01Y-1968D02*
G03Y-13779I0J-5906D01*
G01Y-1968D02*
G03Y-13779I0J-5906D01*
G01Y-1968D02*
G03Y-13779I0J-5906D01*
G01X1394488Y626378D02*
G03Y634252I0J3937D01*
G01Y626378D02*
G03Y634252I0J3937D01*
G01X1405512Y616535D02*
G03Y604724I0J-5905D01*
G01Y616535D02*
G03Y604724I0J-5905D01*
G01Y616535D02*
G03Y604724I0J-5905D01*
G01Y616535D02*
G03Y604724I0J-5905D01*
G01X1429134Y-23622D02*
G03Y-31496I0J-3937D01*
G01X1851181D02*
X1429134D01*
G01X1851181D02*
X1429134D01*
G01Y-23622D02*
G03Y-31496I0J-3937D01*
G01X1413107Y-15529D02*
G03Y-218I6186J7655D01*
G01X1413105Y-15529D02*
G03Y-218I6186J7655D01*
G01Y-15529D02*
G03Y-218I6186J7655D01*
G01Y-15529D02*
G03Y-218I6186J7655D01*
G01Y-15529D02*
G03Y-218I6186J7655D01*
G01X1413107Y-15529D02*
G03Y-218I6186J7655D01*
G01X1408157Y-1968D02*
G03X1413107Y-218I1J7874D01*
G01X1408156Y-1968D02*
G03X1413105Y-218I0J7874D01*
G01X1408156Y-1968D02*
G03X1413105Y-218I0J7874D01*
G01X1408156Y-1968D02*
G03X1413105Y-218I0J7874D01*
G01X1408156Y-1968D02*
G03X1413105Y-218I0J7874D01*
G01X1408157Y-1968D02*
G03X1413107Y-218I1J7874D01*
G01Y-15529D02*
G03X1408157Y-13779I-4949J-6124D01*
G01X1413105Y-15529D02*
G03X1408156Y-13779I-4949J-6124D01*
G01X1413105Y-15529D02*
G03X1408156Y-13779I-4949J-6124D01*
G01X1413105Y-15529D02*
G03X1408156Y-13779I-4949J-6124D01*
G01X1413105Y-15529D02*
G03X1408156Y-13779I-4949J-6124D01*
G01X1413107Y-15529D02*
G03X1408157Y-13779I-4949J-6124D01*
G01X1405512D02*
X1408156D01*
G01X1408157D02*
X1405512D01*
G01X1408157D02*
X1405512D01*
G01D02*
X1408156D01*
G01X1405512Y-1968D02*
X1408157D01*
G01X1408156D02*
X1405512D01*
G01X1408156D02*
X1405512D01*
G01D02*
X1408157D01*
G01X1425197Y634252D02*
X1851181D01*
G01X1425197D02*
X1851181D01*
G01X1425197D02*
G03Y626378I0J-3937D01*
G01Y634252D02*
G03Y626378I0J-3937D01*
G01X1408157Y616535D02*
G03X1413107Y618285I1J7874D01*
G01X1408156Y616535D02*
G03X1413105Y618285I0J7874D01*
G01X1408156Y616535D02*
G03X1413105Y618285I0J7874D01*
G01X1413107Y602975D02*
G03Y618285I6186J7655D01*
G01X1413105Y602975D02*
G03Y618285I6187J7655D01*
G01Y602975D02*
G03Y618285I6187J7655D01*
G01X1413107Y602975D02*
G03X1408157Y604724I-4948J-6125D01*
G01X1413105Y602975D02*
G03X1408156Y604724I-4948J-6125D01*
G01X1413105Y602975D02*
G03X1408156Y604724I-4948J-6125D01*
G01X1413105Y602975D02*
G03X1408156Y604724I-4948J-6125D01*
G01X1413105Y602975D02*
G03X1408156Y604724I-4948J-6125D01*
G01X1413107Y602975D02*
G03X1408157Y604724I-4948J-6125D01*
G01X1413105Y602975D02*
G03Y618285I6187J7655D01*
G01Y602975D02*
G03Y618285I6187J7655D01*
G01X1413107Y602975D02*
G03Y618285I6186J7655D01*
G01X1408156Y616535D02*
G03X1413105Y618285I0J7874D01*
G01X1408156Y616535D02*
G03X1413105Y618285I0J7874D01*
G01X1408157Y616535D02*
G03X1413107Y618285I1J7874D01*
G01X1405512Y616535D02*
X1408157D01*
G01X1408156D02*
X1405512D01*
G01Y604724D02*
X1408156D01*
G01X1408157D02*
X1405512D01*
G01X1408157D02*
X1405512D01*
G01D02*
X1408156D01*
G01Y616535D02*
X1405512D01*
G01D02*
X1408157D01*
G01X1685866Y267244D02*
X1883780D01*
G01X1685866D02*
X1883780D01*
G01X1685866D02*
X1883780D01*
G01X1685866D02*
X1883780D01*
G01X1681929Y271181D02*
G03X1685866Y267244I3937J0D01*
G01X1681929Y271181D02*
G03X1685866Y267244I3937J0D01*
G01X1681929Y271181D02*
G03X1685866Y267244I3937J0D01*
G01X1681929Y271181D02*
G03X1685866Y267244I3937J0D01*
G01X1681929Y428661D02*
Y271181D01*
G01Y428661D02*
Y271181D01*
G01Y428661D02*
Y271181D01*
G01Y428661D02*
Y271181D01*
G01X1685866Y432598D02*
G03X1681929Y428661I0J-3937D01*
G01X1685866Y432598D02*
G03X1681929Y428661I0J-3937D01*
G01X1972441Y432598D02*
X1685866D01*
G01X1972441D02*
X1685866D01*
G01X1972441D02*
X1685866D01*
G01X1972441D02*
X1685866D01*
G01D02*
G03X1681929Y428661I0J-3937D01*
G01X1685866Y432598D02*
G03X1681929Y428661I0J-3937D01*
G01X1851181Y-31496D02*
G03Y-23622I0J3937D01*
G01Y-31496D02*
G03Y-23622I0J3937D01*
G01X1881890D02*
G03Y-31496I0J-3937D01*
G01X1972441D02*
X1881890D01*
G01X1972441D02*
X1881890D01*
G01Y-23622D02*
G03Y-31496I0J-3937D01*
G01X1861926Y-15529D02*
G03X1856976Y-13780I-4948J-6125D01*
G01X1861924Y-15529D02*
G03X1856975Y-13780I-4948J-6125D01*
G01X1861924Y-15529D02*
G03X1856975Y-13780I-4948J-6125D01*
G01X1861924Y-15529D02*
G03X1856975Y-13780I-4948J-6125D01*
G01X1861924Y-15529D02*
G03X1856975Y-13780I-4948J-6125D01*
G01X1861926Y-15529D02*
G03X1856976Y-13780I-4948J-6125D01*
G01Y-1969D02*
G03X1861926Y-219I0J7874D01*
G01X1856975Y-1969D02*
G03X1861924Y-219I0J7874D01*
G01X1856975Y-1969D02*
G03X1861924Y-219I0J7874D01*
G01X1861926Y-15529D02*
G03Y-219I6186J7655D01*
G01X1861924Y-15529D02*
G03Y-219I6186J7655D01*
G01Y-15529D02*
G03Y-219I6186J7655D01*
G01Y-15529D02*
G03Y-219I6186J7655D01*
G01Y-15529D02*
G03Y-219I6186J7655D01*
G01X1861926Y-15529D02*
G03Y-219I6186J7655D01*
G01X1856975Y-1969D02*
G03X1861924Y-219I0J7874D01*
G01X1856975Y-1969D02*
G03X1861924Y-219I0J7874D01*
G01X1856976Y-1969D02*
G03X1861926Y-219I0J7874D01*
G01X1854331Y-1969D02*
G03Y-13780I0J-5906D01*
G01Y-1969D02*
G03Y-13780I0J-5906D01*
G01D02*
X1856975D01*
G01X1856976D02*
X1854331D01*
G01X1856976D02*
X1854331D01*
G01D02*
X1856975D01*
G01X1854331Y-1969D02*
G03Y-13780I0J-5906D01*
G01Y-1969D02*
G03Y-13780I0J-5906D01*
G01Y-1969D02*
X1856976D01*
G01X1856975D02*
X1854331D01*
G01X1856975D02*
X1854331D01*
G01D02*
X1856976D01*
G01X1891654Y246772D02*
X1972441D01*
G01X1891654D02*
X1972441D01*
G01X1891654D02*
X1972441D01*
G01X1891654D02*
X1972441D01*
G01X1887717Y250709D02*
G03X1891654Y246772I3937J0D01*
G01X1887717Y250709D02*
G03X1891654Y246772I3937J0D01*
G01X1887717Y263307D02*
Y250709D01*
G01Y263307D02*
Y250709D01*
G01Y263307D02*
Y250709D01*
G01Y263307D02*
Y250709D01*
G01D02*
G03X1891654Y246772I3937J0D01*
G01X1887717Y250709D02*
G03X1891654Y246772I3937J0D01*
G01X1887717Y263307D02*
G03X1883780Y267244I-3937J0D01*
G01X1887717Y263307D02*
G03X1883780Y267244I-3937J0D01*
G01X1887717Y263307D02*
G03X1883780Y267244I-3937J0D01*
G01X1887717Y263307D02*
G03X1883780Y267244I-3937J0D01*
G01X1881890Y634252D02*
G03Y626378I0J-3937D01*
G01Y634252D02*
X1972441D01*
G01X1881890D02*
X1972441D01*
G01X1881890D02*
G03Y626378I0J-3937D01*
G01X1851181D02*
G03Y634252I0J3937D01*
G01Y626378D02*
G03Y634252I0J3937D01*
G01X1856976Y616535D02*
G03X1861926Y618285I0J7874D01*
G01X1856975Y616535D02*
G03X1861924Y618285I0J7874D01*
G01X1856975Y616535D02*
G03X1861924Y618285I0J7874D01*
G01X1861926Y602975D02*
G03Y618285I6186J7655D01*
G01X1861924Y602975D02*
G03Y618285I6186J7655D01*
G01Y602975D02*
G03Y618285I6186J7655D01*
G01Y602975D02*
G03Y618285I6186J7655D01*
G01Y602975D02*
G03Y618285I6186J7655D01*
G01X1861926Y602975D02*
G03Y618285I6186J7655D01*
G01X1856975Y616535D02*
G03X1861924Y618285I0J7874D01*
G01X1856975Y616535D02*
G03X1861924Y618285I0J7874D01*
G01X1856976Y616535D02*
G03X1861926Y618285I0J7874D01*
G01Y602975D02*
G03X1856976Y604724I-4948J-6125D01*
G01X1861924Y602975D02*
G03X1856975Y604724I-4948J-6125D01*
G01X1861924Y602975D02*
G03X1856975Y604724I-4948J-6125D01*
G01X1861924Y602975D02*
G03X1856975Y604724I-4948J-6125D01*
G01X1861924Y602975D02*
G03X1856975Y604724I-4948J-6125D01*
G01X1861926Y602975D02*
G03X1856976Y604724I-4948J-6125D01*
G01X1854331Y616535D02*
G03Y604724I0J-5905D01*
G01Y616535D02*
G03Y604724I0J-5905D01*
G01D02*
X1856975D01*
G01X1856976D02*
X1854331D01*
G01X1856976D02*
X1854331D01*
G01D02*
X1856975D01*
G01X1854331Y616535D02*
G03Y604724I0J-5905D01*
G01Y616535D02*
G03Y604724I0J-5905D01*
G01Y616535D02*
X1856976D01*
G01X1856975D02*
X1854331D01*
G01X1856975D02*
X1854331D01*
G01D02*
X1856976D01*
G01X1972441Y-11811D02*
X1906890D01*
G01X1904921Y-9843D02*
G03X1906890Y-11811I1969J1D01*
G01X1904921Y53150D02*
Y-9843D01*
G01X1972441Y-11811D02*
X1906890D01*
G01X1904921Y-9843D02*
G03X1906890Y-11811I1969J1D01*
G01X1904921Y53150D02*
Y-9843D01*
G01X1923071Y53150D02*
Y-9843D01*
G01X1940787Y-3937D02*
X1972441D01*
G01X1940787D02*
G03X1938819Y-5906I0J-1968D01*
G01Y-9843D02*
Y-5906D01*
G01Y-9843D02*
G03X1940787Y-11811I1968J0D01*
G01X1921102D02*
G03X1923071Y-9843I0J1969D01*
G01X1906890Y55118D02*
G03X1904921Y53150I0J-1969D01*
G01X1972441Y55118D02*
X1906890D01*
G01X1972441D02*
X1906890D01*
G01X1972441D02*
X1906890D01*
G01X1972441D02*
X1906890D01*
G01D02*
G03X1904921Y53150I0J-1969D01*
G01X1923071D02*
G03X1921102Y55118I-1969J-1D01*
G01X1940787D02*
G03X1938819Y53150I0J-1968D01*
G01Y49213D02*
Y53150D01*
G01Y49213D02*
G03X1940787Y47244I1968J-1D01*
G01X1972441D02*
X1940787D01*
G01X1976378Y-35433D02*
G03X1972441Y-31496I-3937J0D01*
G01X1976378Y-59055D02*
Y-35433D01*
G01Y-59055D02*
Y-35433D01*
G01D02*
G03X1972441Y-31496I-3937J0D01*
G01Y-62992D02*
G03X1976378Y-59055I0J3937D01*
G01X1972441Y-62992D02*
G03X1976378Y-59055I0J3937D01*
G01X1972441Y-23622D02*
G03X1976378Y-19685I0J3937D01*
G01X1972441Y-23622D02*
G03X1976378Y-19685I0J3937D01*
G01X1972441Y-23622D02*
G03X1976378Y-19685I0J3937D01*
G01X1972441Y-23622D02*
G03X1976378Y-19685I0J3937D01*
G01D02*
Y-15748D01*
G01Y-19685D02*
Y-15748D01*
G01Y-19685D02*
Y-15748D01*
G01Y-19685D02*
Y-15748D01*
G01D02*
G03X1972441Y-11811I-3937J0D01*
G01X1976378Y-15748D02*
G03X1972441Y-11811I-3937J0D01*
G01X1976378Y-15748D02*
G03X1972441Y-11811I-3937J0D01*
G01X1976378Y-15748D02*
G03X1972441Y-11811I-3937J0D01*
G01X1976378Y0D02*
Y43307D01*
G01X1972441Y-3937D02*
G03X1976378Y0I0J3937D01*
G01X1972441Y55118D02*
G03X1976378Y59055I0J3937D01*
G01X1972441Y55118D02*
G03X1976378Y59055I0J3937D01*
G01X1972441Y55118D02*
G03X1976378Y59055I0J3937D01*
G01X1972441Y55118D02*
G03X1976378Y59055I0J3937D01*
G01D02*
Y242835D01*
G01Y59055D02*
Y242835D01*
G01Y59055D02*
Y242835D01*
G01Y59055D02*
Y242835D01*
G01Y43307D02*
G03X1972441Y47244I-3937J0D01*
G01X1976378Y242835D02*
G03X1972441Y246772I-3937J0D01*
G01X1976378Y242835D02*
G03X1972441Y246772I-3937J0D01*
G01X1976378Y242835D02*
G03X1972441Y246772I-3937J0D01*
G01X1976378Y242835D02*
G03X1972441Y246772I-3937J0D01*
G01Y432598D02*
G03X1976378Y436535I0J3937D01*
G01X1972441Y432598D02*
G03X1976378Y436535I0J3937D01*
G01X1972441Y432598D02*
G03X1976378Y436535I0J3937D01*
G01X1972441Y432598D02*
G03X1976378Y436535I0J3937D01*
G01D02*
Y622441D01*
G01Y436535D02*
Y622441D01*
G01Y436535D02*
Y622441D01*
G01Y436535D02*
Y622441D01*
G01D02*
G03X1972441Y626378I-3937J0D01*
G01X1976378Y622441D02*
G03X1972441Y626378I-3937J0D01*
G01X1976378Y622441D02*
G03X1972441Y626378I-3937J0D01*
G01X1976378Y622441D02*
G03X1972441Y626378I-3937J0D01*
G01Y634252D02*
G03X1976378Y638189I0J3937D01*
G01X1972441Y634252D02*
G03X1976378Y638189I0J3937D01*
G01D02*
Y661811D01*
G01Y638189D02*
Y661811D01*
G01D02*
G03X1972441Y665748I-3937J0D01*
G01X1976378Y661811D02*
G03X1972441Y665748I-3937J0D01*
G54D12*
G01X34787Y155464D02*
X47197Y161407D01*
G01X32445Y153366D02*
X34787Y155464D01*
G01X34141Y156431D02*
X31842Y154371D01*
G01X28230Y151827D02*
X32445Y153366D01*
G01X31842Y154371D02*
X28026Y152977D01*
G01X-5132Y151827D02*
X28230D01*
G01X28026Y152977D02*
X-5609D01*
G01X-6800Y150159D02*
X-5132Y151827D01*
G01X-5609Y152977D02*
X-7950Y150636D01*
G01X-6800Y148988D02*
Y150159D01*
G01X-7950Y150636D02*
Y148951D01*
G01X49867Y159208D02*
X43678Y155736D01*
G01X42083Y155646D02*
X42938Y156640D01*
G01X43678Y155736D02*
X43090Y155053D01*
G01X40761Y152078D02*
X42083Y155646D01*
G01X43090Y155053D02*
X41764Y151474D01*
G01X36468Y147272D02*
X40761Y152078D01*
G01X41764Y151474D02*
X40865Y150467D01*
G01X36468Y147272D02*
X40761Y152078D01*
G01X39099Y148491D02*
X37234Y146403D01*
G01X33315Y145103D02*
X36468Y147272D01*
G01X37234Y146403D02*
X33673Y143953D01*
G01X9939Y145103D02*
X33315D01*
G01X33673Y143953D02*
X9462D01*
G01X9400Y145642D02*
X9939Y145103D01*
G01X9462Y143953D02*
X8250Y145165D01*
G01X9400Y146709D02*
Y145642D01*
G01X8250Y145165D02*
Y146620D01*
G01X42691Y147691D02*
X46288Y148450D01*
G01X46409Y147300D02*
X43263Y146636D01*
G01X39117Y144117D02*
X42691Y147691D01*
G01X43263Y146636D02*
X39851Y143223D01*
G01X30361Y138266D02*
X39117Y144117D01*
G01X39851Y143223D02*
X38728Y142473D01*
G01X30361Y138266D02*
X39117Y144117D01*
G01X37427Y140822D02*
X36525Y141001D01*
G01X30361Y138266D02*
X39117Y144117D01*
G01X36525Y141001D02*
X35402Y140251D01*
G01X30361Y138266D02*
X39117Y144117D01*
G01X34100Y138600D02*
X33199Y138779D01*
G01X30361Y138266D02*
X39117Y144117D01*
G01X33199Y138779D02*
X30906Y137247D01*
G01X27858Y137229D02*
X30361Y138266D01*
G01X30906Y137247D02*
X28087Y136079D01*
G01X5155Y137229D02*
X27858D01*
G01X28087Y136079D02*
X4678D01*
G01X4400Y137984D02*
X5155Y137229D01*
G01X4678Y136079D02*
X3250Y137507D01*
G01X4400Y139050D02*
Y137984D01*
G01X3250Y137507D02*
Y139262D01*
G01X-7950Y150636D02*
Y148951D01*
G01X-6800Y148988D02*
Y150159D01*
G01X-5609Y152977D02*
X-7950Y150636D01*
G01X-6800Y150159D02*
X-5132Y151827D01*
G01X28026Y152977D02*
X-5609D01*
G01X-5132Y151827D02*
X28230D01*
G01X31842Y154371D02*
X28026Y152977D01*
G01X28230Y151827D02*
X32445Y153366D01*
G01X34141Y156431D02*
X31842Y154371D01*
G01X32445Y153366D02*
X34787Y155464D01*
G01D02*
X47197Y161407D01*
G01X8250Y145165D02*
Y146620D01*
G01X9400Y146709D02*
Y145642D01*
G01X9462Y143953D02*
X8250Y145165D01*
G01X9400Y145642D02*
X9939Y145103D01*
G01X33673Y143953D02*
X9462D01*
G01X9939Y145103D02*
X33315D01*
G01X37234Y146403D02*
X33673Y143953D01*
G01X33315Y145103D02*
X36468Y147272D01*
G01X41764Y151474D02*
X40865Y150467D01*
G01X39099Y148491D02*
X37234Y146403D01*
G01X36468Y147272D02*
X40761Y152078D01*
G01X43090Y155053D02*
X41764Y151474D01*
G01X40761Y152078D02*
X42083Y155646D01*
G01X43678Y155736D02*
X43090Y155053D01*
G01X42083Y155646D02*
X42938Y156640D01*
G01X49867Y159208D02*
X43678Y155736D01*
G01X3250Y137507D02*
Y139262D01*
G01X4400Y139050D02*
Y137984D01*
G01X4678Y136079D02*
X3250Y137507D01*
G01X4400Y137984D02*
X5155Y137229D01*
G01X28087Y136079D02*
X4678D01*
G01X5155Y137229D02*
X27858D01*
G01X30906Y137247D02*
X28087Y136079D01*
G01X27858Y137229D02*
X30361Y138266D01*
G01X39851Y143223D02*
X38728Y142473D01*
G01X37427Y140822D02*
X36525Y141001D01*
G01D02*
X35402Y140251D01*
G01X34100Y138600D02*
X33199Y138779D01*
G01D02*
X30906Y137247D01*
G01X30361Y138266D02*
X39117Y144117D01*
G01X43263Y146636D02*
X39851Y143223D01*
G01X39117Y144117D02*
X42691Y147691D01*
G01X46409Y147300D02*
X43263Y146636D01*
G01X42691Y147691D02*
X46288Y148450D01*
G01X46848Y162516D02*
X34141Y156431D01*
G01X42938Y156640D02*
X49480Y160311D01*
G01X46848Y162516D02*
X34141Y156431D01*
G01X42938Y156640D02*
X49480Y160311D01*
G01X-12100Y158596D02*
Y159700D01*
G01X-13250Y158442D02*
Y160177D01*
G01X-12100Y159700D02*
X-5500Y166300D01*
G01X-13250Y160177D02*
X-5977Y167450D01*
G01X-5500Y166300D02*
X25253D01*
G01X-5977Y167450D02*
X25139D01*
G01X25253Y166300D02*
X39330Y169100D01*
G01X25139Y167450D02*
X39216Y170250D01*
G01X39330Y169100D02*
X44129D01*
G01X39216Y170250D02*
X44015D01*
G01X44129Y169100D02*
X63825Y173017D01*
G01X44015Y170250D02*
X63711Y174167D01*
G01X54972Y168003D02*
X42601Y165976D01*
G01X54766Y169135D02*
X42641Y167148D01*
G01X42601Y165976D02*
X41322Y166275D01*
G01X42641Y167148D02*
X41361Y167447D01*
G01X41322Y166275D02*
X24730Y163557D01*
G01X41361Y167447D02*
X24636Y164707D01*
G01X24730Y163557D02*
X13386D01*
G01X11112D02*
X7779D01*
G01X24636Y164707D02*
X7487D01*
G01X7779Y163557D02*
X6291Y162748D01*
G01X7487Y164707D02*
X5595Y163680D01*
G01X6291Y162748D02*
X4300Y160758D01*
G01X5595Y163680D02*
X3150Y161235D01*
G01X4300Y160758D02*
Y158732D01*
G01X3150Y161235D02*
Y158307D01*
G01X55108Y166562D02*
X42358Y164473D01*
G01X55305Y165428D02*
X42319Y163301D01*
G01X42358Y164473D02*
X41082Y164772D01*
G01X42319Y163301D02*
X41042Y163600D01*
G01X41082Y164772D02*
X22729Y161765D01*
G01X41042Y163600D02*
X23055Y160653D01*
G01X22729Y161765D02*
X21416Y161197D01*
G01X23055Y160653D02*
X22073Y160228D01*
G01X21416Y161197D02*
X19650Y159437D01*
G01X22073Y160228D02*
X20800Y158959D01*
G01X19650Y159437D02*
Y158272D01*
G01X20800Y158959D02*
Y158124D01*
G01X-13250Y158442D02*
Y160177D01*
G01X-12100Y158596D02*
Y159700D01*
G01X-13250Y160177D02*
X-5977Y167450D01*
G01X-12100Y159700D02*
X-5500Y166300D01*
G01X-5977Y167450D02*
X25139D01*
G01X-5500Y166300D02*
X25253D01*
G01X25139Y167450D02*
X39216Y170250D01*
G01X25253Y166300D02*
X39330Y169100D01*
G01X39216Y170250D02*
X44015D01*
G01X39330Y169100D02*
X44129D01*
G01X44015Y170250D02*
X63711Y174167D01*
G01X44129Y169100D02*
X63825Y173017D01*
G01X54766Y169135D02*
X42641Y167148D01*
G01X54972Y168003D02*
X42601Y165976D01*
G01X42641Y167148D02*
X41361Y167447D01*
G01X42601Y165976D02*
X41322Y166275D01*
G01X41361Y167447D02*
X24636Y164707D01*
G01X41322Y166275D02*
X24730Y163557D01*
G01X24636Y164707D02*
X7487D01*
G01X24730Y163557D02*
X13386D01*
G01X24636Y164707D02*
X7487D01*
G01X11112Y163557D02*
X7779D01*
G01X7487Y164707D02*
X5595Y163680D01*
G01X7779Y163557D02*
X6291Y162748D01*
G01X5595Y163680D02*
X3150Y161235D01*
G01X6291Y162748D02*
X4300Y160758D01*
G01X3150Y161235D02*
Y158307D01*
G01X4300Y160758D02*
Y158732D01*
G01X55305Y165428D02*
X42319Y163301D01*
G01X55108Y166562D02*
X42358Y164473D01*
G01X42319Y163301D02*
X41042Y163600D01*
G01X42358Y164473D02*
X41082Y164772D01*
G01X41042Y163600D02*
X23055Y160653D01*
G01X41082Y164772D02*
X22729Y161765D01*
G01X23055Y160653D02*
X22073Y160228D01*
G01X22729Y161765D02*
X21416Y161197D01*
G01X22073Y160228D02*
X20800Y158959D01*
G01X21416Y161197D02*
X19650Y159437D01*
G01X20800Y158959D02*
Y158124D01*
G01X19650Y159437D02*
Y158272D01*
G01X37982Y430254D02*
X76969Y469241D01*
G01X75819Y469718D02*
X36832Y430731D01*
G01X37982Y429618D02*
Y430254D01*
G01X36832Y430731D02*
Y429141D01*
G01X38166Y429434D02*
X37982Y429618D01*
G01X36832Y429141D02*
X37550Y428423D01*
G01X36832Y429141D02*
X37550Y428423D01*
G01X38166Y429434D02*
X37982Y429618D01*
G01X36832Y430731D02*
Y429141D01*
G01X37982Y429618D02*
Y430254D01*
G01X75819Y469718D02*
X36832Y430731D01*
G01X37982Y430254D02*
X76969Y469241D01*
G01X81263Y95850D02*
X68029Y93216D01*
G01X81149Y97000D02*
X67462Y94276D01*
G01X68029Y93216D02*
X66800Y91987D01*
G01X67462Y94276D02*
X65650Y92464D01*
G01X66800Y91987D02*
Y91350D01*
G01X65650Y92464D02*
Y91350D01*
G01X81149Y97000D02*
X67462Y94276D01*
G01X81263Y95850D02*
X68029Y93216D01*
G01X67462Y94276D02*
X65650Y92464D01*
G01X68029Y93216D02*
X66800Y91987D01*
G01X65650Y92464D02*
Y91350D01*
G01X66800Y91987D02*
Y91350D01*
G01X59316Y154516D02*
X67834Y158041D01*
G01X68155Y156929D02*
X59968Y153540D01*
G01X55739Y150939D02*
X59316Y154516D01*
G01X59968Y153540D02*
X56391Y149963D01*
G01X49731Y148450D02*
X55739Y150939D01*
G01X56391Y149963D02*
X49960Y147300D01*
G01X46288Y148450D02*
X49731D01*
G01X49960Y147300D02*
X46409D01*
G01X49960D02*
X46409D01*
G01X46288Y148450D02*
X49731D01*
G01X56391Y149963D02*
X49960Y147300D01*
G01X49731Y148450D02*
X55739Y150939D01*
G01X59968Y153540D02*
X56391Y149963D01*
G01X55739Y150939D02*
X59316Y154516D01*
G01X68155Y156929D02*
X59968Y153540D01*
G01X59316Y154516D02*
X67834Y158041D01*
G01X129722Y101445D02*
X101753Y95850D01*
G01X129273Y102528D02*
X101639Y97000D01*
G01X101753Y95850D02*
X81263D01*
G01X101639Y97000D02*
X97149D01*
G01X101753Y95850D02*
X81263D01*
G01X94499Y97000D02*
X93149D01*
G01X101753Y95850D02*
X81263D01*
G01X90499Y97000D02*
X89149D01*
G01X101753Y95850D02*
X81263D01*
G01X86499Y97000D02*
X85149D01*
G01X101753Y95850D02*
X81263D01*
G01X82499Y97000D02*
X81149D01*
G01X129273Y102528D02*
X101639Y97000D01*
G01X129722Y101445D02*
X101753Y95850D01*
G01X101639Y97000D02*
X97149D01*
G01X94499D02*
X93149D01*
G01X90499D02*
X89149D01*
G01X86499D02*
X85149D01*
G01X82499D02*
X81149D01*
G01X101753Y95850D02*
X81263D01*
G01X48734Y154806D02*
Y155910D01*
G01X49884Y154706D02*
Y155498D01*
G01X48734Y155910D02*
X49936Y157377D01*
G01X49884Y155498D02*
X50631Y156409D01*
G01X107768Y153467D02*
X114038Y151150D01*
G01X113817Y150000D02*
X107472Y152350D01*
G01X100595Y154650D02*
X107768Y153467D01*
G01X107472Y152350D02*
X100500Y153500D01*
G01X92305Y154650D02*
X100595D01*
G01X100500Y153500D02*
X92103D01*
G01X82837Y158059D02*
X92305Y154650D01*
G01X92103Y153500D02*
X82749Y156868D01*
G01X66899Y154872D02*
X82837Y158059D01*
G01X82749Y156868D02*
X67466Y153812D01*
G01X65023Y152996D02*
X66899Y154872D01*
G01X67466Y153812D02*
X66173Y152519D01*
G01X65023Y151823D02*
Y152996D01*
G01X66173Y152519D02*
Y151823D01*
G01X49884Y154706D02*
Y155498D01*
G01X48734Y154806D02*
Y155910D01*
G01X49884Y155498D02*
X50631Y156409D01*
G01X48734Y155910D02*
X49936Y157377D01*
G01X66173Y152519D02*
Y151823D01*
G01X65023D02*
Y152996D01*
G01X67466Y153812D02*
X66173Y152519D01*
G01X65023Y152996D02*
X66899Y154872D01*
G01X82749Y156868D02*
X67466Y153812D01*
G01X66899Y154872D02*
X82837Y158059D01*
G01X92103Y153500D02*
X82749Y156868D01*
G01X82837Y158059D02*
X92305Y154650D01*
G01X100500Y153500D02*
X92103D01*
G01X92305Y154650D02*
X100595D01*
G01X107472Y152350D02*
X100500Y153500D01*
G01X100595Y154650D02*
X107768Y153467D01*
G01X113817Y150000D02*
X107472Y152350D01*
G01X107768Y153467D02*
X114038Y151150D01*
G01X107624Y99585D02*
X61284D01*
G01X61371Y100735D02*
X107510D01*
G01X127916Y103646D02*
X107624Y99585D01*
G01X107510Y100735D02*
X108834Y101000D01*
G01X127916Y103646D02*
X107624Y99585D01*
G01X127916Y103646D02*
X107624Y99585D01*
G01X127916Y103646D02*
X107624Y99585D01*
G01X127916Y103646D02*
X107624Y99585D01*
G01X67203Y107825D02*
X65834D01*
G01Y106675D02*
X67432D01*
G01X68426Y108331D02*
X67203Y107825D01*
G01X67432Y106675D02*
X69078Y107356D01*
G01X70202Y110110D02*
X68426Y108331D01*
G01X69078Y107356D02*
X70679Y108960D01*
G01X75406Y110110D02*
X70202D01*
G01X70679Y108960D02*
X74929D01*
G01X76541Y108975D02*
X75406Y110110D01*
G01X74929Y108960D02*
X76064Y107825D01*
G01X110176Y108975D02*
X76541D01*
G01X76064Y107825D02*
X110405D01*
G01X115260Y115873D02*
X73299D01*
G01X115489Y114723D02*
X73528D01*
G01X73299Y115873D02*
X70651Y114776D01*
G01X73528Y114723D02*
X70880Y113626D01*
G01X70651Y114776D02*
X61199D01*
G01X70880Y113626D02*
X61150D01*
G01X110049Y119277D02*
X107021Y117258D01*
G01X109600Y120360D02*
X106674Y118409D01*
G01X107021Y117258D02*
X91716Y117295D01*
G01X106674Y118409D02*
X91718Y118445D01*
G01X107021Y117258D02*
X91716Y117295D01*
G01Y117294D02*
X76533Y117331D01*
G01X91718Y118445D02*
X91719D01*
G01X91716Y117294D02*
X76533Y117331D01*
G01X91719Y118445D02*
X76763Y118481D01*
G01X76533Y117331D02*
X68463Y120674D01*
G01X76763Y118481D02*
X68692Y121825D01*
G01X68462Y120675D02*
X65875D01*
G01X68692Y121825D02*
X65835D01*
G01X112277Y125100D02*
X76454D01*
G01X112506Y123950D02*
X76225D01*
G01X76454Y125100D02*
X67461Y128825D01*
G01X76225Y123950D02*
X67232Y127675D01*
G01X67461Y128825D02*
X61281D01*
G01X67232Y127675D02*
X61281D01*
G01X66137Y134675D02*
X70797D01*
G01X66137Y135825D02*
X71274D01*
G01X70797Y134675D02*
X71247Y134225D01*
G01X71274Y135825D02*
X72397Y134702D01*
G01X71247Y134225D02*
Y132001D01*
G01X72397Y134702D02*
Y132478D01*
G01X71247Y132001D02*
X72370Y130878D01*
G01X72397Y132478D02*
X72847Y132028D01*
G01X72370Y130878D02*
X75374D01*
G01X72847Y132028D02*
X74897D01*
G01X75374Y130878D02*
X76497Y132001D01*
G01X74897Y132028D02*
X75347Y132478D01*
G01X76497Y132001D02*
Y134225D01*
G01X75347Y132478D02*
Y134702D01*
G01X76497Y134225D02*
X77272Y135000D01*
G01X75347Y134702D02*
X76795Y136150D01*
G01X77272Y135000D02*
X79264D01*
G01X76795Y136150D02*
X79493D01*
G01X79264Y135000D02*
X95784Y128158D01*
G01X79493Y136150D02*
X96013Y129308D01*
G01X95784Y128158D02*
X99725D01*
G01X96013Y129308D02*
X99496D01*
G01X99725Y128158D02*
X119202Y136226D01*
G01X99496Y129308D02*
X119087Y137424D01*
G01X61315Y142848D02*
X64561D01*
G01X61304Y141698D02*
X64332D01*
G01X64561Y142848D02*
X69217Y140920D01*
G01X64332Y141698D02*
X68988Y139770D01*
G01X69217Y140920D02*
X74615D01*
G01X68988Y139770D02*
X74391D01*
G01X74615Y140920D02*
X96533Y132077D01*
G01X74391Y139770D02*
X96309Y130927D01*
G01X96533Y132077D02*
X98958D01*
G01X96309Y130927D02*
X99192D01*
G01X98958Y132077D02*
X116067Y139320D01*
G01X99192Y130927D02*
X116440Y138229D01*
G01X107510Y100735D02*
X108834Y101000D01*
G01X127916Y103646D02*
X107624Y99585D01*
G01X61371Y100735D02*
X107510D01*
G01X107624Y99585D02*
X61284D01*
G01X76064Y107825D02*
X110405D01*
G01X110176Y108975D02*
X76541D01*
G01X74929Y108960D02*
X76064Y107825D01*
G01X76541Y108975D02*
X75406Y110110D01*
G01X70679Y108960D02*
X74929D01*
G01X75406Y110110D02*
X70202D01*
G01X69078Y107356D02*
X70679Y108960D01*
G01X70202Y110110D02*
X68426Y108331D01*
G01X67432Y106675D02*
X69078Y107356D01*
G01X68426Y108331D02*
X67203Y107825D01*
G01X65834Y106675D02*
X67432D01*
G01X67203Y107825D02*
X65834D01*
G01X115489Y114723D02*
X73528D01*
G01X115260Y115873D02*
X73299D01*
G01X73528Y114723D02*
X70880Y113626D01*
G01X73299Y115873D02*
X70651Y114776D01*
G01X70880Y113626D02*
X61150D01*
G01X70651Y114776D02*
X61199D01*
G01X109600Y120360D02*
X106674Y118409D01*
G01X110049Y119277D02*
X107021Y117258D01*
G01X106674Y118409D02*
X91718Y118445D01*
G01D02*
X91719D01*
G01X107021Y117258D02*
X91716Y117295D01*
G01X91718Y118445D02*
X91719D01*
G01D02*
X76763Y118481D01*
G01X91716Y117294D02*
X76533Y117331D01*
G01X76763Y118481D02*
X68692Y121825D01*
G01X76533Y117331D02*
X68463Y120674D01*
G01X68692Y121825D02*
X65835D01*
G01X68462Y120675D02*
X65875D01*
G01X112506Y123950D02*
X76225D01*
G01X112277Y125100D02*
X76454D01*
G01X76225Y123950D02*
X67232Y127675D01*
G01X76454Y125100D02*
X67461Y128825D01*
G01X67232Y127675D02*
X61281D01*
G01X67461Y128825D02*
X61281D01*
G01X66137Y135825D02*
X71274D01*
G01X66137Y134675D02*
X70797D01*
G01X71274Y135825D02*
X72397Y134702D01*
G01X70797Y134675D02*
X71247Y134225D01*
G01X72397Y134702D02*
Y132478D01*
G01X71247Y134225D02*
Y132001D01*
G01X72397Y132478D02*
X72847Y132028D01*
G01X71247Y132001D02*
X72370Y130878D01*
G01X72847Y132028D02*
X74897D01*
G01X72370Y130878D02*
X75374D01*
G01X74897Y132028D02*
X75347Y132478D01*
G01X75374Y130878D02*
X76497Y132001D01*
G01X75347Y132478D02*
Y134702D01*
G01X76497Y132001D02*
Y134225D01*
G01X75347Y134702D02*
X76795Y136150D01*
G01X76497Y134225D02*
X77272Y135000D01*
G01X76795Y136150D02*
X79493D01*
G01X77272Y135000D02*
X79264D01*
G01X79493Y136150D02*
X96013Y129308D01*
G01X79264Y135000D02*
X95784Y128158D01*
G01X96013Y129308D02*
X99496D01*
G01X95784Y128158D02*
X99725D01*
G01X99496Y129308D02*
X119087Y137424D01*
G01X99725Y128158D02*
X119202Y136226D01*
G01X61304Y141698D02*
X64332D01*
G01X61315Y142848D02*
X64561D01*
G01X64332Y141698D02*
X68988Y139770D01*
G01X64561Y142848D02*
X69217Y140920D01*
G01X68988Y139770D02*
X74391D01*
G01X69217Y140920D02*
X74615D01*
G01X74391Y139770D02*
X96309Y130927D01*
G01X74615Y140920D02*
X96533Y132077D01*
G01X96309Y130927D02*
X99192D01*
G01X96533Y132077D02*
X98958D01*
G01X99192Y130927D02*
X116440Y138229D01*
G01X98958Y132077D02*
X116067Y139320D01*
G01X102906Y171739D02*
X123488Y167623D01*
G01X123864Y168721D02*
X102906Y172912D01*
G01X69727Y165104D02*
X102906Y171739D01*
G01Y172912D02*
X69521Y166236D01*
G01X47197Y161407D02*
X69727Y165104D01*
G01X69521Y166236D02*
X46848Y162516D01*
G01X104994Y169716D02*
X112868Y166187D01*
G01X112207Y165222D02*
X104714Y168581D01*
G01X101244Y169950D02*
X104994Y169716D01*
G01X104714Y168581D02*
X101323Y168792D01*
G01X69371Y163578D02*
X101244Y169950D01*
G01X101323Y168792D02*
X98998Y168326D01*
G01X69371Y163578D02*
X101244Y169950D01*
G01X96482Y167824D02*
X69577Y162446D01*
G01X49480Y160311D02*
X69371Y163578D01*
G01X69577Y162446D02*
X49867Y159208D01*
G01X98398Y157800D02*
X101936D01*
G01X104586D02*
X109936D01*
G01X109545Y156650D02*
X98093D01*
G01X91779Y161576D02*
X98398Y157800D01*
G01X98093Y156650D02*
X91382Y160478D01*
G01X67834Y158041D02*
X90180Y161859D01*
G01D02*
X91779Y161576D01*
G01D02*
X98398Y157800D01*
G01X91382Y160478D02*
X90177Y160691D01*
G01X67834Y158041D02*
X90180Y161859D01*
G01X90177Y160691D02*
X68155Y156929D01*
G01X69521Y166236D02*
X46848Y162516D01*
G01X47197Y161407D02*
X69727Y165104D01*
G01X102906Y172912D02*
X69521Y166236D01*
G01X69727Y165104D02*
X102906Y171739D01*
G01X123864Y168721D02*
X102906Y172912D01*
G01Y171739D02*
X123488Y167623D01*
G01X69577Y162446D02*
X49867Y159208D01*
G01X49480Y160311D02*
X69371Y163578D01*
G01X101323Y168792D02*
X98998Y168326D01*
G01X96482Y167824D02*
X69577Y162446D01*
G01X69371Y163578D02*
X101244Y169950D01*
G01X104714Y168581D02*
X101323Y168792D01*
G01X101244Y169950D02*
X104994Y169716D01*
G01X112207Y165222D02*
X104714Y168581D01*
G01X104994Y169716D02*
X112868Y166187D01*
G01X91382Y160478D02*
X90177Y160691D01*
G01D02*
X68155Y156929D01*
G01X67834Y158041D02*
X90180Y161859D01*
G01X91382Y160478D02*
X90177Y160691D01*
G01X90180Y161859D02*
X91779Y161576D01*
G01X98093Y156650D02*
X91382Y160478D01*
G01D02*
X90177Y160691D01*
G01X91779Y161576D02*
X98398Y157800D01*
G01X109545Y156650D02*
X98093D01*
G01X98398Y157800D02*
X101936D01*
G01X109545Y156650D02*
X98093D01*
G01X104586Y157800D02*
X109936D01*
G01X63825Y173017D02*
X67287D01*
G01X63711Y174167D02*
X67173D01*
G01X67287Y173017D02*
X102125Y179985D01*
G01X67173Y174167D02*
X102129Y181159D01*
G01X102126Y179985D02*
X105368Y179310D01*
G01X102130Y181159D02*
X105298Y180500D01*
G01X105368Y179310D02*
X108866Y180477D01*
G01X105298Y180500D02*
X108000Y181401D01*
G01X125638Y172295D02*
X101029Y177214D01*
G01X126001Y173396D02*
X101029Y178387D01*
G01Y177214D02*
X54972Y168003D01*
G01X101029Y178387D02*
X54766Y169135D01*
G01X125178Y171009D02*
X101260Y175791D01*
G01X124797Y169912D02*
X101260Y174618D01*
G01Y175791D02*
X55108Y166562D01*
G01X101260Y174618D02*
X55305Y165428D01*
G01X63711Y174167D02*
X67173D01*
G01X63825Y173017D02*
X67287D01*
G01X67173Y174167D02*
X102129Y181159D01*
G01X67287Y173017D02*
X102125Y179985D01*
G01X102130Y181159D02*
X105298Y180500D01*
G01X102126Y179985D02*
X105368Y179310D01*
G01X105298Y180500D02*
X108000Y181401D01*
G01X105368Y179310D02*
X108866Y180477D01*
G01X126001Y173396D02*
X101029Y178387D01*
G01X125638Y172295D02*
X101029Y177214D01*
G01Y178387D02*
X54766Y169135D01*
G01X101029Y177214D02*
X54972Y168003D01*
G01X124797Y169912D02*
X101260Y174618D01*
G01X125178Y171009D02*
X101260Y175791D01*
G01Y174618D02*
X55305Y165428D01*
G01X101260Y175791D02*
X55108Y166562D01*
G01X49936Y157377D02*
X51349Y157910D01*
G01X50631Y156409D02*
X51651Y156794D01*
G01X51349Y157910D02*
X67960Y160647D01*
G01X51651Y156794D02*
X68166Y159515D01*
G01X67960Y160647D02*
X93035Y165664D01*
G01X68166Y159515D02*
X93022Y164488D01*
G01X93035Y165664D02*
X100697Y163956D01*
G01X93022Y164488D02*
X100379Y162848D01*
G01X100697Y163956D02*
X101970Y163507D01*
G01X104469Y162625D02*
X109717Y160772D01*
G01X100379Y162848D02*
X115439Y157532D01*
G01X50631Y156409D02*
X51651Y156794D01*
G01X49936Y157377D02*
X51349Y157910D01*
G01X51651Y156794D02*
X68166Y159515D01*
G01X51349Y157910D02*
X67960Y160647D01*
G01X68166Y159515D02*
X93022Y164488D01*
G01X67960Y160647D02*
X93035Y165664D01*
G01X93022Y164488D02*
X100379Y162848D01*
G01X93035Y165664D02*
X100697Y163956D01*
G01X100379Y162848D02*
X115439Y157532D01*
G01X100697Y163956D02*
X101970Y163507D01*
G01X100379Y162848D02*
X115439Y157532D01*
G01X104469Y162625D02*
X109717Y160772D01*
G01X100379Y162848D02*
X115439Y157532D01*
G01X76774Y524664D02*
X93693Y541583D01*
G01X93216Y542733D02*
X75624Y525141D01*
G01X76774Y514174D02*
Y524664D01*
G01X75624Y525141D02*
Y514651D01*
G01X68500Y505900D02*
X76774Y514174D01*
G01X75624Y514651D02*
X67350Y506377D01*
G01X68500Y491726D02*
Y505900D01*
G01X67350Y506377D02*
Y491249D01*
G01X76969Y483257D02*
X68500Y491726D01*
G01X67350Y491249D02*
X75819Y482780D01*
G01X76969Y469241D02*
Y483257D01*
G01X75819Y482780D02*
Y469718D01*
G01Y482780D02*
Y469718D01*
G01X76969Y469241D02*
Y483257D01*
G01X67350Y491249D02*
X75819Y482780D01*
G01X76969Y483257D02*
X68500Y491726D01*
G01X67350Y506377D02*
Y491249D01*
G01X68500Y491726D02*
Y505900D01*
G01X75624Y514651D02*
X67350Y506377D01*
G01X68500Y505900D02*
X76774Y514174D01*
G01X75624Y525141D02*
Y514651D01*
G01X76774Y514174D02*
Y524664D01*
G01X93216Y542733D02*
X75624Y525141D01*
G01X76774Y524664D02*
X93693Y541583D01*
G01X103300Y586471D02*
X116032Y599203D01*
G01X115555Y600353D02*
X102150Y586948D01*
G01X103300Y546800D02*
Y586471D01*
G01X102150Y586948D02*
Y547277D01*
G01X98083Y541583D02*
X103300Y546800D01*
G01X102150Y547277D02*
X97606Y542733D01*
G01X93693Y541583D02*
X98083D01*
G01X97606Y542733D02*
X93216D01*
G01X97606D02*
X93216D01*
G01X93693Y541583D02*
X98083D01*
G01X102150Y547277D02*
X97606Y542733D01*
G01X98083Y541583D02*
X103300Y546800D01*
G01X102150Y586948D02*
Y547277D01*
G01X103300Y546800D02*
Y586471D01*
G01X115555Y600353D02*
X102150Y586948D01*
G01X103300Y586471D02*
X116032Y599203D01*
G01X136877Y154000D02*
X163765Y162317D01*
G01X164265Y161267D02*
X137051Y152850D01*
G01X114882Y154000D02*
X136877D01*
G01X137051Y152850D02*
X114491D01*
G01X109936Y157800D02*
X114882Y154000D01*
G01X114491Y152850D02*
X111708Y154988D01*
G01X109936Y157800D02*
X114882Y154000D01*
G01X111708Y154988D02*
X111707D01*
G01X109936Y157800D02*
X114882Y154000D01*
G01X111707Y154988D02*
X109545Y156650D01*
G01X114491Y152850D02*
X111708Y154988D01*
G01D02*
X111707D01*
G01D02*
X109545Y156650D01*
G01X109936Y157800D02*
X114882Y154000D01*
G01X137051Y152850D02*
X114491D01*
G01X114882Y154000D02*
X136877D01*
G01X164265Y161267D02*
X137051Y152850D01*
G01X136877Y154000D02*
X163765Y162317D01*
G01X176603Y132706D02*
X129722Y101445D01*
G01X175773Y133536D02*
X129273Y102528D01*
G01X175773Y133536D02*
X129273Y102528D01*
G01X176603Y132706D02*
X129722Y101445D01*
G01X115439Y157532D02*
X119593Y155450D01*
G01D02*
X135116D01*
G01D02*
X163531Y164040D01*
G01X166403Y159250D02*
X157416Y156205D01*
G01X136200Y151150D02*
X157069Y157302D01*
G01X157416Y156205D02*
X136366Y150000D01*
G01X114038Y151150D02*
X136200D01*
G01X136366Y150000D02*
X113817D01*
G01X115439Y157532D02*
X119593Y155450D01*
G01D02*
X135116D01*
G01D02*
X163531Y164040D01*
G01X136366Y150000D02*
X113817D01*
G01X114038Y151150D02*
X136200D01*
G01X157416Y156205D02*
X136366Y150000D01*
G01X136200Y151150D02*
X157069Y157302D01*
G01X166403Y159250D02*
X157416Y156205D01*
G01X111432Y101520D02*
X112756Y101785D01*
G01X115354Y102305D02*
X116678Y102570D01*
G01X119277Y103090D02*
X120600Y103355D01*
G01X123199Y103875D02*
X127467Y104729D01*
G01X174867Y134978D02*
X127916Y103646D01*
G01X127467Y104729D02*
X174037Y135808D01*
G01X151197Y125968D02*
X110176Y108975D01*
G01X110405Y107825D02*
X126615Y114540D01*
G01X151197Y125968D02*
X110176Y108975D01*
G01X129063Y115554D02*
X130310Y116070D01*
G01X151197Y125968D02*
X110176Y108975D01*
G01X132758Y117085D02*
X134006Y117601D01*
G01X151197Y125968D02*
X110176Y108975D01*
G01X136454Y118615D02*
X151795Y124970D01*
G01X175024Y145505D02*
X151197Y125968D01*
G01X151795Y124970D02*
X155495Y128004D01*
G01X175024Y145505D02*
X151197Y125968D01*
G01X155495Y128004D02*
X156410Y127913D01*
G01X175024Y145505D02*
X151197Y125968D01*
G01X157544Y129684D02*
X158588Y130540D01*
G01X175024Y145505D02*
X151197Y125968D01*
G01X158588Y130540D02*
X159503Y130450D01*
G01X175024Y145505D02*
X151197Y125968D01*
G01X160637Y132220D02*
X161681Y133076D01*
G01X175024Y145505D02*
X151197Y125968D01*
G01X161681Y133076D02*
X162596Y132986D01*
G01X175024Y145505D02*
X151197Y125968D01*
G01X163731Y134757D02*
X175710Y144579D01*
G01X223216Y180911D02*
X163695Y141222D01*
G01X224046Y180081D02*
X164428Y140328D01*
G01X163695Y141222D02*
X154668Y132196D01*
G01X164428Y140328D02*
X155320Y131220D01*
G01X154668Y132196D02*
X115260Y115873D01*
G01X155320Y131220D02*
X150112Y129063D01*
G01X154668Y132196D02*
X115260Y115873D01*
G01X147663Y128049D02*
X146416Y127532D01*
G01X154668Y132196D02*
X115260Y115873D01*
G01X143968Y126518D02*
X142720Y126002D01*
G01X154668Y132196D02*
X115260Y115873D01*
G01X140272Y124988D02*
X139025Y124471D01*
G01X154668Y132196D02*
X115260Y115873D01*
G01X136577Y123457D02*
X128288Y120024D01*
G01X154668Y132196D02*
X115260Y115873D01*
G01X125840Y119010D02*
X124593Y118493D01*
G01X154668Y132196D02*
X115260Y115873D01*
G01X122144Y117479D02*
X115489Y114723D01*
G01X222905Y183089D02*
X161304Y142004D01*
G01X222075Y183919D02*
X160571Y142898D01*
G01X161304Y142004D02*
X152798Y133498D01*
G01X160571Y142898D02*
X152146Y134474D01*
G01X152798Y133498D02*
X126298Y122527D01*
G01X152146Y134474D02*
X150851Y133938D01*
G01X152798Y133498D02*
X126298Y122527D01*
G01X148402Y132924D02*
X147155Y132408D01*
G01X152798Y133498D02*
X126298Y122527D01*
G01X144706Y131394D02*
X143459Y130877D01*
G01X152798Y133498D02*
X126298Y122527D01*
G01X141011Y129864D02*
X139763Y129347D01*
G01X152798Y133498D02*
X126298Y122527D01*
G01X137315Y128333D02*
X125962Y123633D01*
G01X126298Y122527D02*
X110049Y119277D01*
G01X125962Y123633D02*
X124638Y123368D01*
G01X126298Y122527D02*
X110049Y119277D01*
G01X122040Y122848D02*
X120716Y122584D01*
G01X126298Y122527D02*
X110049Y119277D01*
G01X118117Y122064D02*
X109600Y120360D01*
G01X219905Y185875D02*
X155727Y143055D01*
G01X220735Y185045D02*
X156460Y142161D01*
G01X155727Y143055D02*
X153522Y140851D01*
G01X156460Y142161D02*
X154174Y139875D01*
G01X153522Y140851D02*
X150566Y139626D01*
G01X148118Y138612D02*
X146871Y138095D01*
G01X144423Y137081D02*
X143176Y136564D01*
G01X140727Y135550D02*
X121660Y127650D01*
G01X154174Y139875D02*
X121889Y126500D01*
G01X121660Y127650D02*
X118430D01*
G01X121889Y126500D02*
X118659D01*
G01X118430Y127650D02*
X112277Y125100D01*
G01X118659Y126500D02*
X112506Y123950D01*
G01X119202Y136226D02*
X129097Y134214D01*
G01X119087Y137424D02*
X128982Y135412D01*
G01X129097Y134214D02*
X155923Y145328D01*
G01X128982Y135412D02*
X140596Y140224D01*
G01X129097Y134214D02*
X155923Y145328D01*
G01X143045Y141238D02*
X144292Y141755D01*
G01X129097Y134214D02*
X155923Y145328D01*
G01X146740Y142769D02*
X147987Y143286D01*
G01X129097Y134214D02*
X155923Y145328D01*
G01X150435Y144300D02*
X151683Y144817D01*
G01X129097Y134214D02*
X155923Y145328D01*
G01X154131Y145831D02*
X155378Y146348D01*
G01X155923Y145328D02*
X219411Y187678D01*
G01X155378Y146348D02*
X218581Y188508D01*
G01X116067Y139320D02*
X127675Y142388D01*
G01X116440Y138229D02*
X128007Y141286D01*
G01X127675Y142388D02*
X128954Y142821D01*
G01X128007Y141286D02*
X129322Y141731D01*
G01X131463Y143672D02*
X132742Y144105D01*
G01X135252Y144956D02*
X147577Y149133D01*
G01X150086Y149983D02*
X151365Y150416D01*
G01X153875Y151267D02*
X155153Y151700D01*
G01X157663Y152551D02*
X158942Y152984D01*
G01X161451Y153835D02*
X162730Y154268D01*
G01X129322Y141732D02*
X163242Y153227D01*
G01X162730Y154268D02*
X215522Y189489D01*
G01X163242Y153227D02*
X216352Y188659D01*
G01X127467Y104729D02*
X174037Y135808D01*
G01X174867Y134978D02*
X127916Y103646D01*
G01X111432Y101520D02*
X112756Y101785D01*
G01X115354Y102305D02*
X116678Y102570D01*
G01X119277Y103090D02*
X120600Y103355D01*
G01X123199Y103875D02*
X127467Y104729D01*
G01X151795Y124970D02*
X155495Y128004D01*
G01D02*
X156410Y127913D01*
G01X157544Y129684D02*
X158588Y130540D01*
G01D02*
X159503Y130450D01*
G01X160637Y132220D02*
X161681Y133076D01*
G01D02*
X162596Y132986D01*
G01X163731Y134757D02*
X175710Y144579D01*
G01X175024Y145505D02*
X151197Y125968D01*
G01X110405Y107825D02*
X126615Y114540D01*
G01X129063Y115554D02*
X130310Y116070D01*
G01X132758Y117085D02*
X134006Y117601D01*
G01X136454Y118615D02*
X151795Y124970D01*
G01X151197Y125968D02*
X110176Y108975D01*
G01X224046Y180081D02*
X164428Y140328D01*
G01X223216Y180911D02*
X163695Y141222D01*
G01X164428Y140328D02*
X155320Y131220D01*
G01X163695Y141222D02*
X154668Y132196D01*
G01X155320Y131220D02*
X150112Y129063D01*
G01X147663Y128049D02*
X146416Y127532D01*
G01X143968Y126518D02*
X142720Y126002D01*
G01X140272Y124988D02*
X139025Y124471D01*
G01X136577Y123457D02*
X128288Y120024D01*
G01X125840Y119010D02*
X124593Y118493D01*
G01X122144Y117479D02*
X115489Y114723D01*
G01X154668Y132196D02*
X115260Y115873D01*
G01X222075Y183919D02*
X160571Y142898D01*
G01X222905Y183089D02*
X161304Y142004D01*
G01X160571Y142898D02*
X152146Y134474D01*
G01X161304Y142004D02*
X152798Y133498D01*
G01X152146Y134474D02*
X150851Y133938D01*
G01X148402Y132924D02*
X147155Y132408D01*
G01X144706Y131394D02*
X143459Y130877D01*
G01X141011Y129864D02*
X139763Y129347D01*
G01X137315Y128333D02*
X125962Y123633D01*
G01X152798Y133498D02*
X126298Y122527D01*
G01X125962Y123633D02*
X124638Y123368D01*
G01X122040Y122848D02*
X120716Y122584D01*
G01X118117Y122064D02*
X109600Y120360D01*
G01X126298Y122527D02*
X110049Y119277D01*
G01X220735Y185045D02*
X156460Y142161D01*
G01X219905Y185875D02*
X155727Y143055D01*
G01X156460Y142161D02*
X154174Y139875D01*
G01X155727Y143055D02*
X153522Y140851D01*
G01X154174Y139875D02*
X121889Y126500D01*
G01X153522Y140851D02*
X150566Y139626D01*
G01X154174Y139875D02*
X121889Y126500D01*
G01X148118Y138612D02*
X146871Y138095D01*
G01X154174Y139875D02*
X121889Y126500D01*
G01X144423Y137081D02*
X143176Y136564D01*
G01X154174Y139875D02*
X121889Y126500D01*
G01X140727Y135550D02*
X121660Y127650D01*
G01X121889Y126500D02*
X118659D01*
G01X121660Y127650D02*
X118430D01*
G01X118659Y126500D02*
X112506Y123950D01*
G01X118430Y127650D02*
X112277Y125100D01*
G01X119087Y137424D02*
X128982Y135412D01*
G01X119202Y136226D02*
X129097Y134214D01*
G01X128982Y135412D02*
X140596Y140224D01*
G01X143045Y141238D02*
X144292Y141755D01*
G01X146740Y142769D02*
X147987Y143286D01*
G01X150435Y144300D02*
X151683Y144817D01*
G01X154131Y145831D02*
X155378Y146348D01*
G01X129097Y134214D02*
X155923Y145328D01*
G01X155378Y146348D02*
X218581Y188508D01*
G01X155923Y145328D02*
X219411Y187678D01*
G01X116440Y138229D02*
X128007Y141286D01*
G01X116067Y139320D02*
X127675Y142388D01*
G01X128007Y141286D02*
X129322Y141731D01*
G01X127675Y142388D02*
X128954Y142821D01*
G01X129322Y141732D02*
X163242Y153227D01*
G01X131463Y143672D02*
X132742Y144105D01*
G01X129322Y141732D02*
X163242Y153227D01*
G01X135252Y144956D02*
X147577Y149133D01*
G01X129322Y141732D02*
X163242Y153227D01*
G01X150086Y149983D02*
X151365Y150416D01*
G01X129322Y141732D02*
X163242Y153227D01*
G01X153875Y151267D02*
X155153Y151700D01*
G01X129322Y141732D02*
X163242Y153227D01*
G01X157663Y152551D02*
X158942Y152984D01*
G01X129322Y141732D02*
X163242Y153227D01*
G01X161451Y153835D02*
X162730Y154268D01*
G01X163242Y153227D02*
X216352Y188659D01*
G01X162730Y154268D02*
X215522Y189489D01*
G01X160404Y168322D02*
X204304Y197585D01*
G01X203474Y198415D02*
X159908Y169374D01*
G01X141853Y162713D02*
X160404Y168322D01*
G01X159908Y169374D02*
X141682Y163863D01*
G01X133348Y162713D02*
X141853D01*
G01X141682Y163863D02*
X133619D01*
G01X123488Y167623D02*
X133348Y162713D01*
G01X133619Y163863D02*
X123864Y168721D01*
G01X161244Y167164D02*
X205969Y196980D01*
G01X206799Y196150D02*
X161740Y166112D01*
G01X134571Y159100D02*
X161244Y167164D01*
G01X161740Y166112D02*
X134742Y157950D01*
G01X122389Y159100D02*
X134571D01*
G01X134742Y157950D02*
X122112D01*
G01X117535Y161580D02*
X122389Y159100D01*
G01X122112Y157950D02*
X116853Y160636D01*
G01X112868Y166187D02*
X117535Y161580D01*
G01X116853Y160636D02*
X112207Y165222D01*
G01X163765Y162317D02*
X210768Y193650D01*
G01X211598Y192820D02*
X164265Y161267D01*
G01X133619Y163863D02*
X123864Y168721D01*
G01X123488Y167623D02*
X133348Y162713D01*
G01X141682Y163863D02*
X133619D01*
G01X133348Y162713D02*
X141853D01*
G01X159908Y169374D02*
X141682Y163863D01*
G01X141853Y162713D02*
X160404Y168322D01*
G01X203474Y198415D02*
X159908Y169374D01*
G01X160404Y168322D02*
X204304Y197585D01*
G01X116853Y160636D02*
X112207Y165222D01*
G01X112868Y166187D02*
X117535Y161580D01*
G01X122112Y157950D02*
X116853Y160636D01*
G01X117535Y161580D02*
X122389Y159100D01*
G01X134742Y157950D02*
X122112D01*
G01X122389Y159100D02*
X134571D01*
G01X161740Y166112D02*
X134742Y157950D01*
G01X134571Y159100D02*
X161244Y167164D01*
G01X206799Y196150D02*
X161740Y166112D01*
G01X161244Y167164D02*
X205969Y196980D01*
G01X211598Y192820D02*
X164265Y161267D01*
G01X163765Y162317D02*
X210768Y193650D01*
G01X108866Y180477D02*
X110067Y183423D01*
G01X108000Y181401D02*
X109090Y184076D01*
G01X110067Y183423D02*
X111755Y185091D01*
G01X109090Y184076D02*
X111191Y186152D01*
G01X111755Y185091D02*
X114661Y185671D01*
G01X111191Y186152D02*
X114661Y186844D01*
G01Y185671D02*
X117267Y185151D01*
G01X114661Y186844D02*
X117431Y186291D01*
G01X114661Y185671D02*
X117267Y185151D01*
G01X117431Y186291D02*
X117846Y186254D01*
G01X117275Y185148D02*
X126035Y174876D01*
G01X117846Y186254D02*
X126749Y175812D01*
G01X126035Y174876D02*
X135491Y170435D01*
G01X126749Y175812D02*
X135748Y171585D01*
G01X135491Y170435D02*
X141046D01*
G01X135748Y171585D02*
X140880D01*
G01X141046Y170435D02*
X155404Y174653D01*
G01D02*
X155416Y174657D01*
G01X155421Y174658D02*
X155589Y174707D01*
G01X140880Y171585D02*
X155079Y175758D01*
G01X141046Y170435D02*
X155404Y174653D01*
G01X155079Y175758D02*
X155091Y175761D01*
G01X141046Y170435D02*
X155404Y174653D01*
G01X155421Y174658D02*
X155589Y174707D01*
G01X155091Y175761D02*
X155098Y175763D01*
G01X155590Y174708D02*
X197883Y202903D01*
G01X155098Y175763D02*
X197053Y203733D01*
G01X199796Y200904D02*
X157397Y172640D01*
G01X198966Y201734D02*
X156900Y173692D01*
G01X157397Y172640D02*
X141286Y167767D01*
G01X156900Y173692D02*
X141115Y168917D01*
G01X141286Y167767D02*
X135285D01*
G01X141115Y168917D02*
X135542D01*
G01X135285Y167767D02*
X125638Y172295D01*
G01X135542Y168917D02*
X126001Y173396D01*
G01X201392Y200313D02*
X158073Y171433D01*
G01X202222Y199484D02*
X158570Y170381D01*
G01X158073Y171433D02*
X141311Y166363D01*
G01X158570Y170381D02*
X141482Y165213D01*
G01X141311Y166363D02*
X134278D01*
G01X141482Y165213D02*
X134001D01*
G01X134278Y166363D02*
X125178Y171009D01*
G01X134001Y165213D02*
X124797Y169912D01*
G01X108000Y181401D02*
X109090Y184076D01*
G01X108866Y180477D02*
X110067Y183423D01*
G01X109090Y184076D02*
X111191Y186152D01*
G01X110067Y183423D02*
X111755Y185091D01*
G01X111191Y186152D02*
X114661Y186844D01*
G01X111755Y185091D02*
X114661Y185671D01*
G01Y186844D02*
X117431Y186291D01*
G01D02*
X117846Y186254D01*
G01X114661Y185671D02*
X117267Y185151D01*
G01X117846Y186254D02*
X126749Y175812D01*
G01X117275Y185148D02*
X126035Y174876D01*
G01X126749Y175812D02*
X135748Y171585D01*
G01X126035Y174876D02*
X135491Y170435D01*
G01X135748Y171585D02*
X140880D01*
G01X135491Y170435D02*
X141046D01*
G01X140880Y171585D02*
X155079Y175758D01*
G01D02*
X155091Y175761D01*
G01D02*
X155098Y175763D01*
G01X141046Y170435D02*
X155404Y174653D01*
G01X140880Y171585D02*
X155079Y175758D01*
G01X155404Y174653D02*
X155416Y174657D01*
G01X140880Y171585D02*
X155079Y175758D01*
G01X155091Y175761D02*
X155098Y175763D01*
G01X155421Y174658D02*
X155589Y174707D01*
G01X155098Y175763D02*
X197053Y203733D01*
G01X155590Y174708D02*
X197883Y202903D01*
G01X198966Y201734D02*
X156900Y173692D01*
G01X199796Y200904D02*
X157397Y172640D01*
G01X156900Y173692D02*
X141115Y168917D01*
G01X157397Y172640D02*
X141286Y167767D01*
G01X141115Y168917D02*
X135542D01*
G01X141286Y167767D02*
X135285D01*
G01X135542Y168917D02*
X126001Y173396D01*
G01X135285Y167767D02*
X125638Y172295D01*
G01X202222Y199484D02*
X158570Y170381D01*
G01X201392Y200313D02*
X158073Y171433D01*
G01X158570Y170381D02*
X141482Y165213D01*
G01X158073Y171433D02*
X141311Y166363D01*
G01X141482Y165213D02*
X134001D01*
G01X141311Y166363D02*
X134278D01*
G01X134001Y165213D02*
X124797Y169912D01*
G01X134278Y166363D02*
X125178Y171009D01*
G01X112215Y159890D02*
X115890Y158593D01*
G01D02*
X119866Y156600D01*
G01D02*
X134945D01*
G01D02*
X163035Y165092D01*
G01D02*
X208739Y195561D01*
G01X163531Y164040D02*
X209569Y194731D01*
G01X165891Y160291D02*
X213243Y191863D01*
G01X214073Y191033D02*
X166403Y159250D01*
G01X157069Y157302D02*
X165891Y160291D01*
G01X112215Y159890D02*
X115890Y158593D01*
G01D02*
X119866Y156600D01*
G01D02*
X134945D01*
G01D02*
X163035Y165092D01*
G01X163531Y164040D02*
X209569Y194731D01*
G01X163035Y165092D02*
X208739Y195561D01*
G01X157069Y157302D02*
X165891Y160291D01*
G01X214073Y191033D02*
X166403Y159250D01*
G01X165891Y160291D02*
X213243Y191863D01*
G01X116032Y599203D02*
X624844D01*
G01X625321Y600353D02*
X115555D01*
G01X625321D02*
X115555D01*
G01X116032Y599203D02*
X624844D01*
G01X228723Y172411D02*
X183283Y142725D01*
G01X227896Y173246D02*
X182456Y143560D01*
G01X183283Y142725D02*
X176603Y132706D01*
G01X182456Y143560D02*
X175773Y133536D01*
G01X227896Y173246D02*
X182456Y143560D01*
G01X228723Y172411D02*
X183283Y142725D01*
G01X182456Y143560D02*
X175773Y133536D01*
G01X183283Y142725D02*
X176603Y132706D01*
G01X181116Y144351D02*
X174867Y134978D01*
G01X174037Y135808D02*
X180286Y145181D01*
G01X227501Y175277D02*
X181116Y144351D01*
G01X180286Y145181D02*
X226671Y176107D01*
G01X200197Y162292D02*
X175024Y145505D01*
G01X175710Y144579D02*
X226201Y178252D01*
G01X180286Y145181D02*
X226671Y176107D01*
G01X227501Y175277D02*
X181116Y144351D01*
G01X174037Y135808D02*
X180286Y145181D01*
G01X181116Y144351D02*
X174867Y134978D01*
G01X175710Y144579D02*
X226201Y178252D01*
G01X175710Y144579D02*
X226201Y178252D01*
G01X200197Y162292D02*
X175024Y145505D01*
G01X204304Y197585D02*
X225844Y229894D01*
G01X224760Y230343D02*
X203474Y198415D01*
G01X205969Y196980D02*
X228196Y230320D01*
G01X229279Y229871D02*
X206799Y196150D01*
G01X210768Y193650D02*
X233638Y227957D01*
G01X234721Y227508D02*
X211598Y192820D01*
G01X224760Y230343D02*
X203474Y198415D01*
G01X204304Y197585D02*
X225844Y229894D01*
G01X229279Y229871D02*
X206799Y196150D01*
G01X205969Y196980D02*
X228196Y230320D01*
G01X234721Y227508D02*
X211598Y192820D01*
G01X210768Y193650D02*
X233638Y227957D01*
G01X197883Y202903D02*
X215664Y229571D01*
G01X197053Y203733D02*
X214442Y229813D01*
G01X218647Y229181D02*
X199796Y200904D01*
G01X217425Y229423D02*
X198966Y201734D01*
G01X220490Y228958D02*
X201392Y200313D01*
G01X221712Y228716D02*
X211967Y214100D01*
G01X220490Y228958D02*
X201392Y200313D01*
G01X211966Y214099D02*
X202222Y199484D01*
G01X197053Y203733D02*
X214442Y229813D01*
G01X197883Y202903D02*
X215664Y229571D01*
G01X217425Y229423D02*
X198966Y201734D01*
G01X218647Y229181D02*
X199796Y200904D01*
G01X221712Y228716D02*
X211967Y214100D01*
G01X211966Y214099D02*
X202222Y199484D01*
G01X220490Y228958D02*
X201392Y200313D01*
G01X258022Y216359D02*
X228723Y172411D01*
G01X256939Y216808D02*
X227896Y173246D01*
G01X256939Y216808D02*
X227896Y173246D01*
G01X258022Y216359D02*
X228723Y172411D01*
G01X208739Y195561D02*
X231180Y229220D01*
G01X209569Y194731D02*
X232263Y228771D01*
G01X213243Y191863D02*
X236257Y226388D01*
G01X237339Y225935D02*
X214073Y191033D01*
G01X209569Y194731D02*
X232263Y228771D01*
G01X208739Y195561D02*
X231180Y229220D01*
G01X237339Y225935D02*
X214073Y191033D01*
G01X213243Y191863D02*
X236257Y226388D01*
G01X255249Y216896D02*
X227501Y175277D01*
G01X226671Y176107D02*
X254166Y217345D01*
G01X225371Y179082D02*
X200197Y162293D01*
G01X251776Y218685D02*
X225371Y179082D01*
G01X226201Y178252D02*
X252859Y218236D01*
G01X249250Y219960D02*
X223216Y180911D01*
G01X250333Y219511D02*
X224046Y180081D01*
G01X247681Y220249D02*
X222905Y183089D01*
G01X246598Y220698D02*
X222075Y183919D01*
G01X244257Y222397D02*
X219905Y185875D01*
G01X245340Y221948D02*
X220735Y185045D01*
G01X219411Y187678D02*
X242889Y222890D01*
G01X218581Y188508D02*
X241806Y223339D01*
G01X215522Y189489D02*
X239226Y225039D01*
G01X216352Y188659D02*
X240309Y224590D01*
G01X226671Y176107D02*
X254166Y217345D01*
G01X255249Y216896D02*
X227501Y175277D01*
G01X226201Y178252D02*
X252859Y218236D01*
G01X251776Y218685D02*
X225371Y179082D01*
G01D02*
X200197Y162293D01*
G01X250333Y219511D02*
X224046Y180081D01*
G01X249250Y219960D02*
X223216Y180911D01*
G01X246598Y220698D02*
X222075Y183919D01*
G01X247681Y220249D02*
X222905Y183089D01*
G01X245340Y221948D02*
X220735Y185045D01*
G01X244257Y222397D02*
X219905Y185875D01*
G01X218581Y188508D02*
X241806Y223339D01*
G01X219411Y187678D02*
X242889Y222890D01*
G01X216352Y188659D02*
X240309Y224590D01*
G01X215522Y189489D02*
X239226Y225039D01*
G01X226795Y234662D02*
X212941Y303934D01*
G01X211768D02*
X225622Y234662D01*
G01X225844Y229894D02*
X226795Y234662D01*
G01X225622D02*
X224760Y230343D01*
G01X224380Y276498D02*
X235215Y296760D01*
G01X236310Y296367D02*
X225530Y276206D01*
G01X224380Y264799D02*
Y276498D01*
G01X225530Y276206D02*
Y265028D01*
G01X226500Y259680D02*
X224380Y264799D01*
G01X225530Y265028D02*
X227650Y259909D01*
G01X226500Y254542D02*
Y259680D01*
G01X227650Y259909D02*
Y254428D01*
G01X225886Y251471D02*
X226500Y254542D01*
G01X227650Y254428D02*
X227059Y251471D01*
G01X229157Y235121D02*
X225886Y251471D01*
G01X227059D02*
X230330Y235121D01*
G01X228196Y230320D02*
X229156Y235121D01*
G01X230330D02*
X229280Y229871D01*
G01X230480Y277056D02*
X239896Y294650D01*
G01X230480Y269110D02*
Y277056D01*
G01X233914Y265676D02*
X230480Y269110D01*
G01X225622Y234662D02*
X224760Y230343D01*
G01X225844Y229894D02*
X226795Y234662D01*
G01X211768Y303934D02*
X225622Y234662D01*
G01X226795D02*
X212941Y303934D01*
G01X230330Y235121D02*
X229280Y229871D01*
G01X228196Y230320D02*
X229156Y235121D01*
G01X227059Y251471D02*
X230330Y235121D01*
G01X229157D02*
X225886Y251471D01*
G01X227650Y254428D02*
X227059Y251471D01*
G01X225886D02*
X226500Y254542D01*
G01X227650Y259909D02*
Y254428D01*
G01X226500Y254542D02*
Y259680D01*
G01X225530Y265028D02*
X227650Y259909D01*
G01X226500Y259680D02*
X224380Y264799D01*
G01X225530Y276206D02*
Y265028D01*
G01X224380Y264799D02*
Y276498D01*
G01X236310Y296367D02*
X225530Y276206D01*
G01X224380Y276498D02*
X235215Y296760D01*
G01X233914Y265676D02*
X230480Y269110D01*
G01D02*
Y277056D01*
G01D02*
X239896Y294650D01*
G01X215664Y229571D02*
X209910Y258341D01*
G01X214442Y229813D02*
X208760Y258227D01*
G01X209910Y258341D02*
Y277819D01*
G01X208760Y258227D02*
Y277705D01*
G01X209910Y277819D02*
X203115Y311789D01*
G01X208760Y277705D02*
X201942Y311788D01*
G01X206032Y311825D02*
X212860Y277683D01*
G01X204858Y311827D02*
X211710Y277569D01*
G01X212860Y277683D02*
Y258118D01*
G01X211710Y277569D02*
Y258004D01*
G01X212860Y258118D02*
X218647Y229181D01*
G01X211710Y258004D02*
X217425Y229423D01*
G01X208807Y305497D02*
X214244Y278172D01*
G01X209980Y305496D02*
X215394Y278286D01*
G01X214244Y278172D02*
Y260223D01*
G01X215394Y278286D02*
Y260337D01*
G01X214244Y260223D02*
X220490Y228958D01*
G01X215394Y260337D02*
X221712Y228716D01*
G01X214442Y229813D02*
X208760Y258227D01*
G01X215664Y229571D02*
X209910Y258341D01*
G01X208760Y258227D02*
Y277705D01*
G01X209910Y258341D02*
Y277819D01*
G01X208760Y277705D02*
X201942Y311788D01*
G01X209910Y277819D02*
X203115Y311789D01*
G01X204858Y311827D02*
X211710Y277569D01*
G01X206032Y311825D02*
X212860Y277683D01*
G01X211710Y277569D02*
Y258004D01*
G01X212860Y277683D02*
Y258118D01*
G01X211710Y258004D02*
X217425Y229423D01*
G01X212860Y258118D02*
X218647Y229181D01*
G01X209980Y305496D02*
X215394Y278286D01*
G01X208807Y305497D02*
X214244Y278172D01*
G01X215394Y278286D02*
Y260337D01*
G01X214244Y278172D02*
Y260223D01*
G01X215394Y260337D02*
X221712Y228716D01*
G01X214244Y260223D02*
X220490Y228958D01*
G01X231180Y229220D02*
X232208Y234360D01*
G01D02*
X228676Y252021D01*
G01X233381Y234360D02*
X229849Y252021D01*
G01X228676D02*
X229817Y257730D01*
G01X229849Y252021D02*
X231002Y257786D01*
G01X229817Y257730D02*
X227430Y265623D01*
G01X231002Y257786D02*
X228580Y265794D01*
G01X227430Y265623D02*
Y276892D01*
G01X228580Y265794D02*
Y276603D01*
G01X227430Y276892D02*
X237590Y295878D01*
G01X228580Y276603D02*
X238685Y295485D01*
G01X231180Y229220D02*
X232208Y234360D01*
G01X233381D02*
X229849Y252021D01*
G01X232208Y234360D02*
X228676Y252021D01*
G01X229849D02*
X231002Y257786D01*
G01X228676Y252021D02*
X229817Y257730D01*
G01X231002Y257786D02*
X228580Y265794D01*
G01X229817Y257730D02*
X227430Y265623D01*
G01X228580Y265794D02*
Y276603D01*
G01X227430Y265623D02*
Y276892D01*
G01X228580Y276603D02*
X238685Y295485D01*
G01X227430Y276892D02*
X237590Y295878D01*
G01X222035Y334174D02*
X225063Y349319D01*
G01X223890D02*
X220929Y334510D01*
G01X216146Y319960D02*
X222035Y334174D01*
G01X220929Y334510D02*
X215040Y320296D01*
G01X212941Y303934D02*
X216146Y319960D01*
G01X215040Y320296D02*
X211768Y303934D01*
G01X228035Y330175D02*
Y341824D01*
G01X229185Y341938D02*
Y329698D01*
G01X225325Y327465D02*
X228035Y330175D01*
G01X229185Y329698D02*
X226475Y326988D01*
G01X225325Y322871D02*
Y327465D01*
G01X226475Y326988D02*
Y323160D01*
G01X227725Y318382D02*
X225325Y322871D01*
G01X226475Y323160D02*
X228713Y318974D01*
G01X235572Y306628D02*
X227725Y318382D01*
G01X228713Y318974D02*
X236655Y307077D01*
G01X215040Y320296D02*
X211768Y303934D01*
G01X212941D02*
X216146Y319960D01*
G01X220929Y334510D02*
X215040Y320296D01*
G01X216146Y319960D02*
X222035Y334174D01*
G01X223890Y349319D02*
X220929Y334510D01*
G01X222035Y334174D02*
X225063Y349319D01*
G01X228713Y318974D02*
X236655Y307077D01*
G01X235572Y306628D02*
X227725Y318382D01*
G01X226475Y323160D02*
X228713Y318974D01*
G01X227725Y318382D02*
X225325Y322871D01*
G01X226475Y326988D02*
Y323160D01*
G01X225325Y322871D02*
Y327465D01*
G01X229185Y329698D02*
X226475Y326988D01*
G01X225325Y327465D02*
X228035Y330175D01*
G01X229185Y341938D02*
Y329698D01*
G01X228035Y330175D02*
Y341824D01*
G01X203115Y311789D02*
X221685Y405043D01*
G01X201942Y311788D02*
X220601Y405492D01*
G01X224331Y403363D02*
X209136Y327348D01*
G01X223247Y403813D02*
X207914Y327106D01*
G01X209136Y327348D02*
X209488Y326821D01*
G01X207914Y327106D02*
X208795Y325786D01*
G01X209488Y326821D02*
X210491Y326620D01*
G01X208795Y325786D02*
X209798Y325585D01*
G01X210491Y326620D02*
X211373Y325298D01*
G01X209798Y325585D02*
X210151Y325056D01*
G01X211373Y325298D02*
X210978Y323332D01*
G01X210151Y325056D02*
X209944Y324025D01*
G01X210978Y323332D02*
X209657Y322450D01*
G01X209944Y324025D02*
X209415Y323672D01*
G01X209657Y322450D02*
X208654Y322651D01*
G01X209415Y323672D02*
X208412Y323873D01*
G01X208654Y322651D02*
X208126Y322298D01*
G01X208412Y323873D02*
X207091Y322991D01*
G01X208126Y322298D02*
X207919Y321264D01*
G01X207091Y322991D02*
X206697Y321022D01*
G01X207919Y321264D02*
X208271Y320737D01*
G01X206697Y321022D02*
X207578Y319702D01*
G01X208271Y320737D02*
X209274Y320536D01*
G01X207578Y319702D02*
X208581Y319501D01*
G01X209274Y320536D02*
X210156Y319214D01*
G01X208581Y319501D02*
X208934Y318972D01*
G01X210156Y319214D02*
X209761Y317248D01*
G01X208934Y318972D02*
X208727Y317941D01*
G01X209761Y317248D02*
X208440Y316366D01*
G01X208727Y317941D02*
X208198Y317588D01*
G01X208440Y316366D02*
X207437Y316567D01*
G01X208198Y317588D02*
X207195Y317789D01*
G01X207437Y316567D02*
X206909Y316214D01*
G01X207195Y317789D02*
X205874Y316907D01*
G01X206909Y316214D02*
X206031Y311827D01*
G01X205874Y316907D02*
X204858Y311827D01*
G01X221054Y352479D02*
X218747Y341140D01*
G01X217664Y341589D02*
X215319Y338043D01*
G01X218747Y341140D02*
X216402Y337596D01*
G01X215319Y338043D02*
X208807Y305497D01*
G01X216403Y337596D02*
X209980Y305496D01*
G01X201942Y311788D02*
X220601Y405492D01*
G01X203115Y311789D02*
X221685Y405043D01*
G01X223247Y403813D02*
X207914Y327106D01*
G01X224331Y403363D02*
X209136Y327348D01*
G01X207914Y327106D02*
X208795Y325786D01*
G01X209136Y327348D02*
X209488Y326821D01*
G01X208795Y325786D02*
X209798Y325585D01*
G01X209488Y326821D02*
X210491Y326620D01*
G01X209798Y325585D02*
X210151Y325056D01*
G01X210491Y326620D02*
X211373Y325298D01*
G01X210151Y325056D02*
X209944Y324025D01*
G01X211373Y325298D02*
X210978Y323332D01*
G01X209944Y324025D02*
X209415Y323672D01*
G01X210978Y323332D02*
X209657Y322450D01*
G01X209415Y323672D02*
X208412Y323873D01*
G01X209657Y322450D02*
X208654Y322651D01*
G01X208412Y323873D02*
X207091Y322991D01*
G01X208654Y322651D02*
X208126Y322298D01*
G01X207091Y322991D02*
X206697Y321022D01*
G01X208126Y322298D02*
X207919Y321264D01*
G01X206697Y321022D02*
X207578Y319702D01*
G01X207919Y321264D02*
X208271Y320737D01*
G01X207578Y319702D02*
X208581Y319501D01*
G01X208271Y320737D02*
X209274Y320536D01*
G01X208581Y319501D02*
X208934Y318972D01*
G01X209274Y320536D02*
X210156Y319214D01*
G01X208934Y318972D02*
X208727Y317941D01*
G01X210156Y319214D02*
X209761Y317248D01*
G01X208727Y317941D02*
X208198Y317588D01*
G01X209761Y317248D02*
X208440Y316366D01*
G01X208198Y317588D02*
X207195Y317789D01*
G01X208440Y316366D02*
X207437Y316567D01*
G01X207195Y317789D02*
X205874Y316907D01*
G01X207437Y316567D02*
X206909Y316214D01*
G01X205874Y316907D02*
X204858Y311827D01*
G01X206909Y316214D02*
X206031Y311827D01*
G01X221054Y352479D02*
X218747Y341140D01*
G01D02*
X216402Y337596D01*
G01X217664Y341589D02*
X215319Y338043D01*
G01X216403Y337596D02*
X209980Y305496D01*
G01X215319Y338043D02*
X208807Y305497D01*
G01X237928Y307604D02*
X230225Y319141D01*
G01D02*
Y322465D01*
G01D02*
X231725Y323965D01*
G01Y327876D02*
X231130Y328471D01*
G01D02*
Y340616D01*
G01D02*
X231066Y340871D01*
G01D02*
X228820Y352100D01*
G01X237928Y307604D02*
X230225Y319141D01*
G01D02*
Y322465D01*
G01D02*
X231725Y323965D01*
G01Y327876D02*
X231130Y328471D01*
G01D02*
Y340616D01*
G01D02*
X231066Y340871D01*
G01D02*
X228820Y352100D01*
G01X223610Y356584D02*
X233772Y407395D01*
G01X232689Y407844D02*
X222437Y356584D01*
G01X225063Y349319D02*
X223610Y356584D01*
G01X222437D02*
X223890Y349319D01*
G01X226080Y351599D02*
X237512Y408768D01*
G01X238595Y408319D02*
X227253Y351599D01*
G01X228035Y341824D02*
X226080Y351599D01*
G01X227253D02*
X229185Y341938D01*
G01X222437Y356584D02*
X223890Y349319D01*
G01X225063D02*
X223610Y356584D01*
G01X232689Y407844D02*
X222437Y356584D01*
G01X223610D02*
X233772Y407395D01*
G01X227253Y351599D02*
X229185Y341938D01*
G01X228035Y341824D02*
X226080Y351599D01*
G01X238595Y408319D02*
X227253Y351599D01*
G01X226080D02*
X237512Y408768D01*
G01X229273Y407784D02*
X219037Y356625D01*
G01X230356Y407335D02*
X220210Y356626D01*
G01X219036Y356624D02*
X219880Y352479D01*
G01X220210Y356626D02*
X221054Y352479D01*
G01X219880D02*
X217664Y341589D01*
G01X230356Y407335D02*
X220210Y356626D01*
G01X229273Y407784D02*
X219037Y356625D01*
G01X220210Y356626D02*
X221054Y352479D01*
G01X219036Y356624D02*
X219880Y352479D01*
G01D02*
X217664Y341589D01*
G01X232189Y341123D02*
X229994Y352102D01*
G01X228820Y352100D02*
X239980Y407906D01*
G01X229994Y352102D02*
X241063Y407457D01*
G01X232189Y341123D02*
X229994Y352102D01*
G01D02*
X241063Y407457D01*
G01X228820Y352100D02*
X239980Y407906D01*
G01X221685Y405043D02*
X237262Y428407D01*
G01X220601Y405492D02*
X236432Y429237D01*
G01X240266Y427223D02*
X226743Y406973D01*
G01X225271Y404770D02*
X224331Y403363D01*
G01X239436Y428053D02*
X223247Y403813D01*
G01X241829Y426620D02*
X229273Y407784D01*
G01X242659Y425790D02*
X230356Y407335D01*
G01X220601Y405492D02*
X236432Y429237D01*
G01X221685Y405043D02*
X237262Y428407D01*
G01X239436Y428053D02*
X223247Y403813D01*
G01X240266Y427223D02*
X226743Y406973D01*
G01X239436Y428053D02*
X223247Y403813D01*
G01X225271Y404770D02*
X224331Y403363D01*
G01X242659Y425790D02*
X230356Y407335D01*
G01X241829Y426620D02*
X229273Y407784D01*
G01X262035Y236426D02*
X258022Y216359D01*
G01X260862Y236426D02*
X256939Y216808D01*
G01X260862Y236426D02*
X256939Y216808D01*
G01X262035Y236426D02*
X258022Y216359D01*
G01X259037Y235833D02*
X255249Y216896D01*
G01X254166Y217345D02*
X257864Y235833D01*
G01X254166Y217345D02*
X257864Y235833D01*
G01X259037D02*
X255249Y216896D01*
G01X240991Y294257D02*
X231630Y276767D01*
G01D02*
Y269587D01*
G01D02*
X235064Y266153D01*
G01X233914Y264736D02*
Y265676D01*
G01X235064Y266153D02*
Y264617D01*
G01X231505Y252681D02*
X233914Y264736D01*
G01X235064Y264617D02*
X232678Y252681D01*
G01X235043Y234978D02*
X231505Y252681D01*
G01X232678D02*
X236216Y234978D01*
G01X233638Y227957D02*
X235043Y234978D01*
G01X236216D02*
X234721Y227508D01*
G01X236216Y234978D02*
X234721Y227508D01*
G01X233638Y227957D02*
X235043Y234978D01*
G01X232678Y252681D02*
X236216Y234978D01*
G01X235043D02*
X231505Y252681D01*
G01X235064Y264617D02*
X232678Y252681D01*
G01X231505D02*
X233914Y264736D01*
G01X235064Y266153D02*
Y264617D01*
G01X233914Y264736D02*
Y265676D01*
G01X231630Y269587D02*
X235064Y266153D01*
G01X231630Y276767D02*
Y269587D01*
G01X240991Y294257D02*
X231630Y276767D01*
G01X267409Y302755D02*
X258090Y256150D01*
G01X266236Y302755D02*
X256917Y256150D01*
G01X258090D02*
X262035Y236426D01*
G01X256917Y256150D02*
X260862Y236426D01*
G01X266236Y302755D02*
X256917Y256150D01*
G01X267409Y302755D02*
X258090Y256150D01*
G01X256917D02*
X260862Y236426D01*
G01X258090Y256150D02*
X262035Y236426D01*
G01X232263Y228771D02*
X233381Y234360D01*
G01X236730Y265247D02*
Y275806D01*
G01Y278456D02*
Y282914D01*
G01X237880Y282625D02*
Y265133D01*
G01X234380Y253496D02*
X236730Y265247D01*
G01X237880Y265133D02*
X235553Y253496D01*
G01X238031Y235247D02*
X234380Y253496D01*
G01X235553D02*
X239204Y235247D01*
G01X236257Y226388D02*
X238031Y235247D01*
G01X239204D02*
X237340Y225939D01*
G01X232263Y228771D02*
X233381Y234360D01*
G01X239204Y235247D02*
X237340Y225939D01*
G01X236257Y226388D02*
X238031Y235247D01*
G01X235553Y253496D02*
X239204Y235247D01*
G01X238031D02*
X234380Y253496D01*
G01X237880Y265133D02*
X235553Y253496D01*
G01X234380D02*
X236730Y265247D01*
G01X237880Y282625D02*
Y265133D01*
G01X236730Y265247D02*
Y275806D01*
G01X237880Y282625D02*
Y265133D01*
G01X236730Y278456D02*
Y282914D01*
G01X255202Y255006D02*
X259037Y235833D01*
G01X257864D02*
X254029Y255006D01*
G01X264770Y302852D02*
X255202Y255006D01*
G01X254029D02*
X263597Y302852D01*
G01X255260Y236100D02*
X251776Y218685D01*
G01X252859Y218236D02*
X256433Y236100D01*
G01X251474Y255032D02*
X255260Y236100D01*
G01X256433D02*
X252647Y255032D01*
G01X261027Y302802D02*
X251474Y255032D01*
G01X252647D02*
X253500Y259297D01*
G01X261027Y302802D02*
X251474Y255032D01*
G01X253500Y259297D02*
X262200Y302802D01*
G01X258466Y302805D02*
X248842Y254676D01*
G01X259639Y302805D02*
X250015Y254676D01*
G01X248842D02*
X252518Y236290D01*
G01X250015Y254676D02*
X253692Y236290D01*
G01X252519D02*
X249250Y219960D01*
G01X253692Y236290D02*
X250333Y219511D01*
G01X257020Y302901D02*
X247372Y254655D01*
G01X255847Y302901D02*
X246199Y254655D01*
G01X247372D02*
X250969Y236672D01*
G01X246199Y254655D02*
X249795Y236672D01*
G01X250969D02*
X247681Y220249D01*
G01X249796Y236672D02*
X246597Y220698D01*
G01X253257Y302752D02*
X243436Y253638D01*
G01X254430Y302752D02*
X244609Y253638D01*
G01X243436D02*
X246972Y235955D01*
G01X244609Y253638D02*
X248145Y235955D01*
G01X246972D02*
X244256Y222397D01*
G01X248145Y235955D02*
X245340Y221948D01*
G01X242889Y222890D02*
X245385Y235341D01*
G01X241806Y223339D02*
X244212Y235341D01*
G01X245385D02*
X241768Y253430D01*
G01X244212Y235341D02*
X240595Y253430D01*
G01X241768D02*
X251710Y303150D01*
G01X240595Y253430D02*
X250537Y303150D01*
G01X239226Y225039D02*
X241251Y235142D01*
G01X240309Y224590D02*
X242424Y235142D01*
G01X241250D02*
X237602Y253381D01*
G01X242424Y235142D02*
X238775Y253381D01*
G01X237602D02*
X247727Y304000D01*
G01X238775Y253381D02*
X248900Y304000D01*
G01X254029Y255006D02*
X263597Y302852D01*
G01X264770D02*
X255202Y255006D01*
G01X257864Y235833D02*
X254029Y255006D01*
G01X255202D02*
X259037Y235833D01*
G01X252647Y255032D02*
X253500Y259297D01*
G01D02*
X262200Y302802D01*
G01X261027D02*
X251474Y255032D01*
G01X256433Y236100D02*
X252647Y255032D01*
G01X251474D02*
X255260Y236100D01*
G01X252859Y218236D02*
X256433Y236100D01*
G01X255260D02*
X251776Y218685D01*
G01X259639Y302805D02*
X250015Y254676D01*
G01X258466Y302805D02*
X248842Y254676D01*
G01X250015D02*
X253692Y236290D01*
G01X248842Y254676D02*
X252518Y236290D01*
G01X253692D02*
X250333Y219511D01*
G01X252519Y236290D02*
X249250Y219960D01*
G01X255847Y302901D02*
X246199Y254655D01*
G01X257020Y302901D02*
X247372Y254655D01*
G01X246199D02*
X249795Y236672D01*
G01X247372Y254655D02*
X250969Y236672D01*
G01X249796D02*
X246597Y220698D01*
G01X250969Y236672D02*
X247681Y220249D01*
G01X254430Y302752D02*
X244609Y253638D01*
G01X253257Y302752D02*
X243436Y253638D01*
G01X244609D02*
X248145Y235955D01*
G01X243436Y253638D02*
X246972Y235955D01*
G01X248145D02*
X245340Y221948D01*
G01X246972Y235955D02*
X244256Y222397D01*
G01X241806Y223339D02*
X244212Y235341D01*
G01X242889Y222890D02*
X245385Y235341D01*
G01X244212D02*
X240595Y253430D01*
G01X245385Y235341D02*
X241768Y253430D01*
G01X240595D02*
X250537Y303150D01*
G01X241768Y253430D02*
X251710Y303150D01*
G01X240309Y224590D02*
X242424Y235142D01*
G01X239226Y225039D02*
X241251Y235142D01*
G01X242424D02*
X238775Y253381D01*
G01X241250Y235142D02*
X237602Y253381D01*
G01X238775D02*
X248900Y304000D01*
G01X237602Y253381D02*
X247727Y304000D01*
G01X236381Y302580D02*
X235572Y306628D01*
G01X236655Y307077D02*
X237554Y302580D01*
G01X235215Y296760D02*
X236381Y302580D01*
G01X237554D02*
X236310Y296367D01*
G01X241483Y302583D02*
X231695Y351522D01*
G01X232868D02*
X242656Y302583D01*
G01X239896Y294650D02*
X241483Y302583D01*
G01X242656D02*
X240991Y294257D01*
G01X237554Y302580D02*
X236310Y296367D01*
G01X235215Y296760D02*
X236381Y302580D01*
G01X236655Y307077D02*
X237554Y302580D01*
G01X236381D02*
X235572Y306628D01*
G01X242656Y302583D02*
X240991Y294257D01*
G01X239896Y294650D02*
X241483Y302583D01*
G01X232868Y351522D02*
X242656Y302583D01*
G01X241483D02*
X231695Y351522D01*
G01X257771Y350954D02*
X267409Y302755D01*
G01X256598Y350954D02*
X266236Y302755D01*
G01X256598Y350954D02*
X266236Y302755D01*
G01X257771Y350954D02*
X267409Y302755D01*
G01X237590Y295878D02*
X238932Y302581D01*
G01X238685Y295485D02*
X240105Y302581D01*
G01X238932D02*
X237928Y307604D01*
G01X240105Y302581D02*
X239011Y308053D01*
G01D02*
X231375Y319490D01*
G01D02*
Y321988D01*
G01D02*
X232875Y323488D01*
G01X231725Y323965D02*
Y327876D01*
G01X232875Y323488D02*
Y328353D01*
G01D02*
X232280Y328948D01*
G01D02*
Y340758D01*
G01D02*
X232189Y341123D01*
G01X244220Y302703D02*
X234351Y352053D01*
G01X235524D02*
X245393Y302703D01*
G01X242370Y293453D02*
X244220Y302703D01*
G01X245393D02*
X243465Y293060D01*
G01X236730Y282914D02*
X242370Y293453D01*
G01X243465Y293060D02*
X237880Y282625D01*
G01X238685Y295485D02*
X240105Y302581D01*
G01X237590Y295878D02*
X238932Y302581D01*
G01X240105D02*
X239011Y308053D01*
G01X238932Y302581D02*
X237928Y307604D01*
G01X239011Y308053D02*
X231375Y319490D01*
G01D02*
Y321988D01*
G01D02*
X232875Y323488D01*
G01D02*
Y328353D01*
G01X231725Y323965D02*
Y327876D01*
G01X232875Y328353D02*
X232280Y328948D01*
G01D02*
Y340758D01*
G01D02*
X232189Y341123D01*
G01X243465Y293060D02*
X237880Y282625D01*
G01X236730Y282914D02*
X242370Y293453D01*
G01X245393Y302703D02*
X243465Y293060D01*
G01X242370Y293453D02*
X244220Y302703D01*
G01X235524Y352053D02*
X245393Y302703D01*
G01X244220D02*
X234351Y352053D01*
G01X255040Y351503D02*
X264770Y302852D01*
G01X263596D02*
X253867Y351503D01*
G01X251258Y351652D02*
X261027Y302802D01*
G01X262200D02*
X252431Y351652D01*
G01X248608Y352099D02*
X258466Y302805D01*
G01X249781Y352099D02*
X259639Y302805D01*
G01X247191Y352050D02*
X257020Y302901D01*
G01X246018Y352050D02*
X255847Y302901D01*
G01X243328Y352399D02*
X253257Y302752D01*
G01X244501Y352399D02*
X254430Y302752D01*
G01X251710Y303150D02*
X241832Y352547D01*
G01X250537Y303150D02*
X240659Y352547D01*
G01X247727Y304000D02*
X237833Y353473D01*
G01X248900Y304000D02*
X239006Y353473D01*
G01X263596Y302852D02*
X253867Y351503D01*
G01X255040D02*
X264770Y302852D01*
G01X262200Y302802D02*
X252431Y351652D01*
G01X251258D02*
X261027Y302802D01*
G01X249781Y352099D02*
X259639Y302805D01*
G01X248608Y352099D02*
X258466Y302805D01*
G01X246018Y352050D02*
X255847Y302901D01*
G01X247191Y352050D02*
X257020Y302901D01*
G01X244501Y352399D02*
X254430Y302752D01*
G01X243328Y352399D02*
X253257Y302752D01*
G01X250537Y303150D02*
X240659Y352547D01*
G01X251710Y303150D02*
X241832Y352547D01*
G01X248900Y304000D02*
X239006Y353473D01*
G01X247727Y304000D02*
X237833Y353473D01*
G01X231695Y351522D02*
X242838Y407240D01*
G01X243922Y406792D02*
X232868Y351522D01*
G01X243922Y406792D02*
X232868Y351522D01*
G01X231695D02*
X242838Y407240D01*
G01X275901Y403420D02*
X267943Y398118D01*
G01X275452Y404504D02*
X267113Y398947D01*
G01X267943Y398118D02*
X266887Y396531D01*
G01X267113Y398947D02*
X265803Y396980D01*
G01X266887Y396531D02*
X257771Y350954D01*
G01X265803Y396980D02*
X256598Y350954D01*
G01X275452Y404504D02*
X267113Y398947D01*
G01X275901Y403420D02*
X267943Y398118D01*
G01X267113Y398947D02*
X265803Y396980D01*
G01X267943Y398118D02*
X266887Y396531D01*
G01X265803Y396980D02*
X256598Y350954D01*
G01X266887Y396531D02*
X257771Y350954D01*
G01X234351Y352053D02*
X245194Y406265D01*
G01X246277Y405816D02*
X235524Y352053D01*
G01X246277Y405816D02*
X235524Y352053D01*
G01X234351D02*
X245194Y406265D01*
G01X264158Y397084D02*
X255040Y351503D01*
G01X253867D02*
X263074Y397533D01*
G01X266277Y400265D02*
X264158Y397086D01*
G01X263074Y397533D02*
X265447Y401095D01*
G01X275730Y406566D02*
X266277Y400265D01*
G01X265447Y401095D02*
X275281Y407649D01*
G01X260605Y398400D02*
X251258Y351652D01*
G01X252431D02*
X261689Y397951D01*
G01X263950Y403421D02*
X260605Y398400D01*
G01X261689Y397953D02*
X264780Y402591D01*
G01D02*
X274724Y409217D01*
G01X262268Y405631D02*
X258044Y399291D01*
G01X263098Y404801D02*
X259128Y398842D01*
G01X258044Y399291D02*
X248608Y352099D01*
G01X259128Y398842D02*
X249781Y352099D01*
G01X260765Y406446D02*
X256908Y400662D01*
G01X259935Y407276D02*
X255825Y401111D01*
G01X256908Y400662D02*
X247191Y352050D01*
G01X255825Y401111D02*
X246018Y352050D01*
G01X257868Y409131D02*
X253296Y402269D01*
G01X258698Y408301D02*
X254380Y401820D01*
G01X253296Y402269D02*
X243328Y352399D01*
G01X254380Y401820D02*
X244501Y352399D01*
G01X241832Y352547D02*
X252127Y404065D01*
G01X240659Y352547D02*
X251043Y404514D01*
G01X237833Y353473D02*
X248087Y404805D01*
G01X239006Y353473D02*
X249171Y404356D01*
G01X265447Y401095D02*
X275281Y407649D01*
G01X275730Y406566D02*
X266277Y400265D01*
G01X263074Y397533D02*
X265447Y401095D01*
G01X266277Y400265D02*
X264158Y397086D01*
G01X253867Y351503D02*
X263074Y397533D01*
G01X264158Y397084D02*
X255040Y351503D01*
G01X264780Y402591D02*
X274724Y409217D01*
G01X261689Y397953D02*
X264780Y402591D01*
G01X263950Y403421D02*
X260605Y398400D01*
G01X252431Y351652D02*
X261689Y397951D01*
G01X260605Y398400D02*
X251258Y351652D01*
G01X263098Y404801D02*
X259128Y398842D01*
G01X262268Y405631D02*
X258044Y399291D01*
G01X259128Y398842D02*
X249781Y352099D01*
G01X258044Y399291D02*
X248608Y352099D01*
G01X259935Y407276D02*
X255825Y401111D01*
G01X260765Y406446D02*
X256908Y400662D01*
G01X255825Y401111D02*
X246018Y352050D01*
G01X256908Y400662D02*
X247191Y352050D01*
G01X258698Y408301D02*
X254380Y401820D01*
G01X257868Y409131D02*
X253296Y402269D01*
G01X254380Y401820D02*
X244501Y352399D01*
G01X253296Y402269D02*
X243328Y352399D01*
G01X240659Y352547D02*
X251043Y404514D01*
G01X241832Y352547D02*
X252127Y404065D01*
G01X239006Y353473D02*
X249171Y404356D01*
G01X237833Y353473D02*
X248087Y404805D01*
G01X276769Y445430D02*
X327331Y455544D01*
G01Y456717D02*
X276320Y446513D01*
G01X245019Y424262D02*
X269112Y440323D01*
G01X270840Y441476D02*
X272010Y442255D01*
G01X273908Y443522D02*
X276769Y445430D01*
G01X276320Y446513D02*
X244189Y425092D01*
G01X233772Y407395D02*
X245019Y424262D01*
G01X244189Y425092D02*
X232689Y407844D01*
G01X279163Y444503D02*
X326935Y454058D01*
G01Y452885D02*
X279612Y443420D01*
G01X247074Y423110D02*
X279163Y444503D01*
G01X279612Y443420D02*
X247904Y422280D01*
G01X237512Y408768D02*
X247074Y423110D01*
G01X247904Y422280D02*
X238595Y408319D01*
G01X292619Y435296D02*
X327953Y428230D01*
G01Y427057D02*
X292619Y434123D01*
G01X270065Y430784D02*
X292619Y435296D01*
G01Y434123D02*
X270514Y429701D01*
G01X249230Y416897D02*
X270065Y430784D01*
G01X270514Y429701D02*
X250060Y416067D01*
G01X243043Y407615D02*
X249230Y416897D01*
G01X250060Y416067D02*
X244124Y407163D01*
G01X242838Y407240D02*
X243022Y407517D01*
G01X244104Y407066D02*
X243922Y406792D01*
G01X244189Y425092D02*
X232689Y407844D01*
G01X233772Y407395D02*
X245019Y424262D01*
G01X276320Y446513D02*
X244189Y425092D01*
G01X245019Y424262D02*
X269112Y440323D01*
G01X276320Y446513D02*
X244189Y425092D01*
G01X270840Y441476D02*
X272010Y442255D01*
G01X276320Y446513D02*
X244189Y425092D01*
G01X273908Y443522D02*
X276769Y445430D01*
G01X327331Y456717D02*
X276320Y446513D01*
G01X276769Y445430D02*
X327331Y455544D01*
G01X247904Y422280D02*
X238595Y408319D01*
G01X237512Y408768D02*
X247074Y423110D01*
G01X279612Y443420D02*
X247904Y422280D01*
G01X247074Y423110D02*
X279163Y444503D01*
G01X326935Y452885D02*
X279612Y443420D01*
G01X279163Y444503D02*
X326935Y454058D01*
G01X244104Y407066D02*
X243922Y406792D01*
G01X242838Y407240D02*
X243022Y407517D01*
G01X250060Y416067D02*
X244124Y407163D01*
G01X243043Y407615D02*
X249230Y416897D01*
G01X270514Y429701D02*
X250060Y416067D01*
G01X249230Y416897D02*
X270065Y430784D01*
G01X292619Y434123D02*
X270514Y429701D01*
G01X270065Y430784D02*
X292619Y435296D01*
G01X327953Y427057D02*
X292619Y434123D01*
G01Y435296D02*
X327953Y428230D01*
G01X237262Y428407D02*
X274549Y453267D01*
G01X236432Y429237D02*
X274100Y454350D01*
G01X274549Y453267D02*
X326633Y463683D01*
G01X274100Y454350D02*
X326633Y464856D01*
G01X327383Y460954D02*
X275197Y450516D01*
G01X327383Y462127D02*
X274748Y451599D01*
G01X275197Y450516D02*
X240266Y427223D01*
G01X274748Y451599D02*
X239437Y428053D01*
G01X327731Y459476D02*
X275424Y449015D01*
G01X327731Y458303D02*
X275873Y447932D01*
G01X275424Y449015D02*
X241829Y426620D01*
G01X275873Y447932D02*
X242659Y425790D01*
G01X236432Y429237D02*
X274100Y454350D01*
G01X237262Y428407D02*
X274549Y453267D01*
G01X274100Y454350D02*
X326633Y464856D01*
G01X274549Y453267D02*
X326633Y463683D01*
G01X327383Y462127D02*
X274748Y451599D01*
G01X327383Y460954D02*
X275197Y450516D01*
G01X274748Y451599D02*
X239437Y428053D01*
G01X275197Y450516D02*
X240266Y427223D01*
G01X327731Y458303D02*
X275873Y447932D01*
G01X327731Y459476D02*
X275424Y449015D01*
G01X275873Y447932D02*
X242659Y425790D01*
G01X275424Y449015D02*
X241829Y426620D01*
G01X299917Y408223D02*
X275901Y403420D01*
G01X299917Y409396D02*
X275452Y404504D01*
G01X299917Y409396D02*
X275452Y404504D01*
G01X299917Y408223D02*
X275901Y403420D01*
G01X239980Y407906D02*
X248218Y420265D01*
G01X241063Y407457D02*
X249048Y419435D01*
G01X248218Y420265D02*
X281216Y442254D01*
G01X249048Y419435D02*
X281665Y441171D01*
G01X281216Y442254D02*
X327080Y451429D01*
G01X281665Y441171D02*
X327068Y450253D01*
G01X269910Y427292D02*
X294266Y432166D01*
G01Y430993D02*
X270359Y426209D01*
G01X250656Y414460D02*
X269910Y427292D01*
G01X270359Y426209D02*
X251486Y413630D01*
G01X245194Y406265D02*
X250656Y414460D01*
G01X251486Y413630D02*
X246277Y405816D01*
G01X241063Y407457D02*
X249048Y419435D01*
G01X239980Y407906D02*
X248218Y420265D01*
G01X249048Y419435D02*
X281665Y441171D01*
G01X248218Y420265D02*
X281216Y442254D01*
G01X281665Y441171D02*
X327068Y450253D01*
G01X281216Y442254D02*
X327080Y451429D01*
G01X251486Y413630D02*
X246277Y405816D01*
G01X245194Y406265D02*
X250656Y414460D01*
G01X270359Y426209D02*
X251486Y413630D01*
G01X250656Y414460D02*
X269910Y427292D01*
G01X294266Y430993D02*
X270359Y426209D01*
G01X269910Y427292D02*
X294266Y432166D01*
G01X299812Y411382D02*
X275730Y406566D01*
G01X275281Y407649D02*
X299812Y412555D01*
G01X274275Y410301D02*
X263950Y403421D01*
G01X299067Y415258D02*
X274275Y410301D01*
G01X274724Y409217D02*
X299067Y414085D01*
G01X296272Y418375D02*
X275017Y414124D01*
G01X296272Y417202D02*
X275466Y413040D01*
G01X275017Y414124D02*
X262268Y405631D01*
G01X275466Y413040D02*
X263098Y404801D01*
G01X296226Y419764D02*
X274120Y415345D01*
G01X296226Y420937D02*
X273671Y416429D01*
G01X274120Y415345D02*
X260765Y406446D01*
G01X273671Y416429D02*
X259935Y407276D01*
G01X295936Y423546D02*
X272457Y418853D01*
G01X295936Y422373D02*
X272906Y417769D01*
G01X272457Y418853D02*
X257868Y409131D01*
G01X272906Y417769D02*
X258698Y408301D01*
G01X252127Y404067D02*
X255752Y409505D01*
G01X251043Y404514D02*
X254922Y410335D01*
G01X255752Y409505D02*
X271608Y420071D01*
G01X254922Y410335D02*
X271159Y421155D01*
G01X271608Y420071D02*
X295934Y424933D01*
G01X271159Y421155D02*
X295934Y426106D01*
G01X248087Y404805D02*
X252930Y412072D01*
G01X249171Y404356D02*
X253760Y411242D01*
G01X252930Y412072D02*
X270248Y423613D01*
G01X253760Y411242D02*
X270697Y422530D01*
G01X252930Y412072D02*
X270248Y423613D01*
G01D02*
X295721Y428701D01*
G01X270697Y422530D02*
X270698D01*
G01X270248Y423613D02*
X295721Y428701D01*
G01X270698Y422530D02*
X295721Y427528D01*
G01X275281Y407649D02*
X299812Y412555D01*
G01Y411382D02*
X275730Y406566D01*
G01X274724Y409217D02*
X299067Y414085D01*
G01Y415258D02*
X274275Y410301D01*
G01D02*
X263950Y403421D01*
G01X296272Y417202D02*
X275466Y413040D01*
G01X296272Y418375D02*
X275017Y414124D01*
G01X275466Y413040D02*
X263098Y404801D01*
G01X275017Y414124D02*
X262268Y405631D01*
G01X296226Y420937D02*
X273671Y416429D01*
G01X296226Y419764D02*
X274120Y415345D01*
G01X273671Y416429D02*
X259935Y407276D01*
G01X274120Y415345D02*
X260765Y406446D01*
G01X295936Y422373D02*
X272906Y417769D01*
G01X295936Y423546D02*
X272457Y418853D01*
G01X272906Y417769D02*
X258698Y408301D01*
G01X272457Y418853D02*
X257868Y409131D01*
G01X251043Y404514D02*
X254922Y410335D01*
G01X252127Y404067D02*
X255752Y409505D01*
G01X254922Y410335D02*
X271159Y421155D01*
G01X255752Y409505D02*
X271608Y420071D01*
G01X271159Y421155D02*
X295934Y426106D01*
G01X271608Y420071D02*
X295934Y424933D01*
G01X249171Y404356D02*
X253760Y411242D01*
G01X248087Y404805D02*
X252930Y412072D01*
G01X253760Y411242D02*
X270697Y422530D01*
G01D02*
X270698D01*
G01X252930Y412072D02*
X270248Y423613D01*
G01X270697Y422530D02*
X270698D01*
G01D02*
X295721Y427528D01*
G01X270248Y423613D02*
X295721Y428701D01*
G01X364470Y408388D02*
X331783Y401850D01*
G01X364470Y409561D02*
X331783Y403023D01*
G01Y401850D02*
X299917Y408223D01*
G01X331783Y403023D02*
X299917Y409396D01*
G01X364470Y409561D02*
X331783Y403023D01*
G01X364470Y408388D02*
X331783Y401850D01*
G01Y403023D02*
X299917Y409396D01*
G01X331783Y401850D02*
X299917Y408223D01*
G01X327331Y455544D02*
X371457Y446719D01*
G01Y447892D02*
X327331Y456717D01*
G01X326935Y454058D02*
X376271Y444189D01*
G01Y443016D02*
X326935Y452885D01*
G01X327953Y428230D02*
X365288Y435696D01*
G01Y434523D02*
X327953Y427057D01*
G01X371457Y447892D02*
X327331Y456717D01*
G01Y455544D02*
X371457Y446719D01*
G01X376271Y443016D02*
X326935Y452885D01*
G01Y454058D02*
X376271Y444189D01*
G01X365288Y434523D02*
X327953Y427057D01*
G01Y428230D02*
X365288Y435696D01*
G01X326633Y463683D02*
X358106Y457390D01*
G01X326633Y464856D02*
X358106Y458563D01*
G01X363304Y453769D02*
X327383Y460954D01*
G01X363304Y454942D02*
X327383Y462127D01*
G01X367661Y451491D02*
X327731Y459476D01*
G01X367661Y450318D02*
X327731Y458303D01*
G01X326633Y464856D02*
X358106Y458563D01*
G01X326633Y463683D02*
X358106Y457390D01*
G01X363304Y454942D02*
X327383Y462127D01*
G01X363304Y453769D02*
X327383Y460954D01*
G01X367661Y450318D02*
X327731Y458303D01*
G01X367661Y451491D02*
X327731Y459476D01*
G01X327080Y451429D02*
X382326Y440379D01*
G01X327080Y450256D02*
X382326Y439206D01*
G01X327600Y425499D02*
X364754Y432930D01*
G01Y431757D02*
X327600Y424326D01*
G01X294266Y432166D02*
X327600Y425499D01*
G01Y424326D02*
X294266Y430993D01*
G01X327080Y450256D02*
X382326Y439206D01*
G01X327080Y451429D02*
X382326Y440379D01*
G01X327600Y424326D02*
X294266Y430993D01*
G01Y432166D02*
X327600Y425499D01*
G01X364754Y431757D02*
X327600Y424326D01*
G01Y425499D02*
X364754Y432930D01*
G01X329719Y405401D02*
X299812Y411382D01*
G01Y412555D02*
X329719Y406574D01*
G01X363609Y412179D02*
X329719Y405401D01*
G01Y406574D02*
X363609Y413352D01*
G01X329729Y409126D02*
X299067Y415258D01*
G01Y414085D02*
X329729Y407953D01*
G01X363609Y415902D02*
X329729Y409126D01*
G01Y407953D02*
X363609Y414729D01*
G01X364098Y418703D02*
X329365Y411756D01*
G01X364098Y417530D02*
X329365Y410583D01*
G01Y411756D02*
X296272Y418375D01*
G01X329365Y410583D02*
X296272Y417202D01*
G01X364098Y420177D02*
X329131Y413183D01*
G01X364098Y421350D02*
X329131Y414356D01*
G01Y413183D02*
X296226Y419764D01*
G01X329131Y414356D02*
X296226Y420937D01*
G01X364907Y424155D02*
X328896Y416953D01*
G01X364907Y422982D02*
X328896Y415780D01*
G01Y416953D02*
X295936Y423546D01*
G01X328896Y415780D02*
X295936Y422373D01*
G01X295934Y424933D02*
X328125Y418495D01*
G01X295934Y426106D02*
X328125Y419668D01*
G01Y418495D02*
X364990Y425868D01*
G01X328125Y419668D02*
X364990Y427041D01*
G01X295721Y428701D02*
X328133Y422220D01*
G01X295721Y427528D02*
X328133Y421047D01*
G01Y422220D02*
X365216Y429637D01*
G01X328133Y421047D02*
X365216Y428464D01*
G01X329719Y406574D02*
X363609Y413352D01*
G01Y412179D02*
X329719Y405401D01*
G01X299812Y412555D02*
X329719Y406574D01*
G01Y405401D02*
X299812Y411382D01*
G01X329729Y407953D02*
X363609Y414729D01*
G01Y415902D02*
X329729Y409126D01*
G01X299067Y414085D02*
X329729Y407953D01*
G01Y409126D02*
X299067Y415258D01*
G01X364098Y417530D02*
X329365Y410583D01*
G01X364098Y418703D02*
X329365Y411756D01*
G01Y410583D02*
X296272Y417202D01*
G01X329365Y411756D02*
X296272Y418375D01*
G01X364098Y421350D02*
X329131Y414356D01*
G01X364098Y420177D02*
X329131Y413183D01*
G01Y414356D02*
X296226Y420937D01*
G01X329131Y413183D02*
X296226Y419764D01*
G01X364907Y422982D02*
X328896Y415780D01*
G01X364907Y424155D02*
X328896Y416953D01*
G01Y415780D02*
X295936Y422373D01*
G01X328896Y416953D02*
X295936Y423546D01*
G01X295934Y426106D02*
X328125Y419668D01*
G01X295934Y424933D02*
X328125Y418495D01*
G01Y419668D02*
X364990Y427041D01*
G01X328125Y418495D02*
X364990Y425868D01*
G01X295721Y427528D02*
X328133Y421047D01*
G01X295721Y428701D02*
X328133Y422220D01*
G01Y421047D02*
X365216Y428464D01*
G01X328133Y422220D02*
X365216Y429637D01*
G01X409433Y445942D02*
X484248Y460906D01*
G01Y462079D02*
X409433Y447115D01*
G01X388501Y450127D02*
X409433Y445942D01*
G01Y447115D02*
X388501Y451300D01*
G01X371457Y446719D02*
X388501Y450127D01*
G01Y451300D02*
X371457Y447892D01*
G01X406430Y443816D02*
X484098Y459349D01*
G01Y458176D02*
X406430Y442643D01*
G01X390394Y447023D02*
X406430Y443816D01*
G01Y442643D02*
X390394Y445850D01*
G01X376271Y444189D02*
X390394Y447023D01*
G01Y445850D02*
X385149Y444797D01*
G01X376271Y444189D02*
X390394Y447023D01*
G01X382550Y444276D02*
X376271Y443016D01*
G01X379814Y432790D02*
X484645Y453641D01*
G01X379814Y432790D02*
X484645Y453641D01*
G01X458934Y447354D02*
X379813Y431617D01*
G01X365288Y435696D02*
X379814Y432790D01*
G01X379813Y431617D02*
X365288Y434523D01*
G01X388501Y451300D02*
X371457Y447892D01*
G01Y446719D02*
X388501Y450127D01*
G01X409433Y447115D02*
X388501Y451300D01*
G01Y450127D02*
X409433Y445942D01*
G01X484248Y462079D02*
X409433Y447115D01*
G01Y445942D02*
X484248Y460906D01*
G01X390394Y445850D02*
X385149Y444797D01*
G01X382550Y444276D02*
X376271Y443016D01*
G01Y444189D02*
X390394Y447023D01*
G01X406430Y442643D02*
X390394Y445850D01*
G01Y447023D02*
X406430Y443816D01*
G01X484098Y458176D02*
X406430Y442643D01*
G01Y443816D02*
X484098Y459349D01*
G01X379813Y431617D02*
X365288Y434523D01*
G01Y435696D02*
X379814Y432790D01*
G01X458934Y447354D02*
X379813Y431617D01*
G01X379814Y432790D02*
X484645Y453641D01*
G01X358106Y457390D02*
X387402Y463247D01*
G01X358106Y458563D02*
X387402Y464420D01*
G01Y463247D02*
X410446Y458633D01*
G01X413044Y458113D02*
X414368Y457848D01*
G01X387402Y464420D02*
X422212Y457451D01*
G01X417187Y452694D02*
X387547Y458617D01*
G01X417187Y453867D02*
X387547Y459790D01*
G01Y458617D02*
X363304Y453769D01*
G01X387547Y459790D02*
X363304Y454942D01*
G01X484351Y464696D02*
X412782Y450386D01*
G01X484351Y463523D02*
X412782Y449213D01*
G01Y450386D02*
X387449Y455450D01*
G01X412782Y449213D02*
X410579Y449653D01*
G01X412782Y450386D02*
X387449Y455450D01*
G01X407981Y450173D02*
X406657Y450437D01*
G01X412782Y450386D02*
X387449Y455450D01*
G01X404058Y450957D02*
X402734Y451221D01*
G01X412782Y450386D02*
X387449Y455450D01*
G01X400136Y451741D02*
X400135D01*
G01X412782Y450386D02*
X387449Y455450D01*
G01X400135Y451741D02*
X387449Y454277D01*
G01Y455450D02*
X367661Y451491D01*
G01X387449Y454277D02*
X367661Y450318D01*
G01X358106Y458563D02*
X387402Y464420D01*
G01X358106Y457390D02*
X387402Y463247D01*
G01Y464420D02*
X422212Y457451D01*
G01X387402Y463247D02*
X410446Y458633D01*
G01X387402Y464420D02*
X422212Y457451D01*
G01X413044Y458113D02*
X414368Y457848D01*
G01X387402Y464420D02*
X422212Y457451D01*
G01X387402Y464420D02*
X422212Y457451D01*
G01X417187Y453867D02*
X387547Y459790D01*
G01X417187Y452694D02*
X387547Y458617D01*
G01Y459790D02*
X363304Y454942D01*
G01X387547Y458617D02*
X363304Y453769D01*
G01X484351Y463523D02*
X412782Y449213D01*
G01X484351Y464696D02*
X412782Y450386D01*
G01Y449213D02*
X410579Y449653D01*
G01X407981Y450173D02*
X406657Y450437D01*
G01X404058Y450957D02*
X402734Y451221D01*
G01X400136Y451741D02*
X400135D01*
G01D02*
X387449Y454277D01*
G01X412782Y450386D02*
X387449Y455450D01*
G01Y454277D02*
X367661Y450318D01*
G01X387449Y455450D02*
X367661Y451491D01*
G01X420774Y411835D02*
X384011Y404480D01*
G01X420774Y413008D02*
X384011Y405653D01*
G01Y404480D02*
X364470Y408388D01*
G01X384011Y405653D02*
X364470Y409561D01*
G01X420774Y413008D02*
X384011Y405653D01*
G01X420774Y411835D02*
X384011Y404480D01*
G01Y405653D02*
X364470Y409561D01*
G01X384011Y404480D02*
X364470Y408388D01*
G01X382326Y440379D02*
X395318Y442977D01*
G01X382326Y439206D02*
X395318Y441804D01*
G01Y442977D02*
X405701Y440900D01*
G01X395318Y441804D02*
X405701Y439727D01*
G01Y440900D02*
X483678Y456494D01*
G01X405701Y439727D02*
X483678Y455321D01*
G01X381499Y429581D02*
X418899Y437060D01*
G01Y435887D02*
X381499Y428408D01*
G01X364754Y432930D02*
X381499Y429581D01*
G01Y428408D02*
X364754Y431757D01*
G01X382326Y439206D02*
X395318Y441804D01*
G01X382326Y440379D02*
X395318Y442977D01*
G01Y441804D02*
X405701Y439727D01*
G01X395318Y442977D02*
X405701Y440900D01*
G01Y439727D02*
X483678Y455321D01*
G01X405701Y440900D02*
X483678Y456494D01*
G01X381499Y428408D02*
X364754Y431757D01*
G01Y432930D02*
X381499Y429581D01*
G01X418899Y435887D02*
X381499Y428408D01*
G01Y429581D02*
X418899Y437060D01*
G01X386509Y407599D02*
X363609Y412179D01*
G01Y413352D02*
X386509Y408772D01*
G01X421239Y414547D02*
X386509Y407599D01*
G01Y408772D02*
X421239Y415720D01*
G01X385510Y411522D02*
X363609Y415902D01*
G01Y414729D02*
X385510Y410349D01*
G01X420245Y418471D02*
X385510Y411522D01*
G01Y410349D02*
X420245Y417298D01*
G01X420246Y421174D02*
X386000Y414323D01*
G01X420246Y420001D02*
X386000Y413150D01*
G01Y414323D02*
X364098Y418703D01*
G01X386000Y413150D02*
X364098Y417530D01*
G01X420246Y422648D02*
X386000Y415797D01*
G01X420246Y423821D02*
X386000Y416970D01*
G01Y415797D02*
X364098Y420177D01*
G01X386000Y416970D02*
X364098Y421350D01*
G01X420246Y426788D02*
X385999Y419937D01*
G01X420246Y425615D02*
X385999Y418764D01*
G01Y419937D02*
X364907Y424155D01*
G01X385999Y418764D02*
X364907Y422982D01*
G01X364990Y425868D02*
X386203Y421626D01*
G01X364990Y427041D02*
X386203Y422799D01*
G01Y421626D02*
X420698Y428527D01*
G01X386203Y422799D02*
X420698Y429700D01*
G01X365216Y429637D02*
X385753Y425530D01*
G01X365216Y428464D02*
X385753Y424357D01*
G01Y425530D02*
X420050Y432390D01*
G01X385753Y424357D02*
X420050Y431217D01*
G01X386509Y408772D02*
X421239Y415720D01*
G01Y414547D02*
X386509Y407599D01*
G01X363609Y413352D02*
X386509Y408772D01*
G01Y407599D02*
X363609Y412179D01*
G01X385510Y410349D02*
X420245Y417298D01*
G01Y418471D02*
X385510Y411522D01*
G01X363609Y414729D02*
X385510Y410349D01*
G01Y411522D02*
X363609Y415902D01*
G01X420246Y420001D02*
X386000Y413150D01*
G01X420246Y421174D02*
X386000Y414323D01*
G01Y413150D02*
X364098Y417530D01*
G01X386000Y414323D02*
X364098Y418703D01*
G01X420246Y423821D02*
X386000Y416970D01*
G01X420246Y422648D02*
X386000Y415797D01*
G01Y416970D02*
X364098Y421350D01*
G01X386000Y415797D02*
X364098Y420177D01*
G01X420246Y425615D02*
X385999Y418764D01*
G01X420246Y426788D02*
X385999Y419937D01*
G01Y418764D02*
X364907Y422982D01*
G01X385999Y419937D02*
X364907Y424155D01*
G01X364990Y427041D02*
X386203Y422799D01*
G01X364990Y425868D02*
X386203Y421626D01*
G01Y422799D02*
X420698Y429700D01*
G01X386203Y421626D02*
X420698Y428527D01*
G01X365216Y428464D02*
X385753Y424357D01*
G01X365216Y429637D02*
X385753Y425530D01*
G01Y424357D02*
X420050Y431217D01*
G01X385753Y425530D02*
X420050Y432390D01*
G01X484645Y452468D02*
X461533Y447871D01*
G01X484645Y452468D02*
X461533Y447871D01*
G01X416966Y457328D02*
X418290Y457063D01*
G01X420888Y456543D02*
X422212Y456278D01*
G01D02*
X484833Y468802D01*
G01X422212Y457451D02*
X484833Y469975D01*
G01X484439Y466142D02*
X417187Y452694D01*
G01X484439Y467315D02*
X417187Y453867D01*
G01X416966Y457328D02*
X418290Y457063D01*
G01X420888Y456543D02*
X422212Y456278D01*
G01Y457451D02*
X484833Y469975D01*
G01X422212Y456278D02*
X484833Y468802D01*
G01X484439Y467315D02*
X417187Y453867D01*
G01X484439Y466142D02*
X417187Y452694D01*
G01X506280Y403365D02*
X461200Y412383D01*
G01X506847Y404425D02*
X461200Y413556D01*
G01Y412383D02*
X439620Y408066D01*
G01X461200Y413556D02*
X439620Y409239D01*
G01Y408066D02*
X420774Y411835D01*
G01X439620Y409239D02*
X420774Y413008D01*
G01X506847Y404425D02*
X461200Y413556D01*
G01X506280Y403365D02*
X461200Y412383D01*
G01Y413556D02*
X439620Y409239D01*
G01X461200Y412383D02*
X439620Y408066D01*
G01Y409239D02*
X420774Y413008D01*
G01X439620Y408066D02*
X420774Y411835D01*
G01X452116Y437377D02*
X453440Y437112D01*
G01X456038Y436593D02*
X503199Y427160D01*
G01Y425987D02*
X452116Y436204D01*
G01X434717Y433898D02*
X452113Y437378D01*
G01X452116Y436204D02*
X434717Y432725D01*
G01X418899Y437060D02*
X421455Y436549D01*
G01X424053Y436030D02*
X425377Y435765D01*
G01X427976Y435246D02*
X434717Y433898D01*
G01Y432725D02*
X418899Y435887D01*
G01X434717Y432725D02*
X418899Y435887D01*
G01Y437060D02*
X421455Y436549D01*
G01X434717Y432725D02*
X418899Y435887D01*
G01X424053Y436030D02*
X425377Y435765D01*
G01X434717Y432725D02*
X418899Y435887D01*
G01X427976Y435246D02*
X434717Y433898D01*
G01X452116Y436204D02*
X434717Y432725D01*
G01Y433898D02*
X452113Y437378D01*
G01X503199Y425987D02*
X452116Y436204D01*
G01Y437377D02*
X453440Y437112D01*
G01X503199Y425987D02*
X452116Y436204D01*
G01X456038Y436593D02*
X503199Y427160D01*
G01X438355Y411124D02*
X421239Y414547D01*
G01Y415720D02*
X438355Y412297D01*
G01X459470Y415347D02*
X438355Y411124D01*
G01Y412297D02*
X459470Y416520D01*
G01X504059Y406428D02*
X459470Y415347D01*
G01Y416520D02*
X504059Y407601D01*
G01X436780Y415163D02*
X420245Y418471D01*
G01Y417298D02*
X436780Y413990D01*
G01X458188Y419445D02*
X436780Y415163D01*
G01Y413990D02*
X458188Y418272D01*
G01X504200Y410243D02*
X458188Y419445D01*
G01Y418272D02*
X504202Y409069D01*
G01X504546Y412922D02*
X456768Y422478D01*
G01X504546Y411749D02*
X456768Y421305D01*
G01Y422478D02*
X435252Y418173D01*
G01X456768Y421305D02*
X435252Y417000D01*
G01Y418173D02*
X420246Y421174D01*
G01X435252Y417000D02*
X420246Y420001D01*
G01X504328Y414504D02*
X455842Y424201D01*
G01X504328Y415677D02*
X455842Y425374D01*
G01Y424201D02*
X434162Y419864D01*
G01X455842Y425374D02*
X434162Y421037D01*
G01Y419864D02*
X420246Y422648D01*
G01X434162Y421037D02*
X420246Y423821D01*
G01X503308Y418450D02*
X454775Y428156D01*
G01X503308Y417277D02*
X454775Y426983D01*
G01Y428156D02*
X434093Y424018D01*
G01X454775Y426983D02*
X434093Y422845D01*
G01Y424018D02*
X420246Y426788D01*
G01X434093Y422845D02*
X420246Y425615D01*
G01X420698Y428527D02*
X433354Y425995D01*
G01X420698Y429700D02*
X433354Y427168D01*
G01Y425995D02*
X452935Y429912D01*
G01X433354Y427168D02*
X452935Y431085D01*
G01Y429912D02*
X503052Y419889D01*
G01X452935Y431085D02*
X503052Y421062D01*
G01X420050Y432390D02*
X432022Y429994D01*
G01X420050Y431217D02*
X432022Y428821D01*
G01Y429994D02*
X451664Y433923D01*
G01X432022Y428821D02*
X451664Y432750D01*
G01Y433923D02*
X502657Y423723D01*
G01X451664Y432750D02*
X502657Y422550D01*
G01X459470Y416520D02*
X504059Y407601D01*
G01Y406428D02*
X459470Y415347D01*
G01X438355Y412297D02*
X459470Y416520D01*
G01Y415347D02*
X438355Y411124D01*
G01X421239Y415720D02*
X438355Y412297D01*
G01Y411124D02*
X421239Y414547D01*
G01X458188Y418272D02*
X504202Y409069D01*
G01X504200Y410243D02*
X458188Y419445D01*
G01X436780Y413990D02*
X458188Y418272D01*
G01Y419445D02*
X436780Y415163D01*
G01X420245Y417298D02*
X436780Y413990D01*
G01Y415163D02*
X420245Y418471D01*
G01X504546Y411749D02*
X456768Y421305D01*
G01X504546Y412922D02*
X456768Y422478D01*
G01Y421305D02*
X435252Y417000D01*
G01X456768Y422478D02*
X435252Y418173D01*
G01Y417000D02*
X420246Y420001D01*
G01X435252Y418173D02*
X420246Y421174D01*
G01X504328Y415677D02*
X455842Y425374D01*
G01X504328Y414504D02*
X455842Y424201D01*
G01Y425374D02*
X434162Y421037D01*
G01X455842Y424201D02*
X434162Y419864D01*
G01Y421037D02*
X420246Y423821D01*
G01X434162Y419864D02*
X420246Y422648D01*
G01X503308Y417277D02*
X454775Y426983D01*
G01X503308Y418450D02*
X454775Y428156D01*
G01Y426983D02*
X434093Y422845D01*
G01X454775Y428156D02*
X434093Y424018D01*
G01Y422845D02*
X420246Y425615D01*
G01X434093Y424018D02*
X420246Y426788D01*
G01X420698Y429700D02*
X433354Y427168D01*
G01X420698Y428527D02*
X433354Y425995D01*
G01Y427168D02*
X452935Y431085D01*
G01X433354Y425995D02*
X452935Y429912D01*
G01Y431085D02*
X503052Y421062D01*
G01X452935Y429912D02*
X503052Y419889D01*
G01X420050Y431217D02*
X432022Y428821D01*
G01X420050Y432390D02*
X432022Y429994D01*
G01Y428821D02*
X451664Y432750D01*
G01X432022Y429994D02*
X451664Y433923D01*
G01Y432750D02*
X502657Y422550D01*
G01X451664Y433923D02*
X502657Y423723D01*
G01X479062Y643863D02*
X478153Y645164D01*
G01X477731Y654008D02*
X476040Y644426D01*
G01X476680Y654676D02*
X474990Y645095D01*
G01X476040Y644426D02*
X474740Y643515D01*
G01X474990Y645095D02*
X474470Y644731D01*
G01X476040Y644426D02*
X474740Y643515D01*
G01D02*
X472766Y643862D01*
G01X474470Y644731D02*
X473436Y644913D01*
G01X472766Y643862D02*
X471856Y645165D01*
G01X473436Y644913D02*
X473072Y645434D01*
G01X471856Y645165D02*
X473356Y653674D01*
G01X473072Y645434D02*
X474572Y653945D01*
G01X471435Y654011D02*
X469753Y644459D01*
G01X470385Y654681D02*
X468702Y645129D01*
G01X469753Y644459D02*
X468449Y643549D01*
G01X468702Y645129D02*
X468179Y644764D01*
G01X469753Y644459D02*
X468449Y643549D01*
G01D02*
X466475Y643895D01*
G01X468179Y644764D02*
X467145Y644946D01*
G01X466475Y643895D02*
X465565Y645198D01*
G01X467145Y644946D02*
X466781Y645467D01*
G01X465565Y645198D02*
X467056Y653654D01*
G01X466781Y645467D02*
X468272Y653923D01*
G01X465136Y653992D02*
X463457Y644458D01*
G01X464085Y654662D02*
X462407Y645128D01*
G01X463457Y644458D02*
X462153Y643548D01*
G01X462407Y645128D02*
X461884Y644763D01*
G01X463457Y644458D02*
X462153Y643548D01*
G01D02*
X460179Y643894D01*
G01X461884Y644763D02*
X460849Y644945D01*
G01X460179Y643894D02*
X459269Y645197D01*
G01X460849Y644945D02*
X460485Y645466D01*
G01X459269Y645197D02*
X460761Y653651D01*
G01X460485Y645466D02*
X461977Y653919D01*
G01X458841Y653989D02*
X457156Y644439D01*
G01X457790Y654658D02*
X456106Y645108D01*
G01X457156Y644439D02*
X455856Y643529D01*
G01X456106Y645108D02*
X455587Y644745D01*
G01X457156Y644439D02*
X455856Y643529D01*
G01D02*
X453883Y643878D01*
G01X455587Y644745D02*
X454553Y644928D01*
G01X453883Y643878D02*
X452970Y645182D01*
G01X454553Y644928D02*
X454186Y645452D01*
G01X452970Y645182D02*
X454454Y653589D01*
G01X454186Y645452D02*
X455670Y653858D01*
G01X451962Y651088D02*
X450965Y649759D01*
G01D02*
X449899Y648949D01*
G01X450965Y649759D02*
X449899Y648949D01*
G01D02*
X449053D01*
G01X479062Y643863D02*
X478153Y645164D01*
G01X476680Y654676D02*
X474990Y645095D01*
G01X477731Y654008D02*
X476040Y644426D01*
G01X474990Y645095D02*
X474470Y644731D01*
G01D02*
X473436Y644913D01*
G01X476040Y644426D02*
X474740Y643515D01*
G01X474470Y644731D02*
X473436Y644913D01*
G01X474740Y643515D02*
X472766Y643862D01*
G01X473436Y644913D02*
X473072Y645434D01*
G01X472766Y643862D02*
X471856Y645165D01*
G01X473072Y645434D02*
X474572Y653945D01*
G01X471856Y645165D02*
X473356Y653674D01*
G01X470385Y654681D02*
X468702Y645129D01*
G01X471435Y654011D02*
X469753Y644459D01*
G01X468702Y645129D02*
X468179Y644764D01*
G01D02*
X467145Y644946D01*
G01X469753Y644459D02*
X468449Y643549D01*
G01X468179Y644764D02*
X467145Y644946D01*
G01X468449Y643549D02*
X466475Y643895D01*
G01X467145Y644946D02*
X466781Y645467D01*
G01X466475Y643895D02*
X465565Y645198D01*
G01X466781Y645467D02*
X468272Y653923D01*
G01X465565Y645198D02*
X467056Y653654D01*
G01X464085Y654662D02*
X462407Y645128D01*
G01X465136Y653992D02*
X463457Y644458D01*
G01X462407Y645128D02*
X461884Y644763D01*
G01D02*
X460849Y644945D01*
G01X463457Y644458D02*
X462153Y643548D01*
G01X461884Y644763D02*
X460849Y644945D01*
G01X462153Y643548D02*
X460179Y643894D01*
G01X460849Y644945D02*
X460485Y645466D01*
G01X460179Y643894D02*
X459269Y645197D01*
G01X460485Y645466D02*
X461977Y653919D01*
G01X459269Y645197D02*
X460761Y653651D01*
G01X457790Y654658D02*
X456106Y645108D01*
G01X458841Y653989D02*
X457156Y644439D01*
G01X456106Y645108D02*
X455587Y644745D01*
G01D02*
X454553Y644928D01*
G01X457156Y644439D02*
X455856Y643529D01*
G01X455587Y644745D02*
X454553Y644928D01*
G01X455856Y643529D02*
X453883Y643878D01*
G01X454553Y644928D02*
X454186Y645452D01*
G01X453883Y643878D02*
X452970Y645182D01*
G01X454186Y645452D02*
X455670Y653858D01*
G01X452970Y645182D02*
X454454Y653589D01*
G01X451962Y651088D02*
X450965Y649759D01*
G01D02*
X449899Y648949D01*
G01D02*
X449053D01*
G01X479957Y655243D02*
X477983Y655592D01*
G01X478254Y654376D02*
X477731Y654008D01*
G01X477983Y655592D02*
X476680Y654676D01*
G01X473356Y653674D02*
X472990Y654194D01*
G01X474572Y653945D02*
X473657Y655245D01*
G01X472990Y654194D02*
X471957Y654375D01*
G01X473657Y655245D02*
X471688Y655590D01*
G01X472990Y654194D02*
X471957Y654375D01*
G01D02*
X471435Y654011D01*
G01X471688Y655590D02*
X470385Y654681D01*
G01X467056Y653654D02*
X466691Y654176D01*
G01X468272Y653923D02*
X467360Y655227D01*
G01X466691Y654176D02*
X465658Y654357D01*
G01X467360Y655227D02*
X465388Y655572D01*
G01X466691Y654176D02*
X465658Y654357D01*
G01D02*
X465136Y653992D01*
G01X465388Y655572D02*
X464085Y654662D01*
G01X460761Y653651D02*
X460397Y654174D01*
G01X461977Y653919D02*
X461068Y655224D01*
G01X460397Y654174D02*
X459364Y654356D01*
G01X461068Y655224D02*
X459094Y655572D01*
G01X460397Y654174D02*
X459364Y654356D01*
G01D02*
X458841Y653989D01*
G01X459094Y655572D02*
X457790Y654658D01*
G01X454454Y653589D02*
X454089Y654111D01*
G01X455670Y653858D02*
X454759Y655162D01*
G01X454089Y654111D02*
X453055Y654293D01*
G01X454759Y655162D02*
X452785Y655509D01*
G01X454089Y654111D02*
X453055Y654293D01*
G01D02*
X452534Y653928D01*
G01X452785Y655509D02*
X451484Y654597D01*
G01X452534Y653928D02*
X452198Y652018D01*
G01X451484Y654597D02*
X451072Y652260D01*
G01X452198Y652018D02*
X451962Y651088D01*
G01X451072Y652260D02*
X450903Y651594D01*
G01D02*
X450141Y650578D01*
G01D02*
X449511Y650099D01*
G01D02*
X449033D01*
G01X479957Y655243D02*
X477983Y655592D01*
G01D02*
X476680Y654676D01*
G01X477983Y655592D02*
X476680Y654676D01*
G01X478254Y654376D02*
X477731Y654008D01*
G01X474572Y653945D02*
X473657Y655245D01*
G01X473356Y653674D02*
X472990Y654194D01*
G01X473657Y655245D02*
X471688Y655590D01*
G01D02*
X470385Y654681D01*
G01X472990Y654194D02*
X471957Y654375D01*
G01X471688Y655590D02*
X470385Y654681D01*
G01X471957Y654375D02*
X471435Y654011D01*
G01X468272Y653923D02*
X467360Y655227D01*
G01X467056Y653654D02*
X466691Y654176D01*
G01X467360Y655227D02*
X465388Y655572D01*
G01D02*
X464085Y654662D01*
G01X466691Y654176D02*
X465658Y654357D01*
G01X465388Y655572D02*
X464085Y654662D01*
G01X465658Y654357D02*
X465136Y653992D01*
G01X461977Y653919D02*
X461068Y655224D01*
G01X460761Y653651D02*
X460397Y654174D01*
G01X461068Y655224D02*
X459094Y655572D01*
G01D02*
X457790Y654658D01*
G01X460397Y654174D02*
X459364Y654356D01*
G01X459094Y655572D02*
X457790Y654658D01*
G01X459364Y654356D02*
X458841Y653989D01*
G01X455670Y653858D02*
X454759Y655162D01*
G01X454454Y653589D02*
X454089Y654111D01*
G01X454759Y655162D02*
X452785Y655509D01*
G01D02*
X451484Y654597D01*
G01X454089Y654111D02*
X453055Y654293D01*
G01X452785Y655509D02*
X451484Y654597D01*
G01X453055Y654293D02*
X452534Y653928D01*
G01X451484Y654597D02*
X451072Y652260D01*
G01X452534Y653928D02*
X452198Y652018D01*
G01X451072Y652260D02*
X450903Y651594D01*
G01X452198Y652018D02*
X451962Y651088D01*
G01X450903Y651594D02*
X450141Y650578D01*
G01D02*
X449511Y650099D01*
G01D02*
X449033D01*
G01X449511D02*
X449033D01*
G01X524004Y159863D02*
X552403Y148398D01*
G01X524701Y160823D02*
X552606Y149557D01*
G01X521234Y159342D02*
X552884Y146304D01*
G01X520519Y158392D02*
X552683Y145143D01*
G01X524701Y160823D02*
X552606Y149557D01*
G01X524004Y159863D02*
X552403Y148398D01*
G01X520519Y158392D02*
X552683Y145143D01*
G01X521234Y159342D02*
X552884Y146304D01*
G01X497650Y205800D02*
Y187750D01*
G01X498800Y205800D02*
Y188228D01*
G01X497650Y187750D02*
X515950Y169450D01*
G01X498800Y188228D02*
X516799Y170229D01*
G01X515950Y169450D02*
X524004Y159863D01*
G01X516799Y170229D02*
X524701Y160823D01*
G01X493203Y217685D02*
X492689D01*
G01D02*
X492074Y217070D01*
G01X492212Y218835D02*
X490924Y217547D01*
G01X492074Y217070D02*
Y213584D01*
G01X490924Y217547D02*
Y213435D01*
G01X492074Y213584D02*
X495957Y198844D01*
G01X490924Y213435D02*
X494806Y198695D01*
G01X495957Y198844D02*
Y186371D01*
G01X494807Y198694D02*
Y185894D01*
G01X495957Y186371D02*
X514504Y167825D01*
G01X494807Y185894D02*
X513644Y167057D01*
G01X514504Y167824D02*
X521234Y159342D01*
G01X513644Y167057D02*
X520519Y158392D01*
G01X498800Y205800D02*
Y188228D01*
G01X497650Y205800D02*
Y187750D01*
G01X498800Y188228D02*
X516799Y170229D01*
G01X497650Y187750D02*
X515950Y169450D01*
G01X516799Y170229D02*
X524701Y160823D01*
G01X515950Y169450D02*
X524004Y159863D01*
G01X493203Y217685D02*
X492689D01*
G01X492212Y218835D02*
X490924Y217547D01*
G01X492689Y217685D02*
X492074Y217070D01*
G01X490924Y217547D02*
Y213435D01*
G01X492074Y217070D02*
Y213584D01*
G01X490924Y213435D02*
X494806Y198695D01*
G01X492074Y213584D02*
X495957Y198844D01*
G01X494807Y198694D02*
Y185894D01*
G01X495957Y198844D02*
Y186371D01*
G01X494807Y185894D02*
X513644Y167057D01*
G01X495957Y186371D02*
X514504Y167825D01*
G01X513644Y167057D02*
X520519Y158392D01*
G01X514504Y167824D02*
X521234Y159342D01*
G01X560427Y174659D02*
X538031Y182282D01*
G01X560427Y174659D02*
X538031Y182282D01*
G01X560427Y174659D02*
X538031Y182282D01*
G01X560427Y174659D02*
X538031Y182282D01*
G01X560427Y174659D02*
X538031Y182282D01*
G01X560427Y174659D02*
X538031Y182282D01*
G01X539932Y182850D02*
X538655Y183285D01*
G01X538031Y182282D02*
X527010Y193303D01*
G01X538655Y183285D02*
X527823Y194117D01*
G01X560281Y170710D02*
X537159Y178593D01*
G01X560281Y170710D02*
X537159Y178593D01*
G01X560281Y170710D02*
X537159Y178593D01*
G01X560281Y170710D02*
X537159Y178593D01*
G01X560281Y170710D02*
X537159Y178593D01*
G01X560281Y170710D02*
X537159Y178593D01*
G01X560281Y170710D02*
X537159Y178593D01*
G01X539061Y179161D02*
X537784Y179596D01*
G01X537159Y178593D02*
X519757Y195996D01*
G01X537784Y179596D02*
X520907Y196473D01*
G01X519757Y195996D02*
Y201956D01*
G01X520907Y196473D02*
Y202056D01*
G01X536401Y176678D02*
X537661Y176194D01*
G01X557925Y167178D02*
X535760Y175691D01*
G01X517451Y195628D02*
X536401Y176678D01*
G01X535760Y175691D02*
X516301Y195151D01*
G01X517451Y200882D02*
Y195628D01*
G01X516301Y195151D02*
Y200882D01*
G01X556320Y163621D02*
X535325Y172073D01*
G01X556320Y163621D02*
X535325Y172073D01*
G01X556320Y163621D02*
X535325Y172073D01*
G01X556320Y163621D02*
X535325Y172073D01*
G01X556320Y163621D02*
X535325Y172073D01*
G01X540843Y171092D02*
X539591Y171596D01*
G01X556320Y163621D02*
X535325Y172073D01*
G01X537225Y172549D02*
X535973Y173053D01*
G01X535325Y172073D02*
X512896Y194502D01*
G01X535973Y173053D02*
X514046Y194980D01*
G01X512896Y194502D02*
Y203996D01*
G01X514046Y194980D02*
Y203996D01*
G01X555872Y161820D02*
X534623Y170103D01*
G01X555674Y160662D02*
X533980Y169119D01*
G01X534623Y170103D02*
X510152Y194574D01*
G01X533980Y169119D02*
X509002Y194097D01*
G01X510152Y194574D02*
Y205003D01*
G01X509002Y194097D02*
Y205003D01*
G01X555011Y158597D02*
X533028Y167464D01*
G01X554805Y157439D02*
X532381Y166484D01*
G01X533028Y167464D02*
X506827Y193596D01*
G01X532381Y166484D02*
X505677Y193118D01*
G01X506827Y193596D02*
Y202226D01*
G01Y204008D02*
Y205358D01*
G01X505677Y193118D02*
Y205358D01*
G01X554154Y154393D02*
X531050Y163489D01*
G01X554349Y155553D02*
X531695Y164472D01*
G01X531050Y163489D02*
X502812Y191727D01*
G01X531695Y164472D02*
X503962Y192204D01*
G01X502812Y191727D02*
Y205301D01*
G01X503962Y192204D02*
Y205301D01*
G01X554201Y152498D02*
X530431Y161812D01*
G01X554013Y151336D02*
X529991Y160749D01*
G01X530431Y161812D02*
X526317Y163606D01*
G01X529991Y160749D02*
X525613Y162658D01*
G01X526317Y163606D02*
X525443Y164634D01*
G01X523790Y166578D02*
X522916Y167606D01*
G01X521264Y169550D02*
X519550Y171566D01*
G01X525613Y162658D02*
X518705Y170783D01*
G01X519550Y171566D02*
X501396Y189713D01*
G01X518705Y170783D02*
X500246Y189236D01*
G01X501396Y189713D02*
Y205672D01*
G01X500246Y189236D02*
Y205672D01*
G01X542567Y188385D02*
X539686Y189379D01*
G01D02*
X533238Y195374D01*
G01X540291Y190387D02*
X534388Y195876D01*
G01X533238Y195374D02*
Y200588D01*
G01X534388Y195876D02*
Y200588D01*
G01X561352Y178352D02*
X539143Y185553D01*
G01X561352Y178352D02*
X539143Y185553D01*
G01X561352Y178352D02*
X539143Y185553D01*
G01X561352Y178352D02*
X539143Y185553D01*
G01X561352Y178352D02*
X539143Y185553D01*
G01X561352Y178352D02*
X539143Y185553D01*
G01X540809Y186223D02*
X539525Y186639D01*
G01X539143Y185553D02*
X538269Y185885D01*
G01X539525Y186639D02*
X538888Y186881D01*
G01X538269Y185885D02*
X534300Y189575D01*
G01D02*
X534298D01*
G01X538888Y186881D02*
X535083Y190418D01*
G01X534298Y189575D02*
X532563Y191310D01*
G01X535083Y190418D02*
X533377Y192124D01*
G01X539932Y182850D02*
X538655Y183285D01*
G01X560427Y174659D02*
X538031Y182282D01*
G01X538655Y183285D02*
X527823Y194117D01*
G01X538031Y182282D02*
X527010Y193303D01*
G01X539061Y179161D02*
X537784Y179596D01*
G01X560281Y170710D02*
X537159Y178593D01*
G01X537784Y179596D02*
X520907Y196473D01*
G01X537159Y178593D02*
X519757Y195996D01*
G01X520907Y196473D02*
Y202056D01*
G01X519757Y195996D02*
Y201956D01*
G01X516301Y195151D02*
Y200882D01*
G01X517451D02*
Y195628D01*
G01X535760Y175691D02*
X516301Y195151D01*
G01X517451Y195628D02*
X536401Y176678D01*
G01X557925Y167178D02*
X535760Y175691D01*
G01X536401Y176678D02*
X537661Y176194D01*
G01X557925Y167178D02*
X535760Y175691D01*
G01X557925Y167178D02*
X535760Y175691D01*
G01X557925Y167178D02*
X535760Y175691D01*
G01X557925Y167178D02*
X535760Y175691D01*
G01X557925Y167178D02*
X535760Y175691D01*
G01X540843Y171092D02*
X539591Y171596D01*
G01X537225Y172549D02*
X535973Y173053D01*
G01X556320Y163621D02*
X535325Y172073D01*
G01X535973Y173053D02*
X514046Y194980D01*
G01X535325Y172073D02*
X512896Y194502D01*
G01X514046Y194980D02*
Y203996D01*
G01X512896Y194502D02*
Y203996D01*
G01X555674Y160662D02*
X533980Y169119D01*
G01X555872Y161820D02*
X534623Y170103D01*
G01X533980Y169119D02*
X509002Y194097D01*
G01X534623Y170103D02*
X510152Y194574D01*
G01X509002Y194097D02*
Y205003D01*
G01X510152Y194574D02*
Y205003D01*
G01X554805Y157439D02*
X532381Y166484D01*
G01X555011Y158597D02*
X533028Y167464D01*
G01X532381Y166484D02*
X505677Y193118D01*
G01X533028Y167464D02*
X506827Y193596D01*
G01X505677Y193118D02*
Y205358D01*
G01X506827Y193596D02*
Y202226D01*
G01X505677Y193118D02*
Y205358D01*
G01X506827Y204008D02*
Y205358D01*
G01X554349Y155553D02*
X531695Y164472D01*
G01X554154Y154393D02*
X531050Y163489D01*
G01X531695Y164472D02*
X503962Y192204D01*
G01X531050Y163489D02*
X502812Y191727D01*
G01X503962Y192204D02*
Y205301D01*
G01X502812Y191727D02*
Y205301D01*
G01X554013Y151336D02*
X529991Y160749D01*
G01X554201Y152498D02*
X530431Y161812D01*
G01X529991Y160749D02*
X525613Y162658D01*
G01X530431Y161812D02*
X526317Y163606D01*
G01X525613Y162658D02*
X518705Y170783D01*
G01X526317Y163606D02*
X525443Y164634D01*
G01X525613Y162658D02*
X518705Y170783D01*
G01X523790Y166578D02*
X522916Y167606D01*
G01X525613Y162658D02*
X518705Y170783D01*
G01X521264Y169550D02*
X519550Y171566D01*
G01X518705Y170783D02*
X500246Y189236D01*
G01X519550Y171566D02*
X501396Y189713D01*
G01X500246Y189236D02*
Y205672D01*
G01X501396Y189713D02*
Y205672D01*
G01X542567Y188385D02*
X539686Y189379D01*
G01X540291Y190387D02*
X534388Y195876D01*
G01X539686Y189379D02*
X533238Y195374D01*
G01X534388Y195876D02*
Y200588D01*
G01X533238Y195374D02*
Y200588D01*
G01X540809Y186223D02*
X539525Y186639D01*
G01X561352Y178352D02*
X539143Y185553D01*
G01X539525Y186639D02*
X538888Y186881D01*
G01X539143Y185553D02*
X538269Y185885D01*
G01X538888Y186881D02*
X535083Y190418D01*
G01X538269Y185885D02*
X534300Y189575D01*
G01X538888Y186881D02*
X535083Y190418D01*
G01X534300Y189575D02*
X534298D01*
G01X535083Y190418D02*
X533377Y192124D01*
G01X534298Y189575D02*
X532563Y191310D01*
G01X493431Y218835D02*
X492212D01*
G01X493431D02*
X492212D01*
G01X509089Y402822D02*
X506823D01*
G01D02*
X506280Y403365D01*
G01X509089Y402822D02*
X506823D01*
G01D02*
X506280Y403365D01*
G01X522082Y453340D02*
X548586Y426836D01*
G01X562230Y414819D02*
X522649Y454400D01*
G01X484248Y460906D02*
X522082Y453340D01*
G01X522649Y454400D02*
X484248Y462079D01*
G01X520287Y452113D02*
X558379Y414021D01*
G01X520287Y452113D02*
X558379Y414021D01*
G01X547545Y423228D02*
X519720Y451053D01*
G01X484098Y459349D02*
X520287Y452113D01*
G01X519720Y451053D02*
X484098Y458176D01*
G01X514516Y447696D02*
X544908Y417304D01*
G01X544094Y416491D02*
X513949Y446636D01*
G01X484645Y453641D02*
X514516Y447696D01*
G01X513949Y446636D02*
X484645Y452468D01*
G01X522649Y454400D02*
X484248Y462079D01*
G01Y460906D02*
X522082Y453340D01*
G01X562230Y414819D02*
X522649Y454400D01*
G01X522082Y453340D02*
X548586Y426836D01*
G01X562230Y414819D02*
X522649Y454400D01*
G01X519720Y451053D02*
X484098Y458176D01*
G01Y459349D02*
X520287Y452113D01*
G01X547545Y423228D02*
X519720Y451053D01*
G01X520287Y452113D02*
X558379Y414021D01*
G01X513949Y446636D02*
X484645Y452468D01*
G01Y453641D02*
X514516Y447696D01*
G01X544094Y416491D02*
X513949Y446636D01*
G01X514516Y447696D02*
X544908Y417304D01*
G01X484833Y468802D02*
X530003Y459769D01*
G01X484833Y469975D02*
X530570Y460829D01*
G01X530003Y459769D02*
X569330Y420442D01*
G01X530570Y460829D02*
X570480Y420919D01*
G01X544542Y439939D02*
X526812Y457669D01*
G01X567680Y418428D02*
X527379Y458729D01*
G01X526812Y457669D02*
X484439Y466142D01*
G01X527379Y458729D02*
X484439Y467315D01*
G01X565080Y416347D02*
X524821Y456606D01*
G01X563930Y415870D02*
X524254Y455546D01*
G01X524821Y456606D02*
X484351Y464696D01*
G01X524254Y455546D02*
X484351Y463523D01*
G01X484833Y469975D02*
X530570Y460829D01*
G01X484833Y468802D02*
X530003Y459769D01*
G01X530570Y460829D02*
X570480Y420919D01*
G01X530003Y459769D02*
X569330Y420442D01*
G01X567680Y418428D02*
X527379Y458729D01*
G01X567680Y418428D02*
X527379Y458729D01*
G01X567680Y418428D02*
X527379Y458729D01*
G01X544542Y439939D02*
X526812Y457669D01*
G01X527379Y458729D02*
X484439Y467315D01*
G01X526812Y457669D02*
X484439Y466142D01*
G01X563930Y415870D02*
X524254Y455546D01*
G01X565080Y416347D02*
X524821Y456606D01*
G01X524254Y455546D02*
X484351Y463523D01*
G01X524821Y456606D02*
X484351Y464696D01*
G01X509089Y403972D02*
X507300D01*
G01D02*
X506847Y404425D01*
G01X509089Y403972D02*
X507300D01*
G01D02*
X506847Y404425D01*
G01X483678Y456494D02*
X517207Y449777D01*
G01Y449778D02*
X517550Y449709D01*
G01X483678Y455321D02*
X516982Y448649D01*
G01X517550Y449709D02*
X548934Y418325D01*
G01X516982Y448649D02*
X548120Y417511D01*
G01X513398Y429200D02*
X526039D01*
G01Y428050D02*
X513512D01*
G01X503199Y427160D02*
X513398Y429200D01*
G01X513512Y428050D02*
X503199Y425987D01*
G01X483678Y455321D02*
X516982Y448649D01*
G01X483678Y456494D02*
X517207Y449777D01*
G01X483678Y455321D02*
X516982Y448649D01*
G01X517207Y449778D02*
X517550Y449709D01*
G01X516982Y448649D02*
X548120Y417511D01*
G01X517550Y449709D02*
X548934Y418325D01*
G01X513512Y428050D02*
X503199Y425987D01*
G01Y427160D02*
X513398Y429200D01*
G01X526039Y428050D02*
X513512D01*
G01X513398Y429200D02*
X526039D01*
G01X511429Y407907D02*
X504059Y406428D01*
G01Y407601D02*
X511314Y409057D01*
G01X513092Y407907D02*
X511429D01*
G01X511314Y409057D02*
X513092D01*
G01X511155Y411656D02*
X504200Y410243D01*
G01X504202Y409069D02*
X511269Y410506D01*
G01X512230Y411656D02*
X511155D01*
G01D02*
X504200Y410243D01*
G01X511269Y410506D02*
X512230D01*
G01X519871Y414525D02*
X512486D01*
G01X519871Y413375D02*
X512689D01*
G01X512464Y414503D02*
X504546Y412922D01*
G01X512689Y413375D02*
X504546Y411749D01*
G01X520860Y416209D02*
X512856D01*
G01X520860Y417359D02*
X512742D01*
G01X512856Y416209D02*
X504328Y414504D01*
G01X512742Y417359D02*
X504328Y415677D01*
G01X521664Y420092D02*
X511533D01*
G01X521664Y418942D02*
X511647D01*
G01X511533Y420092D02*
X503308Y418450D01*
G01X511647Y418942D02*
X503308Y417277D01*
G01X503052Y419889D02*
X514839Y422246D01*
G01X503052Y421062D02*
X514725Y423396D01*
G01X514839Y422246D02*
X523118D01*
G01X514725Y423396D02*
X523118D01*
G01X502657Y423723D02*
X514378Y426067D01*
G01X502657Y422550D02*
X514492Y424917D01*
G01X514378Y426067D02*
X524063D01*
G01X514492Y424917D02*
X524063D01*
G01X511314Y409057D02*
X513092D01*
G01Y407907D02*
X511429D01*
G01X504059Y407601D02*
X511314Y409057D01*
G01X511429Y407907D02*
X504059Y406428D01*
G01X511269Y410506D02*
X512230D01*
G01Y411656D02*
X511155D01*
G01X504202Y409069D02*
X511269Y410506D01*
G01D02*
X512230D01*
G01X511155Y411656D02*
X504200Y410243D01*
G01X519871Y413375D02*
X512689D01*
G01X519871Y414525D02*
X512486D01*
G01X512689Y413375D02*
X504546Y411749D01*
G01X512464Y414503D02*
X504546Y412922D01*
G01X520860Y417359D02*
X512742D01*
G01X520860Y416209D02*
X512856D01*
G01X512742Y417359D02*
X504328Y415677D01*
G01X512856Y416209D02*
X504328Y414504D01*
G01X521664Y418942D02*
X511647D01*
G01X521664Y420092D02*
X511533D01*
G01X511647Y418942D02*
X503308Y417277D01*
G01X511533Y420092D02*
X503308Y418450D01*
G01X503052Y421062D02*
X514725Y423396D01*
G01X503052Y419889D02*
X514839Y422246D01*
G01X514725Y423396D02*
X523118D01*
G01X514839Y422246D02*
X523118D01*
G01X502657Y422550D02*
X514492Y424917D01*
G01X502657Y423723D02*
X514378Y426067D01*
G01X514492Y424917D02*
X524063D01*
G01X514378Y426067D02*
X524063D01*
G01X540632Y653657D02*
X538942Y644076D01*
G01X539582Y654326D02*
X537891Y644744D01*
G01X538942Y644076D02*
X537639Y643160D01*
G01X537891Y644744D02*
X537368Y644376D01*
G01X538942Y644076D02*
X537639Y643160D01*
G01D02*
X535665Y643509D01*
G01X537368Y644376D02*
X536334Y644559D01*
G01X535665Y643509D02*
X534753Y644810D01*
G01X536334Y644559D02*
X535969Y645080D01*
G01X534753Y644810D02*
X536253Y653317D01*
G01X535969Y645080D02*
X537469Y653588D01*
G01X534334Y653657D02*
X532666Y644188D01*
G01X533284Y654327D02*
X531615Y644857D01*
G01X532666Y644188D02*
X531363Y643274D01*
G01X531615Y644857D02*
X531092Y644490D01*
G01X532666Y644188D02*
X531363Y643274D01*
G01D02*
X529389Y643620D01*
G01X531092Y644490D02*
X530059Y644671D01*
G01X529389Y643620D02*
X528479Y644925D01*
G01X530059Y644671D02*
X529695Y645193D01*
G01X528479Y644925D02*
X529956Y653301D01*
G01X529695Y645193D02*
X531172Y653570D01*
G01X528036Y653639D02*
X526367Y644183D01*
G01X526986Y654309D02*
X525317Y644853D01*
G01X526367Y644183D02*
X525065Y643273D01*
G01X525317Y644853D02*
X524796Y644489D01*
G01X526367Y644183D02*
X525065Y643273D01*
G01D02*
X523094Y643620D01*
G01X524796Y644489D02*
X523764Y644671D01*
G01X523094Y643620D02*
X522183Y644924D01*
G01X523764Y644671D02*
X523399Y645193D01*
G01X522183Y644924D02*
X523661Y653299D01*
G01X523399Y645193D02*
X524877Y653568D01*
G01X521739Y653639D02*
X520073Y644166D01*
G01X520689Y654309D02*
X519022Y644837D01*
G01X520073Y644166D02*
X518767Y643257D01*
G01X519022Y644837D02*
X518498Y644472D01*
G01X520073Y644166D02*
X518767Y643257D01*
G01D02*
X516796Y643601D01*
G01X518498Y644472D02*
X517466Y644652D01*
G01X516796Y643601D02*
X515885Y644908D01*
G01X517466Y644652D02*
X517101Y645176D01*
G01X515885Y644908D02*
X517371Y653332D01*
G01X517101Y645176D02*
X518587Y653601D01*
G01X515449Y653672D02*
X513783Y644216D01*
G01X514399Y654342D02*
X512733Y644885D01*
G01X513783Y644216D02*
X512443Y643277D01*
G01X512733Y644885D02*
X512173Y644493D01*
G01X513783Y644216D02*
X512443Y643277D01*
G01D02*
X510535Y643612D01*
G01X512173Y644493D02*
X511205Y644663D01*
G01X510535Y643612D02*
X509598Y644954D01*
G01X511205Y644663D02*
X510814Y645223D01*
G01X509598Y644954D02*
X511075Y653332D01*
G01X510814Y645223D02*
X512291Y653601D01*
G01X509155Y653671D02*
X507517Y644411D01*
G01X508105Y654341D02*
X506467Y645081D01*
G01X507517Y644411D02*
X506214Y643501D01*
G01X506467Y645081D02*
X505945Y644716D01*
G01X507517Y644411D02*
X506214Y643501D01*
G01D02*
X504241Y643848D01*
G01X505945Y644716D02*
X504911Y644898D01*
G01X504241Y643848D02*
X503331Y645151D01*
G01X504911Y644898D02*
X504547Y645420D01*
G01X503331Y645151D02*
X504808Y653529D01*
G01X504547Y645420D02*
X506024Y653798D01*
G01X502889Y653867D02*
X501223Y644410D01*
G01X501839Y654536D02*
X500173Y645080D01*
G01X501223Y644410D02*
X499920Y643501D01*
G01X500173Y645080D02*
X499651Y644716D01*
G01X501223Y644410D02*
X499920Y643501D01*
G01D02*
X497946Y643847D01*
G01X499651Y644716D02*
X498616Y644898D01*
G01X497946Y643847D02*
X497035Y645151D01*
G01X498616Y644898D02*
X498251Y645420D01*
G01X497035Y645151D02*
X498521Y653576D01*
G01X498251Y645420D02*
X499737Y653844D01*
G01X496600Y653915D02*
X494933Y644443D01*
G01X495549Y654586D02*
X493883Y645113D01*
G01X494933Y644443D02*
X493630Y643534D01*
G01X493883Y645113D02*
X493361Y644749D01*
G01X494933Y644443D02*
X493630Y643534D01*
G01D02*
X491656Y643880D01*
G01X493361Y644749D02*
X492326Y644931D01*
G01X491656Y643880D02*
X490745Y645184D01*
G01X492326Y644931D02*
X491961Y645453D01*
G01X490745Y645184D02*
X492223Y653559D01*
G01X491961Y645453D02*
X493439Y653828D01*
G01X490305Y653899D02*
X488636Y644443D01*
G01X489255Y654569D02*
X487586Y645113D01*
G01X488636Y644443D02*
X487333Y643534D01*
G01X487586Y645113D02*
X487064Y644749D01*
G01X488636Y644443D02*
X487333Y643534D01*
G01D02*
X485360Y643879D01*
G01X487064Y644749D02*
X486030Y644930D01*
G01X485360Y643879D02*
X484450Y645182D01*
G01X486030Y644930D02*
X485666Y645451D01*
G01X484450Y645182D02*
X485927Y653559D01*
G01X485666Y645451D02*
X487143Y653827D01*
G01X484007Y653895D02*
X482338Y644425D01*
G01X482956Y654564D02*
X481288Y645095D01*
G01X482338Y644425D02*
X481035Y643515D01*
G01X481288Y645095D02*
X480766Y644730D01*
G01X482338Y644425D02*
X481035Y643515D01*
G01D02*
X479062Y643863D01*
G01X480766Y644730D02*
X479732Y644913D01*
G01D02*
X479369Y645435D01*
G01X478153Y645164D02*
X479653Y653672D01*
G01X479369Y645435D02*
X480869Y653942D01*
G01X539582Y654326D02*
X537891Y644744D01*
G01X540632Y653657D02*
X538942Y644076D01*
G01X537891Y644744D02*
X537368Y644376D01*
G01D02*
X536334Y644559D01*
G01X538942Y644076D02*
X537639Y643160D01*
G01X537368Y644376D02*
X536334Y644559D01*
G01X537639Y643160D02*
X535665Y643509D01*
G01X536334Y644559D02*
X535969Y645080D01*
G01X535665Y643509D02*
X534753Y644810D01*
G01X535969Y645080D02*
X537469Y653588D01*
G01X534753Y644810D02*
X536253Y653317D01*
G01X533284Y654327D02*
X531615Y644857D01*
G01X534334Y653657D02*
X532666Y644188D01*
G01X531615Y644857D02*
X531092Y644490D01*
G01D02*
X530059Y644671D01*
G01X532666Y644188D02*
X531363Y643274D01*
G01X531092Y644490D02*
X530059Y644671D01*
G01X531363Y643274D02*
X529389Y643620D01*
G01X530059Y644671D02*
X529695Y645193D01*
G01X529389Y643620D02*
X528479Y644925D01*
G01X529695Y645193D02*
X531172Y653570D01*
G01X528479Y644925D02*
X529956Y653301D01*
G01X526986Y654309D02*
X525317Y644853D01*
G01X528036Y653639D02*
X526367Y644183D01*
G01X525317Y644853D02*
X524796Y644489D01*
G01D02*
X523764Y644671D01*
G01X526367Y644183D02*
X525065Y643273D01*
G01X524796Y644489D02*
X523764Y644671D01*
G01X525065Y643273D02*
X523094Y643620D01*
G01X523764Y644671D02*
X523399Y645193D01*
G01X523094Y643620D02*
X522183Y644924D01*
G01X523399Y645193D02*
X524877Y653568D01*
G01X522183Y644924D02*
X523661Y653299D01*
G01X520689Y654309D02*
X519022Y644837D01*
G01X521739Y653639D02*
X520073Y644166D01*
G01X519022Y644837D02*
X518498Y644472D01*
G01D02*
X517466Y644652D01*
G01X520073Y644166D02*
X518767Y643257D01*
G01X518498Y644472D02*
X517466Y644652D01*
G01X518767Y643257D02*
X516796Y643601D01*
G01X517466Y644652D02*
X517101Y645176D01*
G01X516796Y643601D02*
X515885Y644908D01*
G01X517101Y645176D02*
X518587Y653601D01*
G01X515885Y644908D02*
X517371Y653332D01*
G01X514399Y654342D02*
X512733Y644885D01*
G01X515449Y653672D02*
X513783Y644216D01*
G01X512733Y644885D02*
X512173Y644493D01*
G01D02*
X511205Y644663D01*
G01X513783Y644216D02*
X512443Y643277D01*
G01X512173Y644493D02*
X511205Y644663D01*
G01X512443Y643277D02*
X510535Y643612D01*
G01X511205Y644663D02*
X510814Y645223D01*
G01X510535Y643612D02*
X509598Y644954D01*
G01X510814Y645223D02*
X512291Y653601D01*
G01X509598Y644954D02*
X511075Y653332D01*
G01X508105Y654341D02*
X506467Y645081D01*
G01X509155Y653671D02*
X507517Y644411D01*
G01X506467Y645081D02*
X505945Y644716D01*
G01D02*
X504911Y644898D01*
G01X507517Y644411D02*
X506214Y643501D01*
G01X505945Y644716D02*
X504911Y644898D01*
G01X506214Y643501D02*
X504241Y643848D01*
G01X504911Y644898D02*
X504547Y645420D01*
G01X504241Y643848D02*
X503331Y645151D01*
G01X504547Y645420D02*
X506024Y653798D01*
G01X503331Y645151D02*
X504808Y653529D01*
G01X501839Y654536D02*
X500173Y645080D01*
G01X502889Y653867D02*
X501223Y644410D01*
G01X500173Y645080D02*
X499651Y644716D01*
G01D02*
X498616Y644898D01*
G01X501223Y644410D02*
X499920Y643501D01*
G01X499651Y644716D02*
X498616Y644898D01*
G01X499920Y643501D02*
X497946Y643847D01*
G01X498616Y644898D02*
X498251Y645420D01*
G01X497946Y643847D02*
X497035Y645151D01*
G01X498251Y645420D02*
X499737Y653844D01*
G01X497035Y645151D02*
X498521Y653576D01*
G01X495549Y654586D02*
X493883Y645113D01*
G01X496600Y653915D02*
X494933Y644443D01*
G01X493883Y645113D02*
X493361Y644749D01*
G01D02*
X492326Y644931D01*
G01X494933Y644443D02*
X493630Y643534D01*
G01X493361Y644749D02*
X492326Y644931D01*
G01X493630Y643534D02*
X491656Y643880D01*
G01X492326Y644931D02*
X491961Y645453D01*
G01X491656Y643880D02*
X490745Y645184D01*
G01X491961Y645453D02*
X493439Y653828D01*
G01X490745Y645184D02*
X492223Y653559D01*
G01X489255Y654569D02*
X487586Y645113D01*
G01X490305Y653899D02*
X488636Y644443D01*
G01X487586Y645113D02*
X487064Y644749D01*
G01D02*
X486030Y644930D01*
G01X488636Y644443D02*
X487333Y643534D01*
G01X487064Y644749D02*
X486030Y644930D01*
G01X487333Y643534D02*
X485360Y643879D01*
G01X486030Y644930D02*
X485666Y645451D01*
G01X485360Y643879D02*
X484450Y645182D01*
G01X485666Y645451D02*
X487143Y653827D01*
G01X484450Y645182D02*
X485927Y653559D01*
G01X482956Y654564D02*
X481288Y645095D01*
G01X484007Y653895D02*
X482338Y644425D01*
G01X481288Y645095D02*
X480766Y644730D01*
G01D02*
X479732Y644913D01*
G01X482338Y644425D02*
X481035Y643515D01*
G01X480766Y644730D02*
X479732Y644913D01*
G01X481035Y643515D02*
X479062Y643863D01*
G01X479732Y644913D02*
X479369Y645435D01*
G01D02*
X480869Y653942D01*
G01X478153Y645164D02*
X479653Y653672D01*
G01X540882Y655237D02*
X539582Y654326D01*
G01X536253Y653317D02*
X535890Y653839D01*
G01X537469Y653588D02*
X536560Y654889D01*
G01X535890Y653839D02*
X534856Y654022D01*
G01X536560Y654889D02*
X534587Y655237D01*
G01X535890Y653839D02*
X534856Y654022D01*
G01D02*
X534334Y653657D01*
G01X534587Y655237D02*
X533284Y654327D01*
G01X529956Y653301D02*
X529592Y653822D01*
G01X531172Y653570D02*
X530262Y654873D01*
G01X529592Y653822D02*
X528558Y654003D01*
G01X530262Y654873D02*
X528289Y655218D01*
G01X529592Y653822D02*
X528558Y654003D01*
G01D02*
X528036Y653639D01*
G01X528289Y655218D02*
X526986Y654309D01*
G01X523661Y653299D02*
X523296Y653821D01*
G01X524877Y653568D02*
X523966Y654872D01*
G01X523296Y653821D02*
X522261Y654003D01*
G01X523966Y654872D02*
X521992Y655218D01*
G01X523296Y653821D02*
X522261Y654003D01*
G01D02*
X521739Y653639D01*
G01X521992Y655218D02*
X520689Y654309D01*
G01X517371Y653332D02*
X517006Y653854D01*
G01X518587Y653601D02*
X517676Y654905D01*
G01X517006Y653854D02*
X515971Y654036D01*
G01X517676Y654905D02*
X515702Y655251D01*
G01X517006Y653854D02*
X515971Y654036D01*
G01D02*
X515449Y653672D01*
G01X515702Y655251D02*
X514399Y654342D01*
G01X511075Y653332D02*
X510711Y653854D01*
G01X512291Y653601D02*
X511381Y654904D01*
G01X510711Y653854D02*
X509677Y654036D01*
G01X511381Y654904D02*
X509408Y655251D01*
G01X510711Y653854D02*
X509677Y654036D01*
G01D02*
X509155Y653671D01*
G01X509408Y655251D02*
X508105Y654341D01*
G01X504808Y653529D02*
X504417Y654089D01*
G01X506024Y653798D02*
X505087Y655140D01*
G01X504417Y654089D02*
X503449Y654259D01*
G01X505087Y655140D02*
X503179Y655475D01*
G01X504417Y654089D02*
X503449Y654259D01*
G01D02*
X502889Y653867D01*
G01X503179Y655475D02*
X501839Y654536D01*
G01X498521Y653576D02*
X498156Y654100D01*
G01X499737Y653844D02*
X498826Y655151D01*
G01X498156Y654100D02*
X497124Y654280D01*
G01X498826Y655151D02*
X496855Y655495D01*
G01X498156Y654100D02*
X497124Y654280D01*
G01D02*
X496600Y653915D01*
G01X496855Y655495D02*
X495549Y654586D01*
G01X492223Y653559D02*
X491858Y654081D01*
G01X493439Y653828D02*
X492528Y655132D01*
G01X491858Y654081D02*
X490826Y654263D01*
G01X492528Y655132D02*
X490557Y655479D01*
G01X491858Y654081D02*
X490826Y654263D01*
G01D02*
X490305Y653899D01*
G01X490557Y655479D02*
X489255Y654569D01*
G01X485927Y653559D02*
X485563Y654081D01*
G01X487143Y653827D02*
X486233Y655132D01*
G01X485563Y654081D02*
X484530Y654262D01*
G01X486233Y655132D02*
X484259Y655478D01*
G01X485563Y654081D02*
X484530Y654262D01*
G01D02*
X484007Y653895D01*
G01X484259Y655478D02*
X482956Y654564D01*
G01X479653Y653672D02*
X479288Y654193D01*
G01X480869Y653942D02*
X479957Y655243D01*
G01X479288Y654193D02*
X478254Y654376D01*
G01X479288Y654193D02*
X478254Y654376D01*
G01X540882Y655237D02*
X539582Y654326D01*
G01X540882Y655237D02*
X539582Y654326D01*
G01X537469Y653588D02*
X536560Y654889D01*
G01X536253Y653317D02*
X535890Y653839D01*
G01X536560Y654889D02*
X534587Y655237D01*
G01D02*
X533284Y654327D01*
G01X535890Y653839D02*
X534856Y654022D01*
G01X534587Y655237D02*
X533284Y654327D01*
G01X534856Y654022D02*
X534334Y653657D01*
G01X531172Y653570D02*
X530262Y654873D01*
G01X529956Y653301D02*
X529592Y653822D01*
G01X530262Y654873D02*
X528289Y655218D01*
G01D02*
X526986Y654309D01*
G01X529592Y653822D02*
X528558Y654003D01*
G01X528289Y655218D02*
X526986Y654309D01*
G01X528558Y654003D02*
X528036Y653639D01*
G01X524877Y653568D02*
X523966Y654872D01*
G01X523661Y653299D02*
X523296Y653821D01*
G01X523966Y654872D02*
X521992Y655218D01*
G01D02*
X520689Y654309D01*
G01X523296Y653821D02*
X522261Y654003D01*
G01X521992Y655218D02*
X520689Y654309D01*
G01X522261Y654003D02*
X521739Y653639D01*
G01X518587Y653601D02*
X517676Y654905D01*
G01X517371Y653332D02*
X517006Y653854D01*
G01X517676Y654905D02*
X515702Y655251D01*
G01D02*
X514399Y654342D01*
G01X517006Y653854D02*
X515971Y654036D01*
G01X515702Y655251D02*
X514399Y654342D01*
G01X515971Y654036D02*
X515449Y653672D01*
G01X512291Y653601D02*
X511381Y654904D01*
G01X511075Y653332D02*
X510711Y653854D01*
G01X511381Y654904D02*
X509408Y655251D01*
G01D02*
X508105Y654341D01*
G01X510711Y653854D02*
X509677Y654036D01*
G01X509408Y655251D02*
X508105Y654341D01*
G01X509677Y654036D02*
X509155Y653671D01*
G01X506024Y653798D02*
X505087Y655140D01*
G01X504808Y653529D02*
X504417Y654089D01*
G01X505087Y655140D02*
X503179Y655475D01*
G01D02*
X501839Y654536D01*
G01X504417Y654089D02*
X503449Y654259D01*
G01X503179Y655475D02*
X501839Y654536D01*
G01X503449Y654259D02*
X502889Y653867D01*
G01X499737Y653844D02*
X498826Y655151D01*
G01X498521Y653576D02*
X498156Y654100D01*
G01X498826Y655151D02*
X496855Y655495D01*
G01D02*
X495549Y654586D01*
G01X498156Y654100D02*
X497124Y654280D01*
G01X496855Y655495D02*
X495549Y654586D01*
G01X497124Y654280D02*
X496600Y653915D01*
G01X493439Y653828D02*
X492528Y655132D01*
G01X492223Y653559D02*
X491858Y654081D01*
G01X492528Y655132D02*
X490557Y655479D01*
G01D02*
X489255Y654569D01*
G01X491858Y654081D02*
X490826Y654263D01*
G01X490557Y655479D02*
X489255Y654569D01*
G01X490826Y654263D02*
X490305Y653899D01*
G01X487143Y653827D02*
X486233Y655132D01*
G01X485927Y653559D02*
X485563Y654081D01*
G01X486233Y655132D02*
X484259Y655478D01*
G01D02*
X482956Y654564D01*
G01X485563Y654081D02*
X484530Y654262D01*
G01X484259Y655478D02*
X482956Y654564D01*
G01X484530Y654262D02*
X484007Y653895D01*
G01X480869Y653942D02*
X479957Y655243D01*
G01X479653Y653672D02*
X479288Y654193D01*
G01D02*
X478254Y654376D01*
G01X552403Y148398D02*
X582618Y149515D01*
G01X552606Y149557D02*
X582732Y150671D01*
G01X582618Y149515D02*
X647393Y134084D01*
G01X582732Y150671D02*
X647565Y135226D01*
G01X552884Y146304D02*
X577829Y147486D01*
G01X552683Y145143D02*
X577720Y146329D01*
G01X577829Y147486D02*
X639727Y132702D01*
G01X577720Y146329D02*
X639547Y131562D01*
G01X552606Y149557D02*
X582732Y150671D01*
G01X552403Y148398D02*
X582618Y149515D01*
G01X582732Y150671D02*
X647565Y135226D01*
G01X582618Y149515D02*
X647393Y134084D01*
G01X552683Y145143D02*
X577720Y146329D01*
G01X552884Y146304D02*
X577829Y147486D01*
G01X577720Y146329D02*
X639547Y131562D01*
G01X577829Y147486D02*
X639727Y132702D01*
G01X612541Y152791D02*
X584681Y158275D01*
G01X613216Y149972D02*
X583594Y155633D01*
G01X613325Y151122D02*
X583679Y156788D01*
G01X583594Y155633D02*
X554154Y154393D01*
G01X583679Y156788D02*
X554349Y155553D01*
G01X610830Y148647D02*
X582932Y154028D01*
G01X610658Y147508D02*
X582853Y152872D01*
G01X582932Y154028D02*
X554201Y152498D01*
G01X582853Y152871D02*
X554013Y151336D01*
G01X612541Y152791D02*
X584681Y158275D01*
G01X613325Y151122D02*
X583679Y156788D01*
G01X613216Y149972D02*
X583594Y155633D01*
G01X583679Y156788D02*
X554349Y155553D01*
G01X583594Y155633D02*
X554154Y154393D01*
G01X610658Y147508D02*
X582853Y152872D01*
G01X610830Y148647D02*
X582932Y154028D01*
G01X582853Y152871D02*
X554013Y151336D01*
G01X582932Y154028D02*
X554201Y152498D01*
G01X613783Y165691D02*
X577173Y174276D01*
G01X613832Y166861D02*
X577319Y175423D01*
G01X577173Y174276D02*
X560427Y174659D01*
G01X577319Y175423D02*
X565066Y175703D01*
G01X577173Y174276D02*
X560427Y174659D01*
G01X562516Y175763D02*
X560633Y175805D01*
G01D02*
X557443Y176890D01*
G01X555029Y177712D02*
X553699Y178164D01*
G01X551285Y178986D02*
X549732Y179514D01*
G01X547317Y180337D02*
X546039Y180771D01*
G01X543624Y181594D02*
X542347Y182028D01*
G01X613657Y163136D02*
X578682Y170999D01*
G01X613657Y163136D02*
X578682Y170999D01*
G01X613721Y164301D02*
X578800Y172152D01*
G01X578682Y170999D02*
X561621Y170708D01*
G01X578800Y172152D02*
X569082Y171989D01*
G01X578682Y170999D02*
X561621Y170708D01*
G01X566756Y171949D02*
X565406Y171925D01*
G01X578682Y170999D02*
X561621Y170708D01*
G01D02*
X560473Y170710D01*
G01X563080Y171885D02*
X561612Y171859D01*
G01X561621Y170708D02*
X560473Y170710D01*
G01D02*
X560281D01*
G01X561612Y171859D02*
X560474Y171860D01*
G01D02*
X556244Y173302D01*
G01X553829Y174125D02*
X552552Y174560D01*
G01X550137Y175384D02*
X548860Y175819D01*
G01X546445Y176643D02*
X545168Y177078D01*
G01X542753Y177902D02*
X541476Y178337D01*
G01X581984Y168566D02*
X613647Y161658D01*
G01X613587Y160493D02*
X581866Y167414D01*
G01X558133Y168331D02*
X559482Y168344D01*
G01X562033Y168370D02*
X563382Y168383D01*
G01X565933Y168409D02*
X581984Y168566D01*
G01X581866Y167414D02*
X557925Y167178D01*
G01X540042Y175279D02*
X541302Y174795D01*
G01X543683Y173880D02*
X544943Y173397D01*
G01X547324Y172481D02*
X548584Y171998D01*
G01X550965Y171083D02*
X552225Y170600D01*
G01X554606Y169685D02*
X558133Y168331D01*
G01X613102Y157932D02*
X582999Y164339D01*
G01X613172Y159093D02*
X583105Y165493D01*
G01X582999Y164339D02*
X556320Y163621D01*
G01X583105Y165493D02*
X564326Y164988D01*
G01X582999Y164339D02*
X556320Y163621D01*
G01X561776Y164919D02*
X560427Y164883D01*
G01X582999Y164339D02*
X556320Y163621D01*
G01X557877Y164814D02*
X556528Y164778D01*
G01D02*
X554065Y165769D01*
G01X551699Y166723D02*
X550445Y167226D01*
G01X548080Y168179D02*
X546826Y168683D01*
G01X544461Y169635D02*
X543209Y170139D01*
G01X612845Y156548D02*
X586429Y161800D01*
G01D02*
X586416Y161803D01*
G01D02*
X586399Y161806D01*
G01X612725Y155399D02*
X586205Y160671D01*
G01X612845Y156548D02*
X586429Y161800D01*
G01X586399Y161806D02*
X581918Y162700D01*
G01X586205Y160671D02*
X586187Y160675D01*
G01X612845Y156548D02*
X586429Y161800D01*
G01X586399Y161806D02*
X581918Y162700D01*
G01X586186Y160675D02*
X586174Y160677D01*
G01X586429Y161800D02*
X586416Y161803D01*
G01D02*
X586399Y161806D01*
G01D02*
X581918Y162700D01*
G01D02*
X581083Y162654D01*
G01X586174Y160677D02*
X581836Y161543D01*
G01X586399Y161806D02*
X581918Y162700D01*
G01D02*
X581083Y162654D01*
G01D02*
X555872Y161820D01*
G01X581836Y161543D02*
X581134Y161505D01*
G01X581918Y162700D02*
X581083Y162654D01*
G01D02*
X555872Y161820D01*
G01X581134Y161505D02*
X555674Y160662D01*
G01X612660Y153940D02*
X584794Y159425D01*
G01D02*
X581393D01*
G01X584681Y158275D02*
X581418D01*
G01X581393Y159425D02*
X555011Y158597D01*
G01X581418Y158275D02*
X554805Y157439D01*
G01X614699Y176953D02*
X567262Y187690D01*
G01X614596Y178156D02*
X567612Y188790D01*
G01X567262Y187690D02*
X548857Y195315D01*
G01X567612Y188790D02*
X561034Y191515D01*
G01X567262Y187690D02*
X548857Y195315D01*
G01X558926Y192389D02*
X556727Y193300D01*
G01X567262Y187690D02*
X548857Y195315D01*
G01X554620Y194174D02*
X553622Y194587D01*
G01X567262Y187690D02*
X548857Y195315D01*
G01X551515Y195460D02*
X549509Y196291D01*
G01X548857Y195315D02*
X544286Y199886D01*
G01X549509Y196291D02*
X548207Y197593D01*
G01X548857Y195315D02*
X544286Y199886D01*
G01X547570Y199207D02*
X546593D01*
G01X548857Y195315D02*
X544286Y199886D01*
G01X546593Y199207D02*
X545100Y200700D01*
G01X614377Y175318D02*
X568564Y185854D01*
G01X614477Y174114D02*
X568282Y184738D01*
G01X568564Y185854D02*
X556243Y189248D01*
G01X554044Y189854D02*
X553177Y190093D01*
G01X550978Y190699D02*
X550111Y190938D01*
G01X547912Y191544D02*
X546800Y191850D01*
G01D02*
X543676Y192711D01*
G01X568282Y184738D02*
X543027Y191696D01*
G01X543676Y192711D02*
X543294Y193161D01*
G01X543027Y191696D02*
X542557Y192251D01*
G01X543293Y193168D02*
X541620Y194019D01*
G01X542557Y192251D02*
X541116Y192984D01*
G01X612959Y171790D02*
X568385Y181657D01*
G01X613197Y172916D02*
X568587Y182791D01*
G01X568385Y181657D02*
X558005Y183059D01*
G01X568587Y182791D02*
X558272Y184184D01*
G01X558005Y183059D02*
X542567Y188384D01*
G01X558272Y184184D02*
X556996Y184624D01*
G01X558005Y183059D02*
X542567Y188384D01*
G01X554585Y185456D02*
X553309Y185896D01*
G01X558005Y183059D02*
X542567Y188384D01*
G01X550898Y186728D02*
X549429Y187234D01*
G01X558005Y183059D02*
X542567Y188384D01*
G01X547017Y188067D02*
X546800Y188142D01*
G01X558005Y183059D02*
X542567Y188384D01*
G01X546800Y188142D02*
X545353Y188641D01*
G01X542941Y189473D02*
X540291Y190387D01*
G01X614152Y168312D02*
X574183Y177683D01*
G01X614056Y169516D02*
X574346Y178827D01*
G01X574183Y177683D02*
X561352Y178352D01*
G01X574346Y178827D02*
X565458Y179290D01*
G01X574183Y177683D02*
X561352Y178352D01*
G01X562911Y179423D02*
X561563Y179493D01*
G01D02*
X558075Y180624D01*
G01X555649Y181411D02*
X554365Y181827D01*
G01X551939Y182614D02*
X550655Y183030D01*
G01X548229Y183817D02*
X546945Y184233D01*
G01X544519Y185020D02*
X543235Y185436D01*
G01X613832Y166861D02*
X577319Y175423D01*
G01X613783Y165691D02*
X577173Y174276D01*
G01X577319Y175423D02*
X565066Y175703D01*
G01X562516Y175763D02*
X560633Y175805D01*
G01X577173Y174276D02*
X560427Y174659D01*
G01X560633Y175805D02*
X557443Y176890D01*
G01X555029Y177712D02*
X553699Y178164D01*
G01X551285Y178986D02*
X549732Y179514D01*
G01X547317Y180337D02*
X546039Y180771D01*
G01X543624Y181594D02*
X542347Y182028D01*
G01X613721Y164301D02*
X578800Y172152D01*
G01X613657Y163136D02*
X578682Y170999D01*
G01X578800Y172152D02*
X569082Y171989D01*
G01X566756Y171949D02*
X565406Y171925D01*
G01X563080Y171885D02*
X561612Y171859D01*
G01X578682Y170999D02*
X561621Y170708D01*
G01X563080Y171885D02*
X561612Y171859D01*
G01D02*
X560474Y171860D01*
G01X561621Y170708D02*
X560473Y170710D01*
G01X561612Y171859D02*
X560474Y171860D01*
G01X560473Y170710D02*
X560281D01*
G01X561612Y171859D02*
X560474Y171860D01*
G01D02*
X556244Y173302D01*
G01X553829Y174125D02*
X552552Y174560D01*
G01X550137Y175384D02*
X548860Y175819D01*
G01X546445Y176643D02*
X545168Y177078D01*
G01X542753Y177902D02*
X541476Y178337D01*
G01X540042Y175279D02*
X541302Y174795D01*
G01X543683Y173880D02*
X544943Y173397D01*
G01X547324Y172481D02*
X548584Y171998D01*
G01X550965Y171083D02*
X552225Y170600D01*
G01X554606Y169685D02*
X558133Y168331D01*
G01X581866Y167414D02*
X557925Y167178D01*
G01X558133Y168331D02*
X559482Y168344D01*
G01X581866Y167414D02*
X557925Y167178D01*
G01X562033Y168370D02*
X563382Y168383D01*
G01X581866Y167414D02*
X557925Y167178D01*
G01X565933Y168409D02*
X581984Y168566D01*
G01X613587Y160493D02*
X581866Y167414D01*
G01X581984Y168566D02*
X613647Y161658D01*
G01X613172Y159093D02*
X583105Y165493D01*
G01X613102Y157932D02*
X582999Y164339D01*
G01X583105Y165493D02*
X564326Y164988D01*
G01X561776Y164919D02*
X560427Y164883D01*
G01X557877Y164814D02*
X556528Y164778D01*
G01X582999Y164339D02*
X556320Y163621D01*
G01X556528Y164778D02*
X554065Y165769D01*
G01X551699Y166723D02*
X550445Y167226D01*
G01X548080Y168179D02*
X546826Y168683D01*
G01X544461Y169635D02*
X543209Y170139D01*
G01X612725Y155399D02*
X586205Y160671D01*
G01D02*
X586187Y160675D01*
G01X586186D02*
X586174Y160677D01*
G01X612845Y156548D02*
X586429Y161800D01*
G01X612725Y155399D02*
X586205Y160671D01*
G01X586174Y160677D02*
X581836Y161543D01*
G01X586429Y161800D02*
X586416Y161803D01*
G01X612725Y155399D02*
X586205Y160671D01*
G01X586174Y160677D02*
X581836Y161543D01*
G01X586416Y161803D02*
X586399Y161806D01*
G01X586205Y160671D02*
X586187Y160675D01*
G01X586186D02*
X586174Y160677D01*
G01D02*
X581836Y161543D01*
G01D02*
X581134Y161505D01*
G01X586399Y161806D02*
X581918Y162700D01*
G01X586174Y160677D02*
X581836Y161543D01*
G01D02*
X581134Y161505D01*
G01D02*
X555674Y160662D01*
G01X581918Y162700D02*
X581083Y162654D01*
G01X581836Y161543D02*
X581134Y161505D01*
G01D02*
X555674Y160662D01*
G01X581083Y162654D02*
X555872Y161820D01*
G01X612660Y153940D02*
X584794Y159425D01*
G01X584681Y158275D02*
X581418D01*
G01X584794Y159425D02*
X581393D01*
G01X581418Y158275D02*
X554805Y157439D01*
G01X581393Y159425D02*
X555011Y158597D01*
G01X614419Y180927D02*
X574174Y189967D01*
G01X614522Y179725D02*
X573825Y188866D01*
G01X574174Y189967D02*
X571344Y191139D01*
G01X569237Y192012D02*
X568406Y192356D01*
G01X566298Y193229D02*
X565467Y193573D01*
G01X563359Y194446D02*
X562528Y194790D01*
G01X560420Y195663D02*
X559589Y196007D01*
G01X557481Y196880D02*
X555395Y197744D01*
G01X573825Y188866D02*
X554743Y196768D01*
G01X555395Y197744D02*
X552139Y201000D01*
G01X554743Y196768D02*
X551200Y200311D01*
G01X614596Y178156D02*
X567612Y188790D01*
G01X614699Y176953D02*
X567262Y187690D01*
G01X567612Y188790D02*
X561034Y191515D01*
G01X558926Y192389D02*
X556727Y193300D01*
G01X554620Y194174D02*
X553622Y194587D01*
G01X551515Y195460D02*
X549509Y196291D01*
G01X567262Y187690D02*
X548857Y195315D01*
G01X549509Y196291D02*
X548207Y197593D01*
G01X547570Y199207D02*
X546593D01*
G01D02*
X545100Y200700D01*
G01X548857Y195315D02*
X544286Y199886D01*
G01X614477Y174114D02*
X568282Y184738D01*
G01X614377Y175318D02*
X568564Y185854D01*
G01X568282Y184738D02*
X543027Y191696D01*
G01X568564Y185854D02*
X556243Y189248D01*
G01X568282Y184738D02*
X543027Y191696D01*
G01X554044Y189854D02*
X553177Y190093D01*
G01X568282Y184738D02*
X543027Y191696D01*
G01X550978Y190699D02*
X550111Y190938D01*
G01X568282Y184738D02*
X543027Y191696D01*
G01X547912Y191544D02*
X546800Y191850D01*
G01X568282Y184738D02*
X543027Y191696D01*
G01X546800Y191850D02*
X543676Y192711D01*
G01X543027Y191696D02*
X542557Y192251D01*
G01X543676Y192711D02*
X543294Y193161D01*
G01X542557Y192251D02*
X541116Y192984D01*
G01X543293Y193168D02*
X541620Y194019D01*
G01X613197Y172916D02*
X568587Y182791D01*
G01X612959Y171790D02*
X568385Y181657D01*
G01X568587Y182791D02*
X558272Y184184D01*
G01X568385Y181657D02*
X558005Y183059D01*
G01X558272Y184184D02*
X556996Y184624D01*
G01X554585Y185456D02*
X553309Y185896D01*
G01X550898Y186728D02*
X549429Y187234D01*
G01X547017Y188067D02*
X546800Y188142D01*
G01D02*
X545353Y188641D01*
G01X558005Y183059D02*
X542567Y188384D01*
G01X542941Y189473D02*
X540291Y190387D01*
G01X614056Y169516D02*
X574346Y178827D01*
G01X614152Y168312D02*
X574183Y177683D01*
G01X574346Y178827D02*
X565458Y179290D01*
G01X562911Y179423D02*
X561563Y179493D01*
G01X574183Y177683D02*
X561352Y178352D01*
G01X561563Y179493D02*
X558075Y180624D01*
G01X555649Y181411D02*
X554365Y181827D01*
G01X551939Y182614D02*
X550655Y183030D01*
G01X548229Y183817D02*
X546945Y184233D01*
G01X544519Y185020D02*
X543235Y185436D01*
G01X613415Y193348D02*
X598824Y196593D01*
G01X613310Y194550D02*
X599307Y197664D01*
G01X598824Y196593D02*
X589869Y203115D01*
G01X599307Y197664D02*
X590740Y203904D01*
G01X589869Y203115D02*
X588799Y204938D01*
G01X590740Y203904D02*
X589661Y205743D01*
G01X588799Y204938D02*
X567112Y219727D01*
G01X589661Y205743D02*
X567663Y220744D01*
G01X613796Y190663D02*
X597037Y194385D01*
G01X613691Y191865D02*
X597525Y195455D01*
G01X597037Y194385D02*
X580791Y206401D01*
G01X597525Y195455D02*
X581435Y207356D01*
G01X580791Y206401D02*
X573300Y210999D01*
G01X581435Y207356D02*
X573902Y211979D01*
G01X573300Y210998D02*
X567946Y214284D01*
G01X571949Y213177D02*
X568462Y215317D01*
G01X567946Y214284D02*
X566373Y214924D01*
G01X568462Y215317D02*
X566806Y215990D01*
G01X613686Y189140D02*
X595244Y193351D01*
G01X613787Y187937D02*
X594939Y192241D01*
G01X595244Y193351D02*
X591438Y194581D01*
G01X594939Y192241D02*
X591040Y193501D01*
G01X591438Y194581D02*
X578484Y199953D01*
G01X591040Y193501D02*
X577914Y198944D01*
G01X578484Y199953D02*
X572814Y204130D01*
G01X577914Y198944D02*
X571747Y203486D01*
G01X572814Y204130D02*
X572741Y204614D01*
G01X571747Y203486D02*
X571674Y203971D01*
G01X572741Y204614D02*
X568362Y207841D01*
G01X571674Y203971D02*
X567700Y206900D01*
G01X613871Y186381D02*
X592257Y191314D01*
G01X613972Y185178D02*
X591907Y190214D01*
G01X592257Y191314D02*
X571391Y199952D01*
G01X569265Y200832D02*
X568434Y201176D01*
G01X566308Y202056D02*
X565477Y202400D01*
G01X591907Y190214D02*
X565248Y201250D01*
G01X566308Y202056D02*
X565477Y202400D01*
G01D02*
X564739D01*
G01X565248Y201250D02*
X564510D01*
G01X565477Y202400D02*
X564739D01*
G01D02*
X561428Y203773D01*
G01X564510Y201250D02*
X560776Y202797D01*
G01X561428Y203773D02*
X560400Y204800D01*
G01X560776Y202797D02*
X559923Y203650D01*
G01X561428Y203773D02*
X560400Y204800D01*
G01D02*
X558687D01*
G01X559923Y203650D02*
X558687D01*
G01X614483Y182595D02*
X587354Y188689D01*
G01X614380Y183798D02*
X587703Y189790D01*
G01X587354Y188689D02*
X575375Y193650D01*
G01X587703Y189790D02*
X575604Y194800D01*
G01X575375Y193650D02*
X573320D01*
G01X575604Y194800D02*
X573549D01*
G01X573320Y193650D02*
X558960Y199596D01*
G01X573549Y194800D02*
X572073Y195411D01*
G01X573320Y193650D02*
X558960Y199596D01*
G01X569966Y196284D02*
X568428Y196921D01*
G01X573320Y193650D02*
X558960Y199596D01*
G01X566320Y197794D02*
X565489Y198138D01*
G01X573320Y193650D02*
X558960Y199596D01*
G01X563381Y199011D02*
X562550Y199355D01*
G01X573320Y193650D02*
X558960Y199596D01*
G01X560443Y200228D02*
X559612Y200572D01*
G01X558960Y199596D02*
X558277Y200279D01*
G01X559612Y200572D02*
X559091Y201093D01*
G01X614522Y179725D02*
X573825Y188866D01*
G01X614419Y180927D02*
X574174Y189967D01*
G01X573825Y188866D02*
X554743Y196768D01*
G01X574174Y189967D02*
X571344Y191139D01*
G01X573825Y188866D02*
X554743Y196768D01*
G01X569237Y192012D02*
X568406Y192356D01*
G01X573825Y188866D02*
X554743Y196768D01*
G01X566298Y193229D02*
X565467Y193573D01*
G01X573825Y188866D02*
X554743Y196768D01*
G01X563359Y194446D02*
X562528Y194790D01*
G01X573825Y188866D02*
X554743Y196768D01*
G01X560420Y195663D02*
X559589Y196007D01*
G01X573825Y188866D02*
X554743Y196768D01*
G01X557481Y196880D02*
X555395Y197744D01*
G01X554743Y196768D02*
X551200Y200311D01*
G01X555395Y197744D02*
X552139Y201000D01*
G01X613310Y194550D02*
X599307Y197664D01*
G01X613415Y193348D02*
X598824Y196593D01*
G01X599307Y197664D02*
X590740Y203904D01*
G01X598824Y196593D02*
X589869Y203115D01*
G01X590740Y203904D02*
X589661Y205743D01*
G01X589869Y203115D02*
X588799Y204938D01*
G01X589661Y205743D02*
X567663Y220744D01*
G01X588799Y204938D02*
X567112Y219727D01*
G01X613691Y191865D02*
X597525Y195455D01*
G01X613796Y190663D02*
X597037Y194385D01*
G01X597525Y195455D02*
X581435Y207356D01*
G01X597037Y194385D02*
X580791Y206401D01*
G01X581435Y207356D02*
X573902Y211979D01*
G01X580791Y206401D02*
X573300Y210999D01*
G01X571949Y213177D02*
X568462Y215317D01*
G01X573300Y210998D02*
X567946Y214284D01*
G01X568462Y215317D02*
X566806Y215990D01*
G01X567946Y214284D02*
X566373Y214924D01*
G01X613787Y187937D02*
X594939Y192241D01*
G01X613686Y189140D02*
X595244Y193351D01*
G01X594939Y192241D02*
X591040Y193501D01*
G01X595244Y193351D02*
X591438Y194581D01*
G01X591040Y193501D02*
X577914Y198944D01*
G01X591438Y194581D02*
X578484Y199953D01*
G01X577914Y198944D02*
X571747Y203486D01*
G01X578484Y199953D02*
X572814Y204130D01*
G01X571747Y203486D02*
X571674Y203971D01*
G01X572814Y204130D02*
X572741Y204614D01*
G01X571674Y203971D02*
X567700Y206900D01*
G01X572741Y204614D02*
X568362Y207841D01*
G01X613972Y185178D02*
X591907Y190214D01*
G01X613871Y186381D02*
X592257Y191314D01*
G01X591907Y190214D02*
X565248Y201250D01*
G01X592257Y191314D02*
X571391Y199952D01*
G01X591907Y190214D02*
X565248Y201250D01*
G01X569265Y200832D02*
X568434Y201176D01*
G01X591907Y190214D02*
X565248Y201250D01*
G01D02*
X564510D01*
G01X566308Y202056D02*
X565477Y202400D01*
G01X565248Y201250D02*
X564510D01*
G01D02*
X560776Y202797D01*
G01X565477Y202400D02*
X564739D01*
G01X564510Y201250D02*
X560776Y202797D01*
G01X564739Y202400D02*
X561428Y203773D01*
G01X560776Y202797D02*
X559923Y203650D01*
G01D02*
X558687D01*
G01X561428Y203773D02*
X560400Y204800D01*
G01X559923Y203650D02*
X558687D01*
G01X560400Y204800D02*
X558687D01*
G01X614380Y183798D02*
X587703Y189790D01*
G01X614483Y182595D02*
X587354Y188689D01*
G01X587703Y189790D02*
X575604Y194800D01*
G01X587354Y188689D02*
X575375Y193650D01*
G01X575604Y194800D02*
X573549D01*
G01X575375Y193650D02*
X573320D01*
G01X573549Y194800D02*
X572073Y195411D01*
G01X569966Y196284D02*
X568428Y196921D01*
G01X566320Y197794D02*
X565489Y198138D01*
G01X563381Y199011D02*
X562550Y199355D01*
G01X560443Y200228D02*
X559612Y200572D01*
G01X573320Y193650D02*
X558960Y199596D01*
G01X559612Y200572D02*
X559091Y201093D01*
G01X558960Y199596D02*
X558277Y200279D01*
G01X578836Y236412D02*
X583178D01*
G01X578836Y237562D02*
X583245D01*
G01X583178Y236412D02*
X585505Y236141D01*
G01X583245Y237562D02*
X585531Y237296D01*
G01X585505Y236141D02*
X587784Y236303D01*
G01X585531Y237297D02*
X587245Y237418D01*
G01X587784Y236303D02*
X611402Y262131D01*
G01X587245Y237418D02*
X588234Y238500D01*
G01X587784Y236303D02*
X611402Y262131D01*
G01X588234Y238500D02*
X610364Y262702D01*
G01X560999Y276071D02*
X558113D01*
G01Y277221D02*
X560522D01*
G01X563600Y278672D02*
X560999Y276071D01*
G01X560522Y277221D02*
X562896Y279595D01*
G01X583553Y290045D02*
X563600Y278672D01*
G01X562896Y279595D02*
X565594Y281132D01*
G01X583553Y290045D02*
X563600Y278672D01*
G01X579055Y240400D02*
X585550D01*
G01X579055Y239250D02*
X586048D01*
G01X585550Y240400D02*
X594938Y250400D01*
G01D02*
X596064Y251600D01*
G01X586048Y239250D02*
X596515Y250400D01*
G01X594938D02*
X596064Y251600D01*
G01D02*
X608283Y264616D01*
G01X596515Y250400D02*
X597642Y251600D01*
G01X596064D02*
X608283Y264616D01*
G01X597642Y251600D02*
X609318Y264038D01*
G01X565805Y272182D02*
X567616D01*
G01X565805Y271032D02*
X567972D01*
G01X567616Y272182D02*
X586711Y285237D01*
G01X567972Y271032D02*
X587516Y284394D01*
G01X578836Y237562D02*
X583245D01*
G01X578836Y236412D02*
X583178D01*
G01X583245Y237562D02*
X585531Y237296D01*
G01X583178Y236412D02*
X585505Y236141D01*
G01X585531Y237297D02*
X587245Y237418D01*
G01X585505Y236141D02*
X587784Y236303D01*
G01X587245Y237418D02*
X588234Y238500D01*
G01D02*
X610364Y262702D01*
G01X587784Y236303D02*
X611402Y262131D01*
G01X567649Y275660D02*
X570578Y278589D01*
G01X566835Y276474D02*
X569866Y279505D01*
G01X570578Y278589D02*
X586058Y287779D01*
G01X569866Y279505D02*
X585275Y288653D01*
G01X562896Y279595D02*
X565594Y281132D01*
G01X583553Y290045D02*
X563600Y278672D01*
G01X560522Y277221D02*
X562896Y279595D01*
G01X563600Y278672D02*
X560999Y276071D01*
G01X558113Y277221D02*
X560522D01*
G01X560999Y276071D02*
X558113D01*
G01X579055Y239250D02*
X586048D01*
G01X579055Y240400D02*
X585550D01*
G01X586048Y239250D02*
X596515Y250400D01*
G01X585550Y240400D02*
X594938Y250400D01*
G01X586048Y239250D02*
X596515Y250400D01*
G01D02*
X597642Y251600D01*
G01X594938Y250400D02*
X596064Y251600D01*
G01X596515Y250400D02*
X597642Y251600D01*
G01D02*
X609318Y264038D01*
G01X596064Y251600D02*
X608283Y264616D01*
G01X573201Y252105D02*
X579429D01*
G01X573201Y253255D02*
X579188D01*
G01X579429Y252105D02*
X582529Y253462D01*
G01X579188Y253255D02*
X581842Y254417D01*
G01X582529Y253462D02*
X601800Y274731D01*
G01X581842Y254417D02*
X600762Y275299D01*
G01D02*
X618357Y340174D01*
G01X565805Y271032D02*
X567972D01*
G01X565805Y272182D02*
X567616D01*
G01X567972Y271032D02*
X587516Y284394D01*
G01X567616Y272182D02*
X586711Y285237D01*
G01X567112Y219727D02*
X566022Y220181D01*
G01X567663Y220744D02*
X566464Y221243D01*
G01X567663Y220744D02*
X566464Y221243D01*
G01X567112Y219727D02*
X566022Y220181D01*
G01X566835Y276474D02*
X569866Y279505D01*
G01X567649Y275660D02*
X570578Y278589D01*
G01X569866Y279505D02*
X585275Y288653D01*
G01X570578Y278589D02*
X586058Y287779D01*
G01X580378Y242425D02*
X584722D01*
G01X580378Y243575D02*
X584235D01*
G01X584722Y242425D02*
X607108Y265493D01*
G01X584235Y243575D02*
X606075Y266081D01*
G01X584469Y248019D02*
X589758Y253308D01*
G01X585282Y247205D02*
X590585Y252508D01*
G01X589758Y253308D02*
X604191Y268730D01*
G01X590585Y252508D02*
X605227Y268153D01*
G01X569660Y248425D02*
X580285D01*
G01X569660Y249575D02*
X579984D01*
G01X580285Y248425D02*
X585645Y251428D01*
G01X579984Y249575D02*
X584930Y252347D01*
G01X585645Y251428D02*
X585808Y251600D01*
G01D02*
X603068Y269795D01*
G01X584930Y252347D02*
X602034Y270376D01*
G01X573201Y253255D02*
X579188D01*
G01X573201Y252105D02*
X579429D01*
G01X579188Y253255D02*
X581842Y254417D01*
G01X579429Y252105D02*
X582529Y253462D01*
G01X581842Y254417D02*
X600762Y275299D01*
G01X582529Y253462D02*
X601800Y274731D01*
G01X600762Y275299D02*
X618357Y340174D01*
G01X574021Y255539D02*
X576762D01*
G01X574021Y256689D02*
X576450D01*
G01X576762Y255539D02*
X584541Y260079D01*
G01X576450Y256689D02*
X583774Y260964D01*
G01X584541Y260079D02*
X589713Y266585D01*
G01X583774Y260964D02*
X588803Y267289D01*
G01X589713Y266585D02*
X601091Y281704D01*
G01X588803Y267289D02*
X600039Y282219D01*
G01X574489Y265750D02*
X575513D01*
G01X574489Y264600D02*
X575746D01*
G01X574489Y265750D02*
X575513D01*
G01D02*
X583757Y269221D01*
G01X575746Y264600D02*
X584490Y268281D01*
G01X583757Y269221D02*
X599626Y290307D01*
G01X584490Y268281D02*
X600678Y289792D01*
G01X573617Y267279D02*
X574864D01*
G01D02*
X583204Y272153D01*
G01X573617Y268429D02*
X574552D01*
G01X574864Y267279D02*
X583204Y272153D01*
G01X574552Y268429D02*
X582423Y273030D01*
G01X583204Y272153D02*
X598976Y293111D01*
G01X582423Y273030D02*
X597924Y293626D01*
G01X580378Y243575D02*
X584235D01*
G01X580378Y242425D02*
X584722D01*
G01X584235Y243575D02*
X606075Y266081D01*
G01X584722Y242425D02*
X607108Y265493D01*
G01X585282Y247205D02*
X590585Y252508D01*
G01X584469Y248019D02*
X589758Y253308D01*
G01X590585Y252508D02*
X605227Y268153D01*
G01X589758Y253308D02*
X604191Y268730D01*
G01X569660Y249575D02*
X579984D01*
G01X569660Y248425D02*
X580285D01*
G01X579984Y249575D02*
X584930Y252347D01*
G01X580285Y248425D02*
X585645Y251428D01*
G01X584930Y252347D02*
X602034Y270376D01*
G01X585645Y251428D02*
X585808Y251600D01*
G01X584930Y252347D02*
X602034Y270376D01*
G01X585808Y251600D02*
X603068Y269795D01*
G01X574021Y256689D02*
X576450D01*
G01X574021Y255539D02*
X576762D01*
G01X576450Y256689D02*
X583774Y260964D01*
G01X576762Y255539D02*
X584541Y260079D01*
G01X583774Y260964D02*
X588803Y267289D01*
G01X584541Y260079D02*
X589713Y266585D01*
G01X588803Y267289D02*
X600039Y282219D01*
G01X589713Y266585D02*
X601091Y281704D01*
G01X574489Y264600D02*
X575746D01*
G01D02*
X584490Y268281D01*
G01X574489Y265750D02*
X575513D01*
G01X575746Y264600D02*
X584490Y268281D01*
G01X575513Y265750D02*
X583757Y269221D01*
G01X584490Y268281D02*
X600678Y289792D01*
G01X583757Y269221D02*
X599626Y290307D01*
G01X573617Y268429D02*
X574552D01*
G01X573617Y267279D02*
X574864D01*
G01X573617Y268429D02*
X574552D01*
G01D02*
X582423Y273030D01*
G01X574864Y267279D02*
X583204Y272153D01*
G01X582423Y273030D02*
X597924Y293626D01*
G01X583204Y272153D02*
X598976Y293111D01*
G01X567549Y282248D02*
X582776Y290927D01*
G01X594161Y304140D02*
X583553Y290045D01*
G01X582776Y290927D02*
X593109Y304655D01*
G01X605717Y346766D02*
X594161Y304140D01*
G01X593109Y304655D02*
X604673Y347314D01*
G01X592093Y306112D02*
X603452Y347994D01*
G01X602408Y348542D02*
X591059Y306696D01*
G01X580311Y293787D02*
X592093Y306112D01*
G01X591059Y306696D02*
X579633Y294743D01*
G01X570425Y289305D02*
X580311Y293787D01*
G01X579633Y294743D02*
X569797Y290283D01*
G01X566012Y285469D02*
X570425Y289305D01*
G01X569797Y290283D02*
X565228Y286312D01*
G01X562445Y281922D02*
X566012Y285469D01*
G01X565228Y286312D02*
X561970Y283072D01*
G01X560927Y281922D02*
X562445D01*
G01D02*
X566012Y285469D01*
G01X561970Y283072D02*
X560927D01*
G01X566501Y305171D02*
X572874D01*
G01X566501Y304021D02*
X573093D01*
G01X572874Y305171D02*
X573925Y305586D01*
G01X573093Y304021D02*
X574582Y304609D01*
G01X573925Y305586D02*
X582892Y314966D01*
G01X574582Y304609D02*
X583926Y314382D01*
G01X582892Y314966D02*
X593287Y353297D01*
G01X583926Y314382D02*
X594331Y352749D01*
G01X571079Y307041D02*
X572312D01*
G01D02*
X581896Y316493D01*
G01X571079Y308191D02*
X571840D01*
G01X572312Y307041D02*
X581896Y316493D01*
G01X571840Y308191D02*
X580867Y317094D01*
G01X581896Y316493D02*
X592056Y353946D01*
G01X580867Y317094D02*
X591012Y354494D01*
G01X586711Y285237D02*
X596613Y298394D01*
G01X587516Y284394D02*
X597665Y297879D01*
G01X596613Y298394D02*
X609238Y344940D01*
G01X597665Y297879D02*
X610282Y344392D01*
G01X586058Y287779D02*
X595857Y300801D01*
G01X585275Y288653D02*
X594805Y301316D01*
G01X595857Y300801D02*
X608004Y345585D01*
G01X594805Y301316D02*
X606960Y346133D01*
G01X593109Y304655D02*
X604673Y347314D01*
G01X605717Y346766D02*
X594161Y304140D01*
G01X582776Y290927D02*
X593109Y304655D01*
G01X594161Y304140D02*
X583553Y290045D01*
G01X567549Y282248D02*
X582776Y290927D01*
G01X561970Y283072D02*
X560927D01*
G01Y281922D02*
X562445D01*
G01X565228Y286312D02*
X561970Y283072D01*
G01D02*
X560927D01*
G01X562445Y281922D02*
X566012Y285469D01*
G01X569797Y290283D02*
X565228Y286312D01*
G01X566012Y285469D02*
X570425Y289305D01*
G01X579633Y294743D02*
X569797Y290283D01*
G01X570425Y289305D02*
X580311Y293787D01*
G01X591059Y306696D02*
X579633Y294743D01*
G01X580311Y293787D02*
X592093Y306112D01*
G01X602408Y348542D02*
X591059Y306696D01*
G01X592093Y306112D02*
X603452Y347994D01*
G01X566501Y304021D02*
X573093D01*
G01X566501Y305171D02*
X572874D01*
G01X573093Y304021D02*
X574582Y304609D01*
G01X572874Y305171D02*
X573925Y305586D01*
G01X574582Y304609D02*
X583926Y314382D01*
G01X573925Y305586D02*
X582892Y314966D01*
G01X583926Y314382D02*
X594331Y352749D01*
G01X582892Y314966D02*
X593287Y353297D01*
G01X587516Y284394D02*
X597665Y297879D01*
G01X586711Y285237D02*
X596613Y298394D01*
G01X597665Y297879D02*
X610282Y344392D01*
G01X596613Y298394D02*
X609238Y344940D01*
G01X563242Y291885D02*
X564342D01*
G01D02*
X579697Y297463D01*
G01X563242Y293035D02*
X564139D01*
G01X564342Y291885D02*
X579697Y297463D01*
G01X564139Y293035D02*
X579051Y298453D01*
G01X579697Y297463D02*
X590095Y308341D01*
G01X579051Y298453D02*
X589061Y308925D01*
G01X590095Y308341D02*
X601167Y349171D01*
G01X589061Y308925D02*
X600123Y349719D01*
G01X563075Y310003D02*
X566983D01*
G01X563075Y311153D02*
X566544D01*
G01X566983Y310003D02*
X580895Y322405D01*
G01X566544Y311153D02*
X579874Y323036D01*
G01X580895Y322405D02*
X589718Y355068D01*
G01X579874Y323036D02*
X588674Y355615D01*
G01X562507Y314334D02*
X566149D01*
G01X562507Y313184D02*
X566588D01*
G01X566149Y314334D02*
X577616Y324558D01*
G01X566588Y313184D02*
X578637Y323927D01*
G01X577616Y324558D02*
X588827Y365900D01*
G01X578637Y323927D02*
X588544Y360462D01*
G01X577616Y324558D02*
X588827Y365900D01*
G01X577616Y324558D02*
X588827Y365900D01*
G01X571079Y308191D02*
X571840D01*
G01X571079Y307041D02*
X572312D01*
G01X571079Y308191D02*
X571840D01*
G01D02*
X580867Y317094D01*
G01X572312Y307041D02*
X581896Y316493D01*
G01X580867Y317094D02*
X591012Y354494D01*
G01X581896Y316493D02*
X592056Y353946D01*
G01X563075Y311153D02*
X566544D01*
G01X563075Y310003D02*
X566983D01*
G01X566544Y311153D02*
X579874Y323036D01*
G01X566983Y310003D02*
X580895Y322405D01*
G01X579874Y323036D02*
X588674Y355615D01*
G01X580895Y322405D02*
X589718Y355068D01*
G01X562507Y313184D02*
X566588D01*
G01X562507Y314334D02*
X566149D01*
G01X566588Y313184D02*
X578637Y323927D01*
G01X566149Y314334D02*
X577616Y324558D01*
G01X578637Y323927D02*
X588544Y360462D01*
G01X577616Y324558D02*
X588827Y365900D01*
G01X585275Y288653D02*
X594805Y301316D01*
G01X586058Y287779D02*
X595857Y300801D01*
G01X594805Y301316D02*
X606960Y346133D01*
G01X595857Y300801D02*
X608004Y345585D01*
G01X601091Y281704D02*
X617123Y340823D01*
G01X600039Y282219D02*
X616079Y341371D01*
G01X599626Y290307D02*
X613798Y342559D01*
G01X600678Y289792D02*
X614842Y342011D01*
G01X598976Y293111D02*
X612562Y343202D01*
G01X597924Y293626D02*
X611518Y343750D01*
G01X563242Y293035D02*
X564139D01*
G01X563242Y291885D02*
X564342D01*
G01X563242Y293035D02*
X564139D01*
G01D02*
X579051Y298453D01*
G01X564342Y291885D02*
X579697Y297463D01*
G01X579051Y298453D02*
X589061Y308925D01*
G01X579697Y297463D02*
X590095Y308341D01*
G01X589061Y308925D02*
X600123Y349719D01*
G01X590095Y308341D02*
X601167Y349171D01*
G01X600039Y282219D02*
X616079Y341371D01*
G01X601091Y281704D02*
X617123Y340823D01*
G01X600678Y289792D02*
X614842Y342011D01*
G01X599626Y290307D02*
X613798Y342559D01*
G01X597924Y293626D02*
X611518Y343750D01*
G01X598976Y293111D02*
X612562Y343202D01*
G01X571809Y298489D02*
X574364D01*
G01X571809Y299639D02*
X574137D01*
G01X574364Y298489D02*
X578355Y300114D01*
G01X574137Y299639D02*
X577693Y301087D01*
G01X578355Y300114D02*
X587997Y310201D01*
G01X577693Y301087D02*
X586963Y310785D01*
G01X587997Y310201D02*
X598886Y350361D01*
G01X586963Y310785D02*
X597842Y350909D01*
G01X560275Y298315D02*
X560725D01*
G01X560275Y297165D02*
X561202D01*
G01X560725Y298315D02*
X564832Y302422D01*
G01X561202Y297165D02*
X565309Y301272D01*
G01X564832Y302422D02*
X573127D01*
G01X565309Y301272D02*
X573347D01*
G01X573127Y302422D02*
X575571Y303390D01*
G01X573347Y301272D02*
X576228Y302413D01*
G01X575571Y303390D02*
X585042Y313299D01*
G01X576228Y302413D02*
X586076Y312715D01*
G01X585042Y313299D02*
X595564Y352101D01*
G01X586076Y312715D02*
X596608Y351553D01*
G01X571809Y299639D02*
X574137D01*
G01X571809Y298489D02*
X574364D01*
G01X574137Y299639D02*
X577693Y301087D01*
G01X574364Y298489D02*
X578355Y300114D01*
G01X577693Y301087D02*
X586963Y310785D01*
G01X578355Y300114D02*
X587997Y310201D01*
G01X586963Y310785D02*
X597842Y350909D01*
G01X587997Y310201D02*
X598886Y350361D01*
G01X560275Y297165D02*
X561202D01*
G01X560275Y298315D02*
X560725D01*
G01X561202Y297165D02*
X565309Y301272D01*
G01X560725Y298315D02*
X564832Y302422D01*
G01X565309Y301272D02*
X573347D01*
G01X564832Y302422D02*
X573127D01*
G01X573347Y301272D02*
X576228Y302413D01*
G01X573127Y302422D02*
X575571Y303390D01*
G01X576228Y302413D02*
X586076Y312715D01*
G01X575571Y303390D02*
X585042Y313299D01*
G01X586076Y312715D02*
X596608Y351553D01*
G01X585042Y313299D02*
X595564Y352101D01*
G01X561080Y414342D02*
Y394358D01*
G01X562230D02*
Y414819D01*
G01Y394358D02*
Y414819D01*
G01X561080Y414342D02*
Y394358D01*
G01X569330Y420442D02*
Y370677D01*
G01X570480Y420919D02*
Y370200D01*
G01X569330Y370677D02*
X566067Y367414D01*
G01X570480Y370200D02*
X566881Y366601D01*
G01X563679Y370169D02*
X566530Y373020D01*
G01X564492Y369355D02*
X567680Y372543D01*
G01X566530Y373020D02*
Y417951D01*
G01X567680Y372543D02*
Y418428D01*
G01X565080Y386564D02*
Y416347D01*
G01X563930Y386564D02*
Y415870D01*
G01X570480Y420919D02*
Y370200D01*
G01X569330Y420442D02*
Y370677D01*
G01X570480Y370200D02*
X566881Y366601D01*
G01X569330Y370677D02*
X566067Y367414D01*
G01X564492Y369355D02*
X567680Y372543D01*
G01X563679Y370169D02*
X566530Y373020D01*
G01X567680Y372543D02*
Y418428D01*
G01X566530Y373020D02*
Y417951D01*
G01X563930Y386564D02*
Y415870D01*
G01X565080Y386564D02*
Y416347D01*
G01X593287Y353297D02*
X617499Y381949D01*
G01X594331Y352749D02*
X618587Y381453D01*
G01X592056Y353946D02*
X616215Y382534D01*
G01X591012Y354494D02*
X615127Y383030D01*
G01X594331Y352749D02*
X618587Y381453D01*
G01X593287Y353297D02*
X617499Y381949D01*
G01X601167Y349171D02*
X625706Y378209D01*
G01X600123Y349719D02*
X624618Y378705D01*
G01X589718Y355068D02*
X613842Y383616D01*
G01X588674Y355615D02*
X612754Y384112D01*
G01X589023Y362230D02*
X589258Y363092D01*
G01X589739Y364868D02*
X589966Y365706D01*
G01X588827Y365900D02*
X590451Y388304D01*
G01X589966Y365706D02*
X590089Y367384D01*
G01X588827Y365900D02*
X590451Y388304D01*
G01X590240Y369475D02*
X590307Y370374D01*
G01X588827Y365900D02*
X590451Y388304D01*
G01X590458Y372465D02*
X590525Y373364D01*
G01X588827Y365900D02*
X590451Y388304D01*
G01X590676Y375455D02*
X590743Y376354D01*
G01X588827Y365900D02*
X590451Y388304D01*
G01X590894Y378445D02*
X590961Y379344D01*
G01X588827Y365900D02*
X590451Y388304D01*
G01X591112Y381435D02*
X591179Y382334D01*
G01X590454Y388306D02*
X590742Y392339D01*
G01X591330Y384425D02*
X591872Y392004D01*
G01X590742Y392339D02*
X592737Y395949D01*
G01X591872Y392004D02*
X593654Y395230D01*
G01X592737Y395949D02*
X597251Y400114D01*
G01D02*
X597250D01*
G01D02*
X597512Y400355D01*
G01X593654Y395230D02*
X598031Y399269D01*
G01X597251Y400114D02*
X597250D01*
G01D02*
X597512Y400355D01*
G01D02*
X609995Y402236D01*
G01X598031Y399269D02*
X610531Y401153D01*
G01X591012Y354494D02*
X615127Y383030D01*
G01X592056Y353946D02*
X616215Y382534D01*
G01X588674Y355615D02*
X612754Y384112D01*
G01X589718Y355068D02*
X613842Y383616D01*
G01X589023Y362230D02*
X589258Y363092D01*
G01X589739Y364868D02*
X589966Y365706D01*
G01D02*
X590089Y367384D01*
G01X590240Y369475D02*
X590307Y370374D01*
G01X590458Y372465D02*
X590525Y373364D01*
G01X590676Y375455D02*
X590743Y376354D01*
G01X590894Y378445D02*
X590961Y379344D01*
G01X591112Y381435D02*
X591179Y382334D01*
G01X588827Y365900D02*
X590451Y388304D01*
G01X591330Y384425D02*
X591872Y392004D01*
G01X590454Y388306D02*
X590742Y392339D01*
G01X591872Y392004D02*
X593654Y395230D01*
G01X590742Y392339D02*
X592737Y395949D01*
G01X593654Y395230D02*
X598031Y399269D01*
G01X592737Y395949D02*
X597251Y400114D01*
G01X593654Y395230D02*
X598031Y399269D01*
G01D02*
X610531Y401153D01*
G01X597251Y400114D02*
X597250D01*
G01X593654Y395230D02*
X598031Y399269D01*
G01D02*
X610531Y401153D01*
G01X597250Y400114D02*
X597512Y400355D01*
G01X598031Y399269D02*
X610531Y401153D01*
G01X597512Y400355D02*
X609995Y402236D01*
G01X600123Y349719D02*
X624618Y378705D01*
G01X601167Y349171D02*
X625706Y378209D01*
G01X598886Y350361D02*
X623332Y379291D01*
G01X597842Y350909D02*
X622244Y379787D01*
G01X595564Y352101D02*
X619870Y380862D01*
G01X596608Y351553D02*
X620958Y380366D01*
G01X597842Y350909D02*
X622244Y379787D01*
G01X598886Y350361D02*
X623332Y379291D01*
G01X596608Y351553D02*
X620958Y380366D01*
G01X595564Y352101D02*
X619870Y380862D01*
G01X550178Y425244D02*
X561080Y414342D01*
G01X558379Y414021D02*
Y403499D01*
G01X557229D02*
Y413544D01*
G01D02*
X549419Y421354D01*
G01X550178Y425244D02*
X561080Y414342D01*
G01X557229Y413544D02*
X549419Y421354D01*
G01X557229Y403499D02*
Y413544D01*
G01X558379Y414021D02*
Y403499D01*
G01X566530Y417951D02*
X549245Y435236D01*
G01X547371Y437110D02*
X546416Y438065D01*
G01X566530Y417951D02*
X549245Y435236D01*
G01X547371Y437110D02*
X546416Y438065D01*
G01X566531Y648711D02*
X565894Y648741D01*
G01X566531Y648711D02*
X565894Y648741D01*
G01D02*
X565215Y648180D01*
G01X565504Y649911D02*
X564376Y648980D01*
G01X565215Y648180D02*
X564858Y647704D01*
G01X564376Y648980D02*
X563799Y648211D01*
G01X564858Y647704D02*
X564550Y646492D01*
G01X563799Y648211D02*
X563424Y646734D01*
G01X564550Y646492D02*
X564139Y644155D01*
G01X563424Y646734D02*
X563089Y644824D01*
G01X564139Y644155D02*
X562837Y643243D01*
G01X563089Y644824D02*
X562567Y644459D01*
G01X564139Y644155D02*
X562837Y643243D01*
G01D02*
X560863Y643590D01*
G01X562567Y644459D02*
X561533Y644641D01*
G01X560863Y643590D02*
X559952Y644894D01*
G01X561533Y644641D02*
X561168Y645163D01*
G01X559952Y644894D02*
X561436Y653300D01*
G01X561168Y645163D02*
X562652Y653570D01*
G01X559516Y653644D02*
X557832Y644094D01*
G01X558466Y654313D02*
X556781Y644763D01*
G01X557832Y644094D02*
X556528Y643180D01*
G01X556781Y644763D02*
X556258Y644396D01*
G01X557832Y644094D02*
X556528Y643180D01*
G01D02*
X554554Y643528D01*
G01X556258Y644396D02*
X555225Y644578D01*
G01X554554Y643528D02*
X553645Y644833D01*
G01X555225Y644578D02*
X554861Y645101D01*
G01X553645Y644833D02*
X555137Y653286D01*
G01X554861Y645101D02*
X556353Y653555D01*
G01X553215Y653624D02*
X551537Y644090D01*
G01X552165Y654294D02*
X550486Y644760D01*
G01X551537Y644090D02*
X550234Y643180D01*
G01X550486Y644760D02*
X549964Y644395D01*
G01X551537Y644090D02*
X550234Y643180D01*
G01D02*
X548262Y643525D01*
G01X549964Y644395D02*
X548931Y644576D01*
G01X548262Y643525D02*
X547350Y644829D01*
G01X548931Y644576D02*
X548566Y645098D01*
G01X547350Y644829D02*
X548841Y653285D01*
G01X548566Y645098D02*
X550057Y653554D01*
G01X546920Y653623D02*
X545237Y644071D01*
G01X545869Y654293D02*
X544187Y644741D01*
G01X545237Y644071D02*
X543934Y643162D01*
G01X544187Y644741D02*
X543665Y644377D01*
G01X545237Y644071D02*
X543934Y643162D01*
G01D02*
X541965Y643507D01*
G01X543665Y644377D02*
X542632Y644558D01*
G01X541965Y643507D02*
X541050Y644807D01*
G01X542632Y644558D02*
X542266Y645078D01*
G01X541050Y644807D02*
X542550Y653318D01*
G01X542266Y645078D02*
X543766Y653587D01*
G01X565504Y649911D02*
X564376Y648980D01*
G01X566531Y648711D02*
X565894Y648741D01*
G01X565504Y649911D02*
X564376Y648980D01*
G01X565894Y648741D02*
X565215Y648180D01*
G01X564376Y648980D02*
X563799Y648211D01*
G01X565215Y648180D02*
X564858Y647704D01*
G01X563799Y648211D02*
X563424Y646734D01*
G01X564858Y647704D02*
X564550Y646492D01*
G01X563424Y646734D02*
X563089Y644824D01*
G01X564550Y646492D02*
X564139Y644155D01*
G01X563089Y644824D02*
X562567Y644459D01*
G01D02*
X561533Y644641D01*
G01X564139Y644155D02*
X562837Y643243D01*
G01X562567Y644459D02*
X561533Y644641D01*
G01X562837Y643243D02*
X560863Y643590D01*
G01X561533Y644641D02*
X561168Y645163D01*
G01X560863Y643590D02*
X559952Y644894D01*
G01X561168Y645163D02*
X562652Y653570D01*
G01X559952Y644894D02*
X561436Y653300D01*
G01X558466Y654313D02*
X556781Y644763D01*
G01X559516Y653644D02*
X557832Y644094D01*
G01X556781Y644763D02*
X556258Y644396D01*
G01D02*
X555225Y644578D01*
G01X557832Y644094D02*
X556528Y643180D01*
G01X556258Y644396D02*
X555225Y644578D01*
G01X556528Y643180D02*
X554554Y643528D01*
G01X555225Y644578D02*
X554861Y645101D01*
G01X554554Y643528D02*
X553645Y644833D01*
G01X554861Y645101D02*
X556353Y653555D01*
G01X553645Y644833D02*
X555137Y653286D01*
G01X552165Y654294D02*
X550486Y644760D01*
G01X553215Y653624D02*
X551537Y644090D01*
G01X550486Y644760D02*
X549964Y644395D01*
G01D02*
X548931Y644576D01*
G01X551537Y644090D02*
X550234Y643180D01*
G01X549964Y644395D02*
X548931Y644576D01*
G01X550234Y643180D02*
X548262Y643525D01*
G01X548931Y644576D02*
X548566Y645098D01*
G01X548262Y643525D02*
X547350Y644829D01*
G01X548566Y645098D02*
X550057Y653554D01*
G01X547350Y644829D02*
X548841Y653285D01*
G01X545869Y654293D02*
X544187Y644741D01*
G01X546920Y653623D02*
X545237Y644071D01*
G01X544187Y644741D02*
X543665Y644377D01*
G01D02*
X542632Y644558D01*
G01X545237Y644071D02*
X543934Y643162D01*
G01X543665Y644377D02*
X542632Y644558D01*
G01X543934Y643162D02*
X541965Y643507D01*
G01X542632Y644558D02*
X542266Y645078D01*
G01X541965Y643507D02*
X541050Y644807D01*
G01X542266Y645078D02*
X543766Y653587D01*
G01X541050Y644807D02*
X542550Y653318D01*
G01X566624Y649859D02*
X565504Y649911D01*
G01X561436Y653300D02*
X561069Y653824D01*
G01X562652Y653570D02*
X561739Y654874D01*
G01X561069Y653824D02*
X560035Y654007D01*
G01X561739Y654874D02*
X559766Y655223D01*
G01X561069Y653824D02*
X560035Y654007D01*
G01D02*
X559516Y653644D01*
G01X559766Y655223D02*
X558466Y654313D01*
G01X555137Y653286D02*
X554773Y653807D01*
G01X556353Y653555D02*
X555443Y654858D01*
G01X554773Y653807D02*
X553738Y653989D01*
G01X555443Y654858D02*
X553469Y655204D01*
G01X554773Y653807D02*
X553738Y653989D01*
G01D02*
X553215Y653624D01*
G01X553469Y655204D02*
X552165Y654294D01*
G01X548841Y653285D02*
X548477Y653806D01*
G01X550057Y653554D02*
X549147Y654857D01*
G01X548477Y653806D02*
X547443Y653988D01*
G01X549147Y654857D02*
X547173Y655203D01*
G01X548477Y653806D02*
X547443Y653988D01*
G01D02*
X546920Y653623D01*
G01X547173Y655203D02*
X545869Y654293D01*
G01X542550Y653318D02*
X542186Y653839D01*
G01X543766Y653587D02*
X542856Y654890D01*
G01X542186Y653839D02*
X541152Y654021D01*
G01X542856Y654890D02*
X540882Y655237D01*
G01X542186Y653839D02*
X541152Y654021D01*
G01D02*
X540632Y653657D01*
G01X566624Y649859D02*
X565504Y649911D01*
G01X562652Y653570D02*
X561739Y654874D01*
G01X561436Y653300D02*
X561069Y653824D01*
G01X561739Y654874D02*
X559766Y655223D01*
G01D02*
X558466Y654313D01*
G01X561069Y653824D02*
X560035Y654007D01*
G01X559766Y655223D02*
X558466Y654313D01*
G01X560035Y654007D02*
X559516Y653644D01*
G01X556353Y653555D02*
X555443Y654858D01*
G01X555137Y653286D02*
X554773Y653807D01*
G01X555443Y654858D02*
X553469Y655204D01*
G01D02*
X552165Y654294D01*
G01X554773Y653807D02*
X553738Y653989D01*
G01X553469Y655204D02*
X552165Y654294D01*
G01X553738Y653989D02*
X553215Y653624D01*
G01X550057Y653554D02*
X549147Y654857D01*
G01X548841Y653285D02*
X548477Y653806D01*
G01X549147Y654857D02*
X547173Y655203D01*
G01D02*
X545869Y654293D01*
G01X548477Y653806D02*
X547443Y653988D01*
G01X547173Y655203D02*
X545869Y654293D01*
G01X547443Y653988D02*
X546920Y653623D01*
G01X543766Y653587D02*
X542856Y654890D01*
G01X542550Y653318D02*
X542186Y653839D01*
G01X542856Y654890D02*
X540882Y655237D01*
G01X542186Y653839D02*
X541152Y654021D01*
G01D02*
X540632Y653657D01*
G01X647393Y134084D02*
X666948Y132804D01*
G01X647565Y135226D02*
X667354Y133930D01*
G01X639727Y132702D02*
X667114Y130536D01*
G01X639547Y131562D02*
X666704Y129414D01*
G01X647565Y135226D02*
X667354Y133930D01*
G01X647393Y134084D02*
X666948Y132804D01*
G01X639547Y131562D02*
X666704Y129414D01*
G01X639727Y132702D02*
X667114Y130536D01*
G01X667500Y156088D02*
X635225Y156455D01*
G01X667500Y156088D02*
X635225Y156455D01*
G01X666325Y154951D02*
X635127Y155305D01*
G01D02*
X629450Y156219D01*
G01X628654Y156363D02*
X614178Y155382D01*
G01D02*
X612725Y155399D01*
G01X669911Y153286D02*
X652128Y153490D01*
G01X669911Y153286D02*
X652128Y153490D01*
G01D02*
X634344Y153694D01*
G01X669898Y152136D02*
X634230Y152545D01*
G01X634344Y153694D02*
X628188Y154850D01*
G01X634230Y152545D02*
X628120Y153692D01*
G01X628188Y154850D02*
X614570Y153918D01*
G01X628120Y153692D02*
X614602Y152767D01*
G01X614570Y153918D02*
X612660Y153940D01*
G01X614602Y152767D02*
X612541Y152791D01*
G01X664300Y145800D02*
X657550Y146456D01*
G01X664822Y146905D02*
X657662Y147601D01*
G01X657550Y146456D02*
X646991Y147483D01*
G01X657662Y147601D02*
X647140Y148624D01*
G01X646991Y147483D02*
X627251Y150724D01*
G01X647140Y148624D02*
X627309Y151880D01*
G01X627251Y150724D02*
X614916Y149951D01*
G01X627309Y151880D02*
X614887Y151102D01*
G01X614916Y149951D02*
X613216Y149972D01*
G01X614887Y151102D02*
X613325Y151122D01*
G01X666186Y138761D02*
X655025Y139472D01*
G01X666000Y137620D02*
X654826Y138332D01*
G01X655025Y139472D02*
X644850Y142427D01*
G01X654826Y138332D02*
X644570Y141310D01*
G01X644850Y142427D02*
X640265Y143398D01*
G01X644570Y141310D02*
X639921Y142295D01*
G01X640265Y143398D02*
X632927Y146469D01*
G01X639921Y142295D02*
X632679Y145325D01*
G01X632927Y146469D02*
X629669Y146568D01*
G01X632679Y145325D02*
X629634Y145417D01*
G01X632927Y146469D02*
X629669Y146568D01*
G01D02*
X610830Y148647D01*
G01X629634Y145417D02*
X629542Y145425D01*
G01X629669Y146568D02*
X610830Y148647D01*
G01X629542Y145425D02*
X610658Y147508D01*
G01X666325Y154951D02*
X635127Y155305D01*
G01X667500Y156088D02*
X635225Y156455D01*
G01X635127Y155305D02*
X629450Y156219D01*
G01X635127Y155305D02*
X629450Y156219D01*
G01X628654Y156363D02*
X614178Y155382D01*
G01D02*
X612725Y155399D01*
G01X669898Y152136D02*
X634230Y152545D01*
G01X669898Y152136D02*
X634230Y152545D01*
G01X669911Y153286D02*
X652128Y153490D01*
G01X669898Y152136D02*
X634230Y152545D01*
G01X652128Y153490D02*
X634344Y153694D01*
G01X634230Y152545D02*
X628120Y153692D01*
G01X634344Y153694D02*
X628188Y154850D01*
G01X628120Y153692D02*
X614602Y152767D01*
G01X628188Y154850D02*
X614570Y153918D01*
G01X614602Y152767D02*
X612541Y152791D01*
G01X614570Y153918D02*
X612660Y153940D01*
G01X664822Y146905D02*
X657662Y147601D01*
G01X664300Y145800D02*
X657550Y146456D01*
G01X657662Y147601D02*
X647140Y148624D01*
G01X657550Y146456D02*
X646991Y147483D01*
G01X647140Y148624D02*
X627309Y151880D01*
G01X646991Y147483D02*
X627251Y150724D01*
G01X627309Y151880D02*
X614887Y151102D01*
G01X627251Y150724D02*
X614916Y149951D01*
G01X614887Y151102D02*
X613325Y151122D01*
G01X614916Y149951D02*
X613216Y149972D01*
G01X666000Y137620D02*
X654826Y138332D01*
G01X666186Y138761D02*
X655025Y139472D01*
G01X654826Y138332D02*
X644570Y141310D01*
G01X655025Y139472D02*
X644850Y142427D01*
G01X644570Y141310D02*
X639921Y142295D01*
G01X644850Y142427D02*
X640265Y143398D01*
G01X639921Y142295D02*
X632679Y145325D01*
G01X640265Y143398D02*
X632927Y146469D01*
G01X632679Y145325D02*
X629634Y145417D01*
G01D02*
X629542Y145425D01*
G01X632927Y146469D02*
X629669Y146568D01*
G01X629634Y145417D02*
X629542Y145425D01*
G01D02*
X610658Y147508D01*
G01X629669Y146568D02*
X610830Y148647D01*
G01X672824Y167739D02*
X656989Y166431D01*
G01X672900Y168900D02*
X656895Y167578D01*
G01X656989Y166431D02*
X637012Y166732D01*
G01X656895Y167578D02*
X637147Y167881D01*
G01X637012Y166732D02*
X630539Y168173D01*
G01X637147Y167881D02*
X630581Y169342D01*
G01X630539Y168173D02*
X613783Y165691D01*
G01X630581Y169342D02*
X613832Y166861D01*
G01X672439Y164145D02*
X657092Y163380D01*
G01X672500Y165300D02*
X657035Y164529D01*
G01X657092Y163380D02*
X651621Y163461D01*
G01D02*
X637727Y163674D01*
G01X657035Y164529D02*
X637852Y164823D01*
G01X637727Y163674D02*
X629348Y165381D01*
G01X637852Y164823D02*
X629381Y166548D01*
G01X629348Y165381D02*
X614747Y163259D01*
G01X629381Y166548D02*
X614601Y164400D01*
G01X629348Y165381D02*
X614747Y163259D01*
G01D02*
X613657Y163136D01*
G01X614601Y164400D02*
X613721Y164301D01*
G01X637380Y162030D02*
X663274D01*
G01X663265Y160880D02*
X637280D01*
G01X629381Y163430D02*
X637380Y162030D01*
G01X637280Y160880D02*
X629345Y162268D01*
G01X613647Y161658D02*
X629381Y163430D01*
G01X629345Y162268D02*
X613587Y160493D01*
G01X665300Y157900D02*
X636613Y158314D01*
G01X665309Y159050D02*
X636703Y159463D01*
G01X636613Y158314D02*
X629166Y159370D01*
G01X636703Y159463D02*
X629196Y160528D01*
G01X629166Y159370D02*
X613102Y157932D01*
G01X629196Y160528D02*
X613172Y159093D01*
G01X635225Y156455D02*
X629644Y157353D01*
G01D02*
X628719Y157521D01*
G01X635225Y156455D02*
X629644Y157353D01*
G01D02*
X628719Y157521D01*
G01D02*
X614146Y156533D01*
G01X629450Y156219D02*
X628654Y156363D01*
G01X628719Y157521D02*
X614146Y156533D01*
G01D02*
X612845Y156548D01*
G01X663736Y184441D02*
X648522Y187303D01*
G01X664039Y185555D02*
X648499Y188478D01*
G01X648522Y187303D02*
X628801Y182793D01*
G01X648499Y188478D02*
X628450Y183893D01*
G01X628801Y182793D02*
X614699Y176953D01*
G01X628450Y183893D02*
X614596Y178156D01*
G01X713435Y164742D02*
X662577Y183292D01*
G01X713176Y163612D02*
X662270Y182179D01*
G01X662577Y183292D02*
X649019Y185884D01*
G01X662270Y182179D02*
X649038Y184709D01*
G01X649019Y185884D02*
X628987Y181367D01*
G01X649038Y184709D02*
X629336Y180266D01*
G01X628987Y181367D02*
X614377Y175318D01*
G01X629336Y180266D02*
X614477Y174114D01*
G01X665194Y178256D02*
X661848Y179462D01*
G01X665584Y179339D02*
X662147Y180578D01*
G01X661848Y179462D02*
X648420Y181866D01*
G01X662147Y180578D02*
X648396Y183039D01*
G01X648420Y181866D02*
X634489Y178773D01*
G01Y178772D02*
X629989Y177774D01*
G01X648396Y183039D02*
X629639Y178875D01*
G01X629989Y177774D02*
X615826Y171834D01*
G01X629639Y178875D02*
X615394Y172901D01*
G01X629989Y177774D02*
X615826Y171834D01*
G01D02*
X614772Y171426D01*
G01X615394Y172901D02*
X614670Y172620D01*
G01X614772Y171426D02*
X612959Y171790D01*
G01X614670Y172620D02*
X613197Y172916D01*
G01X665832Y175169D02*
X660585Y177063D01*
G01X666223Y176251D02*
X660889Y178176D01*
G01X660585Y177063D02*
X649241Y179205D01*
G01X660889Y178176D02*
X649228Y180378D01*
G01X649241Y179205D02*
X634027Y175992D01*
G01X649228Y180378D02*
X633803Y177121D01*
G01X634027Y175992D02*
X631869Y175593D01*
G01X633803Y177121D02*
X631542Y176703D01*
G01X631869Y175593D02*
X614152Y168312D01*
G01X631542Y176703D02*
X614056Y169516D01*
G01X672900Y168900D02*
X656895Y167578D01*
G01X672824Y167739D02*
X656989Y166431D01*
G01X656895Y167578D02*
X637147Y167881D01*
G01X656989Y166431D02*
X637012Y166732D01*
G01X637147Y167881D02*
X630581Y169342D01*
G01X637012Y166732D02*
X630539Y168173D01*
G01X630581Y169342D02*
X613832Y166861D01*
G01X630539Y168173D02*
X613783Y165691D01*
G01X672500Y165300D02*
X657035Y164529D01*
G01X672439Y164145D02*
X657092Y163380D01*
G01X657035Y164529D02*
X637852Y164823D01*
G01X657092Y163380D02*
X651621Y163461D01*
G01X657035Y164529D02*
X637852Y164823D01*
G01X651621Y163461D02*
X637727Y163674D01*
G01X637852Y164823D02*
X629381Y166548D01*
G01X637727Y163674D02*
X629348Y165381D01*
G01X629381Y166548D02*
X614601Y164400D01*
G01D02*
X613721Y164301D01*
G01X629348Y165381D02*
X614747Y163259D01*
G01X614601Y164400D02*
X613721Y164301D01*
G01X614747Y163259D02*
X613657Y163136D01*
G01X614601Y164400D02*
X613721Y164301D01*
G01X629345Y162268D02*
X613587Y160493D01*
G01X613647Y161658D02*
X629381Y163430D01*
G01X637280Y160880D02*
X629345Y162268D01*
G01X629381Y163430D02*
X637380Y162030D01*
G01X663265Y160880D02*
X637280D01*
G01X637380Y162030D02*
X663274D01*
G01X665309Y159050D02*
X636703Y159463D01*
G01X665300Y157900D02*
X636613Y158314D01*
G01X636703Y159463D02*
X629196Y160528D01*
G01X636613Y158314D02*
X629166Y159370D01*
G01X629196Y160528D02*
X613172Y159093D01*
G01X629166Y159370D02*
X613102Y157932D01*
G01X629450Y156219D02*
X628654Y156363D01*
G01X635225Y156455D02*
X629644Y157353D01*
G01X629450Y156219D02*
X628654Y156363D01*
G01X629644Y157353D02*
X628719Y157521D01*
G01X629450Y156219D02*
X628654Y156363D01*
G01X628719Y157521D02*
X614146Y156533D01*
G01D02*
X612845Y156548D01*
G01X665512Y187806D02*
X649019Y191198D01*
G01X665201Y186695D02*
X649026Y190022D01*
G01X649019Y191198D02*
X628433Y186711D01*
G01X649026Y190022D02*
X628778Y185609D01*
G01X628433Y186711D02*
X614419Y180927D01*
G01X628778Y185609D02*
X614522Y179725D01*
G01X664039Y185555D02*
X648499Y188478D01*
G01X663736Y184441D02*
X648522Y187303D01*
G01X648499Y188478D02*
X628450Y183893D01*
G01X648522Y187303D02*
X628801Y182793D01*
G01X628450Y183893D02*
X614596Y178156D01*
G01X628801Y182793D02*
X614699Y176953D01*
G01X713176Y163612D02*
X662270Y182179D01*
G01X713435Y164742D02*
X662577Y183292D01*
G01X662270Y182179D02*
X649038Y184709D01*
G01X662577Y183292D02*
X649019Y185884D01*
G01X649038Y184709D02*
X629336Y180266D01*
G01X649019Y185884D02*
X628987Y181367D01*
G01X629336Y180266D02*
X614477Y174114D01*
G01X628987Y181367D02*
X614377Y175318D01*
G01X665584Y179339D02*
X662147Y180578D01*
G01X665194Y178256D02*
X661848Y179462D01*
G01X662147Y180578D02*
X648396Y183039D01*
G01X661848Y179462D02*
X648420Y181866D01*
G01X648396Y183039D02*
X629639Y178875D01*
G01X648420Y181866D02*
X634489Y178773D01*
G01X648396Y183039D02*
X629639Y178875D01*
G01X634489Y178772D02*
X629989Y177774D01*
G01X629639Y178875D02*
X615394Y172901D01*
G01D02*
X614670Y172620D01*
G01X629989Y177774D02*
X615826Y171834D01*
G01X615394Y172901D02*
X614670Y172620D01*
G01X615826Y171834D02*
X614772Y171426D01*
G01X614670Y172620D02*
X613197Y172916D01*
G01X614772Y171426D02*
X612959Y171790D01*
G01X666223Y176251D02*
X660889Y178176D01*
G01X665832Y175169D02*
X660585Y177063D01*
G01X660889Y178176D02*
X649228Y180378D01*
G01X660585Y177063D02*
X649241Y179205D01*
G01X649228Y180378D02*
X633803Y177121D01*
G01X649241Y179205D02*
X634027Y175992D01*
G01X633803Y177121D02*
X631542Y176703D01*
G01X634027Y175992D02*
X631869Y175593D01*
G01X631542Y176703D02*
X614056Y169516D01*
G01X631869Y175593D02*
X614152Y168312D01*
G01X667439Y199871D02*
X649887Y203924D01*
G01X667756Y200979D02*
X649914Y205099D01*
G01X649887Y203924D02*
X630273Y200329D01*
G01X649914Y205099D02*
X629946Y201439D01*
G01X630273Y200329D02*
X613415Y193348D01*
G01X629946Y201439D02*
X613310Y194550D01*
G01X667085Y197190D02*
X649244Y201093D01*
G01X667394Y198300D02*
X649261Y202267D01*
G01X649244Y201093D02*
X630359Y197516D01*
G01X649261Y202267D02*
X630028Y198625D01*
G01X630359Y197516D02*
X613796Y190663D01*
G01X630028Y198625D02*
X613691Y191865D01*
G01X667399Y195597D02*
X648943Y199372D01*
G01X667095Y194485D02*
X648934Y198199D01*
G01X648943Y199372D02*
X629551Y195712D01*
G01X648934Y198199D02*
X629883Y194604D01*
G01X629551Y195712D02*
X613686Y189140D01*
G01X629883Y194604D02*
X613787Y187937D01*
G01X665599Y193281D02*
X649131Y196697D01*
G01X665292Y192170D02*
X649127Y195523D01*
G01X649131Y196697D02*
X629056Y192669D01*
G01X649127Y195523D02*
X629393Y191563D01*
G01X629056Y192669D02*
X613871Y186381D01*
G01X629393Y191563D02*
X613972Y185178D01*
G01X664444Y189690D02*
X649668Y192845D01*
G01X664756Y190800D02*
X649671Y194021D01*
G01X649668Y192845D02*
X628662Y188466D01*
G01X649671Y194021D02*
X628322Y189570D01*
G01X628662Y188466D02*
X614483Y182595D01*
G01X628322Y189570D02*
X614380Y183798D01*
G01X665201Y186695D02*
X649026Y190022D01*
G01X665512Y187806D02*
X649019Y191198D01*
G01X649026Y190022D02*
X628778Y185609D01*
G01X649019Y191198D02*
X628433Y186711D01*
G01X628778Y185609D02*
X614522Y179725D01*
G01X628433Y186711D02*
X614419Y180927D01*
G01X667756Y200979D02*
X649914Y205099D01*
G01X667439Y199871D02*
X649887Y203924D01*
G01X649914Y205099D02*
X629946Y201439D01*
G01X649887Y203924D02*
X630273Y200329D01*
G01X629946Y201439D02*
X613310Y194550D01*
G01X630273Y200329D02*
X613415Y193348D01*
G01X667394Y198300D02*
X649261Y202267D01*
G01X667085Y197190D02*
X649244Y201093D01*
G01X649261Y202267D02*
X630028Y198625D01*
G01X649244Y201093D02*
X630359Y197516D01*
G01X630028Y198625D02*
X613691Y191865D01*
G01X630359Y197516D02*
X613796Y190663D01*
G01X667095Y194485D02*
X648934Y198199D01*
G01X667399Y195597D02*
X648943Y199372D01*
G01X648934Y198199D02*
X629883Y194604D01*
G01X648943Y199372D02*
X629551Y195712D01*
G01X629883Y194604D02*
X613787Y187937D01*
G01X629551Y195712D02*
X613686Y189140D01*
G01X665292Y192170D02*
X649127Y195523D01*
G01X665599Y193281D02*
X649131Y196697D01*
G01X649127Y195523D02*
X629393Y191563D01*
G01X649131Y196697D02*
X629056Y192669D01*
G01X629393Y191563D02*
X613972Y185178D01*
G01X629056Y192669D02*
X613871Y186381D01*
G01X664756Y190800D02*
X649671Y194021D01*
G01X664444Y189690D02*
X649668Y192845D01*
G01X649671Y194021D02*
X628322Y189570D01*
G01X649668Y192845D02*
X628662Y188466D01*
G01X628322Y189570D02*
X614380Y183798D01*
G01X628662Y188466D02*
X614483Y182595D01*
G01X611402Y262131D02*
X630800Y333676D01*
G01X610364Y262702D02*
X629756Y334224D01*
G01X608283Y264616D02*
X627477Y335414D01*
G01X609318Y264038D02*
X628521Y334866D01*
G01X610364Y262702D02*
X629756Y334224D01*
G01X611402Y262131D02*
X630800Y333676D01*
G01X609318Y264038D02*
X628521Y334866D01*
G01X608283Y264616D02*
X627477Y335414D01*
G01X601800Y274731D02*
X619401Y339626D01*
G01X607108Y265493D02*
X626240Y336055D01*
G01X606075Y266081D02*
X625196Y336603D01*
G01X604191Y268730D02*
X622916Y337793D01*
G01X605227Y268153D02*
X623960Y337245D01*
G01X603068Y269795D02*
X621682Y338439D01*
G01X602034Y270376D02*
X620638Y338987D01*
G01X601800Y274731D02*
X619401Y339626D01*
G01X606075Y266081D02*
X625196Y336603D01*
G01X607108Y265493D02*
X626240Y336055D01*
G01X605227Y268153D02*
X623960Y337245D01*
G01X604191Y268730D02*
X622916Y337793D01*
G01X602034Y270376D02*
X620638Y338987D01*
G01X603068Y269795D02*
X621682Y338439D01*
G01X630800Y333676D02*
X656881Y364538D01*
G01X629756Y334224D02*
X655793Y365034D01*
G01X627477Y335414D02*
X653419Y366114D01*
G01X628521Y334866D02*
X654507Y365618D01*
G01X629756Y334224D02*
X655793Y365034D01*
G01X630800Y333676D02*
X656881Y364538D01*
G01X628521Y334866D02*
X654507Y365618D01*
G01X627477Y335414D02*
X653419Y366114D01*
G01X619401Y339626D02*
X644925Y369832D01*
G01X618357Y340174D02*
X643837Y370328D01*
G01X626240Y336055D02*
X652134Y366699D01*
G01X625196Y336603D02*
X651046Y367195D01*
G01X622916Y337793D02*
X648675Y368277D01*
G01X623960Y337245D02*
X649763Y367781D01*
G01X621682Y338439D02*
X647389Y368861D01*
G01X620638Y338987D02*
X646301Y369357D01*
G01X618357Y340174D02*
X643837Y370328D01*
G01X619401Y339626D02*
X644925Y369832D01*
G01X617123Y340823D02*
X642313Y370633D01*
G01X616079Y341371D02*
X616671Y342072D01*
G01X617123Y340823D02*
X642313Y370633D01*
G01X625196Y336603D02*
X651046Y367195D01*
G01X626240Y336055D02*
X652134Y366699D01*
G01X623960Y337245D02*
X649763Y367781D01*
G01X622916Y337793D02*
X648675Y368277D01*
G01X620638Y338987D02*
X646301Y369357D01*
G01X621682Y338439D02*
X647389Y368861D01*
G01X616079Y341371D02*
X616671Y342072D01*
G01X617123Y340823D02*
X642313Y370633D01*
G01X656881Y364538D02*
X657831Y370691D01*
G01X655793Y365034D02*
X656749Y371225D01*
G01X657831Y370691D02*
X682847Y396794D01*
G01X656749Y371225D02*
X682267Y397852D01*
G01X630448Y376034D02*
X605717Y346766D01*
G01X604673Y347314D02*
X629360Y376530D01*
G01X633398Y395121D02*
X630448Y376034D01*
G01X629360Y376530D02*
X632321Y395683D01*
G01X677750Y437433D02*
X633398Y395121D01*
G01X632321Y395683D02*
X677099Y438403D01*
G01X631049Y396348D02*
X677983Y441127D01*
G01X677331Y442095D02*
X629972Y396910D01*
G01X628078Y377127D02*
X631049Y396348D01*
G01X629972Y396910D02*
X626990Y377623D01*
G01X603452Y347994D02*
X628078Y377127D01*
G01X626990Y377623D02*
X602408Y348542D01*
G01X617499Y381949D02*
X620571Y401816D01*
G01X618587Y381453D02*
X621648Y401254D01*
G01X620571Y401816D02*
X648184Y428162D01*
G01X621648Y401254D02*
X648978Y427329D01*
G01X616215Y382534D02*
X619296Y402482D01*
G01X615127Y383030D02*
X618219Y403044D01*
G01X619296Y402482D02*
X646762Y428685D01*
G01X618219Y403044D02*
X674617Y456851D01*
G01X653419Y366114D02*
X654463Y372865D01*
G01X654507Y365618D02*
X655545Y372330D01*
G01X654463Y372865D02*
X680543Y400070D01*
G01X655545Y372330D02*
X681123Y399012D01*
G01X609238Y344940D02*
X634106Y374370D01*
G01X610282Y344392D02*
X635194Y373874D01*
G01X634106Y374370D02*
X636766Y391569D01*
G01X635194Y373874D02*
X637844Y391013D01*
G01X636766Y391569D02*
X663673Y417770D01*
G01X637844Y391013D02*
X664293Y416768D01*
G01X655793Y365034D02*
X656749Y371225D01*
G01X656881Y364538D02*
X657831Y370691D01*
G01X656749Y371225D02*
X682267Y397852D01*
G01X657831Y370691D02*
X682847Y396794D01*
G01X608012Y345596D02*
X632820Y374952D01*
G01X606960Y346133D02*
X607134Y346339D01*
G01X608012Y345596D02*
X632820Y374952D01*
G01X607138Y346344D02*
X631732Y375448D01*
G01X632820Y374952D02*
X635748Y393893D01*
G01X631732Y375448D02*
X634671Y394455D01*
G01X635748Y393893D02*
X678572Y434750D01*
G01X634671Y394455D02*
X677922Y435721D01*
G01X632321Y395683D02*
X677099Y438403D01*
G01X677750Y437433D02*
X633398Y395121D01*
G01X629360Y376530D02*
X632321Y395683D01*
G01X633398Y395121D02*
X630448Y376034D01*
G01X604673Y347314D02*
X629360Y376530D01*
G01X630448Y376034D02*
X605717Y346766D01*
G01X626990Y377623D02*
X602408Y348542D01*
G01X603452Y347994D02*
X628078Y377127D01*
G01X629972Y396910D02*
X626990Y377623D01*
G01X628078Y377127D02*
X631049Y396348D01*
G01X677331Y442095D02*
X629972Y396910D01*
G01X631049Y396348D02*
X677983Y441127D01*
G01X618587Y381453D02*
X621648Y401254D01*
G01X617499Y381949D02*
X620571Y401816D01*
G01X621648Y401254D02*
X648978Y427329D01*
G01X620571Y401816D02*
X648184Y428162D01*
G01X654507Y365618D02*
X655545Y372330D01*
G01X653419Y366114D02*
X654463Y372865D01*
G01X655545Y372330D02*
X681123Y399012D01*
G01X654463Y372865D02*
X680543Y400070D01*
G01X644925Y369832D02*
X646255Y378443D01*
G01X643837Y370328D02*
X644789Y376492D01*
G01X644925Y369832D02*
X646255Y378443D01*
G01X644791Y376493D02*
X645173Y378977D01*
G01X646255Y378443D02*
X661683Y394524D01*
G01X661682D02*
X677110Y410605D01*
G01X645173Y378977D02*
X676470Y411601D01*
G01X610282Y344392D02*
X635194Y373874D01*
G01X609238Y344940D02*
X634106Y374370D01*
G01X635194Y373874D02*
X637844Y391013D01*
G01X634106Y374370D02*
X636766Y391569D01*
G01X637844Y391013D02*
X664293Y416768D01*
G01X636766Y391569D02*
X663673Y417770D01*
G01X625706Y378209D02*
X628698Y397574D01*
G01X624618Y378705D02*
X627621Y398136D01*
G01X628698Y397574D02*
X677235Y443882D01*
G01X627621Y398136D02*
X676584Y444852D01*
G01X613842Y383616D02*
X616880Y403264D01*
G01X612754Y384112D02*
X615730Y403354D01*
G01X613842Y383616D02*
X616880Y403264D01*
G01X609995Y402236D02*
X670284Y460642D01*
G01X610531Y401153D02*
X670939Y459674D01*
G01X615127Y383030D02*
X618219Y403044D01*
G01X616215Y382534D02*
X619296Y402482D01*
G01X618219Y403044D02*
X674617Y456851D01*
G01X619296Y402482D02*
X646762Y428685D01*
G01X618219Y403044D02*
X674617Y456851D01*
G01X612754Y384112D02*
X615730Y403354D01*
G01X613842Y383616D02*
X616880Y403264D01*
G01X612754Y384112D02*
X615730Y403354D01*
G01X610531Y401153D02*
X670939Y459674D01*
G01X609995Y402236D02*
X670284Y460642D01*
G01X606960Y346133D02*
X607134Y346339D01*
G01X607138Y346344D02*
X631732Y375448D01*
G01X608012Y345596D02*
X632820Y374952D01*
G01X631732Y375448D02*
X634671Y394455D01*
G01X632820Y374952D02*
X635748Y393893D01*
G01X634671Y394455D02*
X677922Y435721D01*
G01X635748Y393893D02*
X678572Y434750D01*
G01X652134Y366699D02*
X653265Y374013D01*
G01X651046Y367195D02*
X652183Y374547D01*
G01X653265Y374013D02*
X679332Y401214D01*
G01X652183Y374547D02*
X678752Y402272D01*
G01X648675Y368277D02*
X649864Y375969D01*
G01X649763Y367781D02*
X650946Y375435D01*
G01X649864Y375969D02*
X677234Y404530D01*
G01X650946Y375435D02*
X677814Y403472D01*
G01X647389Y368861D02*
X648635Y376924D01*
G01X646301Y369357D02*
X647553Y377459D01*
G01X648635Y376924D02*
X676262Y405722D01*
G01X647553Y377459D02*
X675682Y406780D01*
G01X643837Y370328D02*
X644789Y376492D01*
G01X644791Y376493D02*
X645173Y378977D01*
G01X644925Y369832D02*
X646255Y378443D01*
G01X645173Y378977D02*
X676470Y411601D01*
G01X646255Y378443D02*
X661683Y394524D01*
G01X645173Y378977D02*
X676470Y411601D01*
G01X661682Y394524D02*
X677110Y410605D01*
G01X616671Y342072D02*
X641225Y371129D01*
G01X642313Y370633D02*
X643685Y379507D01*
G01X641225Y371129D02*
X642603Y380042D01*
G01X643685Y379507D02*
X675549Y412719D01*
G01X642603Y380042D02*
X643156Y380618D01*
G01X643685Y379507D02*
X675549Y412719D01*
G01X643156Y380618D02*
X674910Y413716D01*
G01X613798Y342559D02*
X638851Y372207D01*
G01X614842Y342011D02*
X639939Y371711D01*
G01X638851Y372207D02*
X641334Y388272D01*
G01X639939Y371711D02*
X642413Y387717D01*
G01X641334Y388272D02*
X667382Y413747D01*
G01X642413Y387717D02*
X668004Y412746D01*
G01X612562Y343202D02*
X637568Y372796D01*
G01X611518Y343750D02*
X636480Y373292D01*
G01X637568Y372796D02*
X640145Y389468D01*
G01X636480Y373292D02*
X639067Y390024D01*
G01X640145Y389468D02*
X666097Y414739D01*
G01X639067Y390024D02*
X665477Y415741D01*
G01X624618Y378705D02*
X627621Y398136D01*
G01X625706Y378209D02*
X628698Y397574D01*
G01X627621Y398136D02*
X676584Y444852D01*
G01X628698Y397574D02*
X677235Y443882D01*
G01X651046Y367195D02*
X652183Y374547D01*
G01X652134Y366699D02*
X653265Y374013D01*
G01X652183Y374547D02*
X678752Y402272D01*
G01X653265Y374013D02*
X679332Y401214D01*
G01X649763Y367781D02*
X650946Y375435D01*
G01X648675Y368277D02*
X649864Y375969D01*
G01X650946Y375435D02*
X677814Y403472D01*
G01X649864Y375969D02*
X677234Y404530D01*
G01X646301Y369357D02*
X647553Y377459D01*
G01X647389Y368861D02*
X648635Y376924D01*
G01X647553Y377459D02*
X675682Y406780D01*
G01X648635Y376924D02*
X676262Y405722D01*
G01X616671Y342072D02*
X641225Y371129D01*
G01D02*
X642603Y380042D01*
G01X642313Y370633D02*
X643685Y379507D01*
G01X642603Y380042D02*
X643156Y380618D01*
G01D02*
X674910Y413716D01*
G01X643685Y379507D02*
X675549Y412719D01*
G01X643156Y380618D02*
X674910Y413716D01*
G01X614842Y342011D02*
X639939Y371711D01*
G01X613798Y342559D02*
X638851Y372207D01*
G01X639939Y371711D02*
X642413Y387717D01*
G01X638851Y372207D02*
X641334Y388272D01*
G01X642413Y387717D02*
X668004Y412746D01*
G01X641334Y388272D02*
X667382Y413747D01*
G01X611518Y343750D02*
X636480Y373292D01*
G01X612562Y343202D02*
X637568Y372796D01*
G01X636480Y373292D02*
X639067Y390024D01*
G01X637568Y372796D02*
X640145Y389468D01*
G01X639067Y390024D02*
X665477Y415741D01*
G01X640145Y389468D02*
X666097Y414739D01*
G01X623332Y379291D02*
X626356Y398852D01*
G01X622244Y379787D02*
X625279Y399414D01*
G01X626356Y398852D02*
X674977Y445237D01*
G01X625279Y399414D02*
X674233Y446118D01*
G01X619870Y380862D02*
X622921Y400593D01*
G01X620958Y380366D02*
X623998Y400031D01*
G01X622921Y400593D02*
X677022Y452204D01*
G01X623998Y400031D02*
X677671Y451233D01*
G01X622244Y379787D02*
X625279Y399414D01*
G01X623332Y379291D02*
X626356Y398852D01*
G01X625279Y399414D02*
X674233Y446118D01*
G01X626356Y398852D02*
X674977Y445237D01*
G01X620958Y380366D02*
X623998Y400031D01*
G01X619870Y380862D02*
X622921Y400593D01*
G01X623998Y400031D02*
X677671Y451233D01*
G01X622921Y400593D02*
X677022Y452204D01*
G01X648184Y428162D02*
X675340Y454072D01*
G01X648978Y427329D02*
X675995Y453106D01*
G01X646762Y428686D02*
X675268Y455881D01*
G01X648978Y427329D02*
X675995Y453106D01*
G01X648184Y428162D02*
X675340Y454072D01*
G01X616882Y403286D02*
X617009Y404106D01*
G01X616882Y403286D02*
X617009Y404106D01*
G01X615730Y403360D02*
X615745Y403458D01*
G01X616882Y403286D02*
X617009Y404106D01*
G01X615745Y403462D02*
X615932Y404668D01*
G01X617009Y404106D02*
X673274Y457784D01*
G01X615932Y404668D02*
X629837Y417934D01*
G01X617009Y404106D02*
X673274Y457784D01*
G01X629837Y417934D02*
X629838D01*
G01X617009Y404106D02*
X673274Y457784D01*
G01X629838Y417934D02*
X672623Y458753D01*
G01X646762Y428686D02*
X675268Y455881D01*
G01X615730Y403360D02*
X615745Y403458D01*
G01X615730Y403360D02*
X615745Y403458D01*
G01Y403462D02*
X615932Y404668D01*
G01X616882Y403286D02*
X617009Y404106D01*
G01X615932Y404668D02*
X629837Y417934D01*
G01D02*
X629838D01*
G01D02*
X672623Y458753D01*
G01X617009Y404106D02*
X673274Y457784D01*
G01X659374Y584000D02*
X698165D01*
G01X698642Y585150D02*
X659851D01*
G01X646859Y596515D02*
X659374Y584000D01*
G01X659851Y585150D02*
X647336Y597665D01*
G01X659851Y585150D02*
X647336Y597665D01*
G01X646859Y596515D02*
X659374Y584000D01*
G01X698642Y585150D02*
X659851D01*
G01X659374Y584000D02*
X698165D01*
G01X627532Y596515D02*
X646859D01*
G01X647336Y597665D02*
X628009D01*
G01X624844Y599203D02*
X627532Y596515D01*
G01X628009Y597665D02*
X625321Y600353D01*
G01X628009Y597665D02*
X625321Y600353D01*
G01X624844Y599203D02*
X627532Y596515D01*
G01X647336Y597665D02*
X628009D01*
G01X627532Y596515D02*
X646859D01*
G01X666948Y132804D02*
X679658Y123594D01*
G01X667354Y133930D02*
X680186Y124633D01*
G01X679658Y123594D02*
X689829Y120304D01*
G01X680186Y124633D02*
X689985Y121463D01*
G01X689829Y120304D02*
X706967Y121030D01*
G01X689986Y121462D02*
X706967Y122181D01*
G01Y121030D02*
X761111Y123321D01*
G01X706967Y122181D02*
X760898Y124464D01*
G01X667114Y130536D02*
X679295Y121804D01*
G01X666704Y129414D02*
X678770Y120764D01*
G01X679295Y121804D02*
X689163Y118613D01*
G01X678770Y120764D02*
X689006Y117454D01*
G01X689163Y118612D02*
X760431Y121630D01*
G01X689006Y117454D02*
X760628Y120487D01*
G01X667354Y133930D02*
X680186Y124633D01*
G01X666948Y132804D02*
X679658Y123594D01*
G01X680186Y124633D02*
X689985Y121463D01*
G01X679658Y123594D02*
X689829Y120304D01*
G01X689986Y121462D02*
X706967Y122181D01*
G01X689829Y120304D02*
X706967Y121030D01*
G01Y122181D02*
X760898Y124464D01*
G01X706967Y121030D02*
X761111Y123321D01*
G01X666704Y129414D02*
X678770Y120764D01*
G01X667114Y130536D02*
X679295Y121804D01*
G01X678770Y120764D02*
X689006Y117454D01*
G01X679295Y121804D02*
X689163Y118613D01*
G01X689006Y117454D02*
X760628Y120487D01*
G01X689163Y118612D02*
X760431Y121630D01*
G01X740517Y143918D02*
X717900Y148283D01*
G01X740605Y145073D02*
X718117Y149412D01*
G01X717900Y148283D02*
X710498Y149711D01*
G01X718117Y149412D02*
X710880Y150809D01*
G01X710498Y149711D02*
X704019Y153072D01*
G01X710880Y150809D02*
X704578Y154078D01*
G01X704019Y153072D02*
X683073Y165515D01*
G01X704578Y154078D02*
X683500Y166600D01*
G01X740097Y141256D02*
X709728Y147046D01*
G01X740183Y142411D02*
X710130Y148141D01*
G01X709728Y147046D02*
X682315Y162596D01*
G01X710130Y148141D02*
X682700Y163700D01*
G01X708835Y145635D02*
X740130Y139642D01*
G01X740044Y138487D02*
X708438Y144540D01*
G01X680440Y161364D02*
X708835Y145635D01*
G01X708438Y144540D02*
X680098Y160238D01*
G01X739173Y135911D02*
X709202Y141563D01*
G01D02*
X708937Y141645D01*
G01X739258Y137066D02*
X709480Y142682D01*
G01X709202Y141563D02*
X708937Y141645D01*
G01X709480Y142682D02*
X709347Y142722D01*
G01X708937Y141645D02*
X703077Y144320D01*
G01X709347Y142722D02*
X706485Y144028D01*
G01X708937Y141645D02*
X703077Y144320D01*
G01X706485Y144030D02*
X703555Y145368D01*
G01X703077Y144320D02*
X702994Y144364D01*
G01D02*
X680016Y157196D01*
G01X703555Y145368D02*
X680400Y158300D01*
G01X738666Y134526D02*
X709042Y140106D01*
G01X738581Y133371D02*
X708763Y138988D01*
G01X738666Y134526D02*
X709042Y140106D01*
G01D02*
X708909Y140148D01*
G01X708763Y138988D02*
X708497Y139071D01*
G01X708909Y140148D02*
X701752Y143415D01*
G01X708497Y139071D02*
X701274Y142368D01*
G01X701752Y143415D02*
X679500Y155700D01*
G01X701274Y142368D02*
X701196Y142408D01*
G01X701752Y143415D02*
X679500Y155700D01*
G01X701196Y142408D02*
X679186Y154559D01*
G01X679500Y155700D02*
X667500Y156088D01*
G01X679186Y154559D02*
X667463Y154938D01*
G01D02*
X666325Y154951D01*
G01X738257Y131921D02*
X707405Y137006D01*
G01X738186Y130767D02*
X707140Y135884D01*
G01X738257Y131921D02*
X707405Y137006D01*
G01D02*
X707251Y137054D01*
G01X707140Y135884D02*
X706831Y135980D01*
G01X707251Y137054D02*
X691736Y144457D01*
G01X706831Y135980D02*
X691240Y143418D01*
G01X691736Y144457D02*
X678700Y152500D01*
G01X691132Y143478D02*
X678261Y151419D01*
G01X678700Y152500D02*
X676000Y153100D01*
G01X678261Y151419D02*
X675854Y151954D01*
G01X676000Y153100D02*
X670700Y153286D01*
G01D02*
X669911D01*
G01X675854Y151954D02*
X670660Y152136D01*
G01X676000Y153100D02*
X670700Y153286D01*
G01D02*
X669911D01*
G01X670660Y152136D02*
X669898D01*
G01X670700Y153286D02*
X669911D01*
G01X737811Y127990D02*
X703784Y131876D01*
G01D02*
X703419Y131945D01*
G01X737853Y129143D02*
X703956Y133014D01*
G01X737811Y127990D02*
X703784Y131876D01*
G01D02*
X703419Y131945D01*
G01D02*
X668400Y141700D01*
G01X703956Y133014D02*
X703681Y133066D01*
G01X703419Y131945D02*
X668400Y141700D01*
G01X703681Y133066D02*
X669000Y142727D01*
G01X668400Y141700D02*
X664300Y145800D01*
G01X669000Y142727D02*
X664822Y146905D01*
G01X759871Y126997D02*
X716418Y125397D01*
G01X760104Y125854D02*
X716289Y124241D01*
G01X716418Y125397D02*
X666186Y138761D01*
G01X716289Y124241D02*
X666000Y137620D01*
G01X741622Y146511D02*
X710525Y152482D01*
G01X741710Y147666D02*
X710938Y153574D01*
G01X710525Y152482D02*
X683377Y168524D01*
G01X710938Y153574D02*
X683888Y169558D01*
G01X740605Y145073D02*
X718117Y149412D01*
G01X740517Y143918D02*
X717900Y148283D01*
G01X718117Y149412D02*
X710880Y150809D01*
G01X717900Y148283D02*
X710498Y149711D01*
G01X710880Y150809D02*
X704578Y154078D01*
G01X710498Y149711D02*
X704019Y153072D01*
G01X704578Y154078D02*
X683500Y166600D01*
G01X704019Y153072D02*
X683073Y165515D01*
G01X740183Y142411D02*
X710130Y148141D01*
G01X740097Y141256D02*
X709728Y147046D01*
G01X710130Y148141D02*
X682700Y163700D01*
G01X709728Y147046D02*
X682315Y162596D01*
G01X708438Y144540D02*
X680098Y160238D01*
G01X680440Y161364D02*
X708835Y145635D01*
G01X740044Y138487D02*
X708438Y144540D01*
G01X708835Y145635D02*
X740130Y139642D01*
G01X739258Y137066D02*
X709480Y142682D01*
G01X739173Y135911D02*
X709202Y141563D01*
G01X739258Y137066D02*
X709480Y142682D01*
G01D02*
X709347Y142722D01*
G01X709202Y141563D02*
X708937Y141645D01*
G01X709347Y142722D02*
X706485Y144028D01*
G01Y144030D02*
X703555Y145368D01*
G01X708937Y141645D02*
X703077Y144320D01*
G01X703555Y145368D02*
X680400Y158300D01*
G01X703077Y144320D02*
X702994Y144364D01*
G01X703555Y145368D02*
X680400Y158300D01*
G01X702994Y144364D02*
X680016Y157196D01*
G01X738581Y133371D02*
X708763Y138988D01*
G01D02*
X708497Y139071D01*
G01X738666Y134526D02*
X709042Y140106D01*
G01X708763Y138988D02*
X708497Y139071D01*
G01X709042Y140106D02*
X708909Y140148D01*
G01X708497Y139071D02*
X701274Y142368D01*
G01X708909Y140148D02*
X701752Y143415D01*
G01X701274Y142368D02*
X701196Y142408D01*
G01D02*
X679186Y154559D01*
G01X701752Y143415D02*
X679500Y155700D01*
G01X679186Y154559D02*
X667463Y154938D01*
G01X679500Y155700D02*
X667500Y156088D01*
G01X667463Y154938D02*
X666325Y154951D01*
G01X738186Y130767D02*
X707140Y135884D01*
G01D02*
X706831Y135980D01*
G01X738257Y131921D02*
X707405Y137006D01*
G01X707140Y135884D02*
X706831Y135980D01*
G01X707405Y137006D02*
X707251Y137054D01*
G01X706831Y135980D02*
X691240Y143418D01*
G01X707251Y137054D02*
X691736Y144457D01*
G01X691132Y143478D02*
X678261Y151419D01*
G01X691736Y144457D02*
X678700Y152500D01*
G01X678261Y151419D02*
X675854Y151954D01*
G01X678700Y152500D02*
X676000Y153100D01*
G01X675854Y151954D02*
X670660Y152136D01*
G01D02*
X669898D01*
G01X676000Y153100D02*
X670700Y153286D01*
G01X675854Y151954D02*
X670660Y152136D01*
G01D02*
X669898D01*
G01X670700Y153286D02*
X669911D01*
G01X670660Y152136D02*
X669898D01*
G01X737853Y129143D02*
X703956Y133014D01*
G01X737853Y129143D02*
X703956Y133014D01*
G01D02*
X703681Y133066D01*
G01X737811Y127990D02*
X703784Y131876D01*
G01X737853Y129143D02*
X703956Y133014D01*
G01D02*
X703681Y133066D01*
G01X703784Y131876D02*
X703419Y131945D01*
G01X703956Y133014D02*
X703681Y133066D01*
G01D02*
X669000Y142727D01*
G01X703419Y131945D02*
X668400Y141700D01*
G01X669000Y142727D02*
X664822Y146905D01*
G01X668400Y141700D02*
X664300Y145800D01*
G01X760104Y125854D02*
X716289Y124241D01*
G01X759871Y126997D02*
X716418Y125397D01*
G01X716289Y124241D02*
X666000Y137620D01*
G01X716418Y125397D02*
X666186Y138761D01*
G01X741710Y147666D02*
X710938Y153574D01*
G01X741622Y146511D02*
X710525Y152482D01*
G01X710938Y153574D02*
X683888Y169558D01*
G01X710525Y152482D02*
X683377Y168524D01*
G01X683073Y165515D02*
X672824Y167739D01*
G01X683500Y166600D02*
X672900Y168900D01*
G01X682315Y162596D02*
X672439Y164145D01*
G01X682700Y163700D02*
X672500Y165300D01*
G01X672809Y162000D02*
X680440Y161364D01*
G01X680098Y160238D02*
X672761Y160850D01*
G01X665345Y162000D02*
X672809D01*
G01X672761Y160850D02*
X665336D01*
G01X663274Y162030D02*
X665345Y162000D01*
G01X665336Y160850D02*
X663265Y160880D01*
G01X680016Y157196D02*
X674729Y158046D01*
G01X680400Y158300D02*
X674800Y159200D01*
G01X674729Y158046D02*
X670641Y157900D01*
G01X674800Y159200D02*
X670600Y159050D01*
G01X670641Y157900D02*
X665300D01*
G01X670600Y159050D02*
X665309D01*
G01X725465Y167686D02*
X715492Y166049D01*
G01D02*
X715462Y166045D01*
G01D02*
X715127Y165989D01*
G01X725351Y168833D02*
X715234Y167173D01*
G01X715127Y165989D02*
X663736Y184441D01*
G01X715234Y167173D02*
X664039Y185555D01*
G01X739684Y162096D02*
X713435Y164742D01*
G01X739842Y160924D02*
X713176Y163612D01*
G01X740928Y154156D02*
X717300Y160600D01*
G01X741294Y155249D02*
X717490Y161741D01*
G01X717300Y160600D02*
X713526Y160841D01*
G01X717490Y161741D02*
X713762Y161979D01*
G01X713526Y160841D02*
X690381Y169179D01*
G01X713762Y161979D02*
X690771Y170262D01*
G01X690381Y169179D02*
X688431Y169882D01*
G01X690771Y170262D02*
X688763Y170986D01*
G01X688431Y169882D02*
X665194Y178256D01*
G01X688763Y170986D02*
X665584Y179338D01*
G01X683377Y168524D02*
X676271Y171402D01*
G01D02*
X676262Y171406D01*
G01X683888Y169558D02*
X676721Y172461D01*
G01X683377Y168524D02*
X676271Y171402D01*
G01X676721Y172461D02*
X676691Y172474D01*
G01X676262Y171406D02*
X667785Y174464D01*
G01X676691Y172474D02*
X668176Y175546D01*
G01X667785Y174464D02*
X665832Y175169D01*
G01X668176Y175546D02*
X666223Y176251D01*
G01X683500Y166600D02*
X672900Y168900D01*
G01X683073Y165515D02*
X672824Y167739D01*
G01X682700Y163700D02*
X672500Y165300D01*
G01X682315Y162596D02*
X672439Y164145D01*
G01X665336Y160850D02*
X663265Y160880D01*
G01X663274Y162030D02*
X665345Y162000D01*
G01X672761Y160850D02*
X665336D01*
G01X665345Y162000D02*
X672809D01*
G01X680098Y160238D02*
X672761Y160850D01*
G01X672809Y162000D02*
X680440Y161364D01*
G01X680400Y158300D02*
X674800Y159200D01*
G01X680016Y157196D02*
X674729Y158046D01*
G01X674800Y159200D02*
X670600Y159050D01*
G01X674729Y158046D02*
X670641Y157900D01*
G01X670600Y159050D02*
X665309D01*
G01X670641Y157900D02*
X665300D01*
G01X725841Y171702D02*
X715305Y170042D01*
G01D02*
X715244Y170033D01*
G01X725944Y170554D02*
X715305Y168878D01*
G01Y170042D02*
X715244Y170033D01*
G01X715240Y170032D02*
X665515Y187805D01*
G01X715129Y168850D02*
X665201Y186695D01*
G01X725351Y168833D02*
X715234Y167173D01*
G01X725465Y167686D02*
X715492Y166049D01*
G01X725351Y168833D02*
X715234Y167173D01*
G01X715492Y166049D02*
X715462Y166045D01*
G01X725351Y168833D02*
X715234Y167173D01*
G01X715462Y166045D02*
X715127Y165989D01*
G01X715234Y167173D02*
X664039Y185555D01*
G01X715127Y165989D02*
X663736Y184441D01*
G01X739842Y160924D02*
X713176Y163612D01*
G01X739684Y162096D02*
X713435Y164742D01*
G01X741294Y155249D02*
X717490Y161741D01*
G01X740928Y154156D02*
X717300Y160600D01*
G01X717490Y161741D02*
X713762Y161979D01*
G01X717300Y160600D02*
X713526Y160841D01*
G01X713762Y161979D02*
X690771Y170262D01*
G01X713526Y160841D02*
X690381Y169179D01*
G01X690771Y170262D02*
X688763Y170986D01*
G01X690381Y169179D02*
X688431Y169882D01*
G01X688763Y170986D02*
X665584Y179338D01*
G01X688431Y169882D02*
X665194Y178256D01*
G01X683888Y169558D02*
X676721Y172461D01*
G01D02*
X676691Y172474D01*
G01X683377Y168524D02*
X676271Y171402D01*
G01X683888Y169558D02*
X676721Y172461D01*
G01X676271Y171402D02*
X676262Y171406D01*
G01X676691Y172474D02*
X668176Y175546D01*
G01X676262Y171406D02*
X667785Y174464D01*
G01X668176Y175546D02*
X666223Y176251D01*
G01X667785Y174464D02*
X665832Y175169D01*
G01X727645Y183882D02*
X716246Y183476D01*
G01X727621Y185032D02*
X716411Y184633D01*
G01X716246Y183476D02*
X706967Y186533D01*
G01X716411Y184633D02*
X706967Y187744D01*
G01Y186533D02*
X691772Y191539D01*
G01D02*
X691758Y191543D01*
G01X691754Y191544D02*
X691740Y191549D01*
G01D02*
X691735Y191551D01*
G01X706967Y187744D02*
X692132Y192631D01*
G01X706967Y186533D02*
X691772Y191539D01*
G01X691735Y191551D02*
X667439Y199871D01*
G01X692132Y192631D02*
X692110Y192639D01*
G01X706967Y186533D02*
X691772Y191539D01*
G01X692110Y192639D02*
X692102Y192641D01*
G01X691772Y191539D02*
X691758Y191543D01*
G01X691754Y191544D02*
X691740Y191549D01*
G01X691735Y191551D02*
X667439Y199871D01*
G01X692102Y192641D02*
X667756Y200979D01*
G01X725641Y181204D02*
X716145Y180511D01*
G01X725594Y182354D02*
X716294Y181675D01*
G01X716145Y180511D02*
X667085Y197190D01*
G01X716294Y181675D02*
X667394Y198300D01*
G01X726431Y179852D02*
X716250Y178766D01*
G01X726431Y179852D02*
X716250Y178766D01*
G01X725865Y178635D02*
X716117Y177595D01*
G01X726431Y179852D02*
X716250Y178766D01*
G01D02*
X667399Y195597D01*
G01X716117Y177595D02*
X715874Y177678D01*
G01X716250Y178766D02*
X667399Y195597D01*
G01X715874Y177679D02*
X667095Y194485D01*
G01X725603Y177177D02*
X715791Y175808D01*
G01X725689Y176027D02*
X715675Y174630D01*
G01X715791Y175808D02*
X665599Y193281D01*
G01X715675Y174630D02*
X665292Y192170D01*
G01X725559Y173289D02*
X715781Y171656D01*
G01X725453Y174438D02*
X715883Y172840D01*
G01X715781Y171656D02*
X664444Y189690D01*
G01X715883Y172840D02*
X664756Y190800D01*
G01X725944Y170554D02*
X715305Y168878D01*
G01X725841Y171702D02*
X715305Y170042D01*
G01X725944Y170554D02*
X715305Y168878D01*
G01X715129Y168850D02*
X665201Y186695D01*
G01X715305Y170042D02*
X715244Y170033D01*
G01X715129Y168850D02*
X665201Y186695D01*
G01X715240Y170032D02*
X665515Y187805D01*
G01X727621Y185032D02*
X716411Y184633D01*
G01X727645Y183882D02*
X716246Y183476D01*
G01X716411Y184633D02*
X706967Y187744D01*
G01X716246Y183476D02*
X706967Y186533D01*
G01Y187744D02*
X692132Y192631D01*
G01D02*
X692110Y192639D01*
G01D02*
X692102Y192641D01*
G01X706967Y186533D02*
X691772Y191539D01*
G01X706967Y187744D02*
X692132Y192631D01*
G01X692102Y192641D02*
X667756Y200979D01*
G01X691772Y191539D02*
X691758Y191543D01*
G01X706967Y187744D02*
X692132Y192631D01*
G01X692102Y192641D02*
X667756Y200979D01*
G01X691754Y191544D02*
X691740Y191549D01*
G01X706967Y187744D02*
X692132Y192631D01*
G01X691740Y191549D02*
X691735Y191551D01*
G01X692132Y192631D02*
X692110Y192639D01*
G01X692102Y192641D02*
X667756Y200979D01*
G01X691735Y191551D02*
X667439Y199871D01*
G01X725594Y182354D02*
X716294Y181675D01*
G01X725641Y181204D02*
X716145Y180511D01*
G01X716294Y181675D02*
X667394Y198300D01*
G01X716145Y180511D02*
X667085Y197190D01*
G01X725865Y178635D02*
X716117Y177595D01*
G01D02*
X715874Y177678D01*
G01X726431Y179852D02*
X716250Y178766D01*
G01X716117Y177595D02*
X715874Y177678D01*
G01Y177679D02*
X667095Y194485D01*
G01X716250Y178766D02*
X667399Y195597D01*
G01X725689Y176027D02*
X715675Y174630D01*
G01X725603Y177177D02*
X715791Y175808D01*
G01X715675Y174630D02*
X665292Y192170D01*
G01X715791Y175808D02*
X665599Y193281D01*
G01X725453Y174438D02*
X715883Y172840D01*
G01X725559Y173289D02*
X715781Y171656D01*
G01X715883Y172840D02*
X664756Y190800D01*
G01X715781Y171656D02*
X664444Y189690D01*
G01X740028Y192500D02*
X724250Y208278D01*
G01D02*
Y228685D01*
G01X740028Y192500D02*
X724250Y208278D01*
G01D02*
Y228685D01*
G01X725400Y229162D02*
X722298Y232264D01*
G01X720424Y234138D02*
X719470Y235092D01*
G01X717596Y236966D02*
X715012Y239550D01*
G01X724250Y228685D02*
X714535Y238400D01*
G01X715012Y239550D02*
X704581D01*
G01X714535Y238400D02*
X704104D01*
G01X704581Y239550D02*
X702966Y241165D01*
G01X704104Y238400D02*
X702489Y240015D01*
G01X702966Y241165D02*
X699250D01*
G01X702489Y240015D02*
X698773D01*
G01X699250Y241165D02*
X697335Y243080D01*
G01X698773Y240015D02*
X696185Y242603D01*
G01X697335Y243080D02*
Y244430D01*
G01Y247080D02*
Y248430D01*
G01Y251080D02*
Y252430D01*
G01Y255080D02*
Y256430D01*
G01Y259080D02*
Y264112D01*
G01X696185Y242603D02*
Y263635D01*
G01X697335Y264112D02*
X693847Y267600D01*
G01X696185Y263635D02*
X692697Y267123D01*
G01X693847Y267600D02*
Y278255D01*
G01X692697Y267123D02*
Y278732D01*
G01X693847Y278255D02*
X698250Y282658D01*
G01X692697Y278732D02*
X697100Y283135D01*
G01X724250Y228685D02*
X714535Y238400D01*
G01X725400Y229162D02*
X722298Y232264D01*
G01X724250Y228685D02*
X714535Y238400D01*
G01X720424Y234138D02*
X719470Y235092D01*
G01X724250Y228685D02*
X714535Y238400D01*
G01X717596Y236966D02*
X715012Y239550D01*
G01X714535Y238400D02*
X704104D01*
G01X715012Y239550D02*
X704581D01*
G01X704104Y238400D02*
X702489Y240015D01*
G01X704581Y239550D02*
X702966Y241165D01*
G01X702489Y240015D02*
X698773D01*
G01X702966Y241165D02*
X699250D01*
G01X698773Y240015D02*
X696185Y242603D01*
G01X699250Y241165D02*
X697335Y243080D01*
G01X696185Y242603D02*
Y263635D01*
G01X697335Y243080D02*
Y244430D01*
G01X696185Y242603D02*
Y263635D01*
G01X697335Y247080D02*
Y248430D01*
G01X696185Y242603D02*
Y263635D01*
G01X697335Y251080D02*
Y252430D01*
G01X696185Y242603D02*
Y263635D01*
G01X697335Y255080D02*
Y256430D01*
G01X696185Y242603D02*
Y263635D01*
G01X697335Y259080D02*
Y264112D01*
G01X696185Y263635D02*
X692697Y267123D01*
G01X697335Y264112D02*
X693847Y267600D01*
G01X692697Y267123D02*
Y278732D01*
G01X693847Y267600D02*
Y278255D01*
G01X692697Y278732D02*
X697100Y283135D01*
G01X693847Y278255D02*
X698250Y282658D01*
G01X728500Y231394D02*
X723745Y236149D01*
G01X727350Y230917D02*
X722595Y235672D01*
G01X723745Y236149D02*
Y243746D01*
G01X722595Y235672D02*
Y244223D01*
G01X723745Y243746D02*
X725417Y245418D01*
G01X722595Y244223D02*
X724940Y246568D01*
G01X728202Y251028D02*
X724760Y254470D01*
G01X725237Y255620D02*
X711737D01*
G01X724760Y254470D02*
X711260D01*
G01X711737Y255620D02*
X707750Y259607D01*
G01X711260Y254470D02*
X706600Y259130D01*
G01X707750Y259607D02*
Y268676D01*
G01X706600Y259130D02*
Y268199D01*
G01X707750Y268676D02*
X701786Y274640D01*
G01X706600Y268199D02*
X700636Y274163D01*
G01X701786Y274640D02*
Y296094D01*
G01X700636Y274163D02*
Y295617D01*
G01X727350Y230917D02*
X722595Y235672D01*
G01X728500Y231394D02*
X723745Y236149D01*
G01X722595Y235672D02*
Y244223D01*
G01X723745Y236149D02*
Y243746D01*
G01X722595Y244223D02*
X724940Y246568D01*
G01X723745Y243746D02*
X725417Y245418D01*
G01X728202Y251028D02*
X724760Y254470D01*
G01D02*
X711260D01*
G01X725237Y255620D02*
X711737D01*
G01X711260Y254470D02*
X706600Y259130D01*
G01X711737Y255620D02*
X707750Y259607D01*
G01X706600Y259130D02*
Y268199D01*
G01X707750Y259607D02*
Y268676D01*
G01X706600Y268199D02*
X700636Y274163D01*
G01X707750Y268676D02*
X701786Y274640D01*
G01X700636Y274163D02*
Y295617D01*
G01X701786Y274640D02*
Y296094D01*
G01X726230Y263270D02*
X719576D01*
G01X725753Y262120D02*
X719099D01*
G01X719576Y263270D02*
X713927Y268919D01*
G01X719099Y262120D02*
X712777Y268442D01*
G01X713927Y268919D02*
Y283601D01*
G01X712777Y268442D02*
Y283124D01*
G01X725753Y262120D02*
X719099D01*
G01X726230Y263270D02*
X719576D01*
G01X719099Y262120D02*
X712777Y268442D01*
G01X719576Y263270D02*
X713927Y268919D01*
G01X712777Y268442D02*
Y283124D01*
G01X713927Y268919D02*
Y283601D01*
G01X698250Y282658D02*
Y291460D01*
G01X697100Y283135D02*
Y290983D01*
G01X698250Y291460D02*
X692300Y297410D01*
G01X697100Y290983D02*
X691150Y296933D01*
G01X692300Y297410D02*
Y300883D01*
G01X691150Y296933D02*
Y301360D01*
G01X692300Y300883D02*
X693910Y302493D01*
G01X691150Y301360D02*
X693433Y303643D01*
G01X693910Y302493D02*
X694976D01*
G01X693433Y303643D02*
X695414D01*
G01X697100Y283135D02*
Y290983D01*
G01X698250Y282658D02*
Y291460D01*
G01X697100Y290983D02*
X691150Y296933D01*
G01X698250Y291460D02*
X692300Y297410D01*
G01X691150Y296933D02*
Y301360D01*
G01X692300Y297410D02*
Y300883D01*
G01X691150Y301360D02*
X693433Y303643D01*
G01X692300Y300883D02*
X693910Y302493D01*
G01X693433Y303643D02*
X695414D01*
G01X693910Y302493D02*
X694976D01*
G01X701786Y296094D02*
X700645Y297235D01*
G01X700636Y295617D02*
X699495Y296758D01*
G01X700645Y297235D02*
Y307471D01*
G01X699495Y296758D02*
Y306994D01*
G01X700645Y307471D02*
X696528Y311588D01*
G01X699495Y306994D02*
X696051Y310438D01*
G01X696528Y311588D02*
X689416D01*
G01X696051Y310438D02*
X688939D01*
G01X689416Y311588D02*
X684800Y316204D01*
G01X688939Y310438D02*
X683650Y315727D01*
G01X684800Y316204D02*
Y334300D01*
G01X683650Y315727D02*
Y333823D01*
G01X684800Y334300D02*
X672068Y347032D01*
G01X683650Y333823D02*
X670918Y346555D01*
G01X700636Y295617D02*
X699495Y296758D01*
G01X701786Y296094D02*
X700645Y297235D01*
G01X699495Y296758D02*
Y306994D01*
G01X700645Y297235D02*
Y307471D01*
G01X699495Y306994D02*
X696051Y310438D01*
G01X700645Y307471D02*
X696528Y311588D01*
G01X696051Y310438D02*
X688939D01*
G01X696528Y311588D02*
X689416D01*
G01X688939Y310438D02*
X683650Y315727D01*
G01X689416Y311588D02*
X684800Y316204D01*
G01X683650Y315727D02*
Y333823D01*
G01X684800Y316204D02*
Y334300D01*
G01X683650Y333823D02*
X670918Y346555D01*
G01X684800Y334300D02*
X672068Y347032D01*
G01X713927Y283601D02*
X708085Y289443D01*
G01X712777Y283124D02*
X706935Y288966D01*
G01X708085Y289443D02*
Y295505D01*
G01X706935Y288966D02*
Y295028D01*
G01X708085Y295505D02*
X703833Y299757D01*
G01X706935Y295028D02*
X702683Y299280D01*
G01X703833Y299757D02*
Y308688D01*
G01X702683Y299280D02*
Y308211D01*
G01X703833Y308688D02*
X696608Y315913D01*
G01X702683Y308211D02*
X696131Y314763D01*
G01X696608Y315913D02*
X693987D01*
G01X696131Y314763D02*
X693510D01*
G01X693987Y315913D02*
X691873Y318027D01*
G01X693510Y314763D02*
X690723Y317550D01*
G01X691873Y318027D02*
Y336114D01*
G01X690723Y317550D02*
Y335637D01*
G01X691873Y336114D02*
X687054Y340933D01*
G01X690723Y335637D02*
X681210Y345150D01*
G01X712777Y283124D02*
X706935Y288966D01*
G01X713927Y283601D02*
X708085Y289443D01*
G01X706935Y288966D02*
Y295028D01*
G01X708085Y289443D02*
Y295505D01*
G01X706935Y295028D02*
X702683Y299280D01*
G01X708085Y295505D02*
X703833Y299757D01*
G01X702683Y299280D02*
Y308211D01*
G01X703833Y299757D02*
Y308688D01*
G01X702683Y308211D02*
X696131Y314763D01*
G01X703833Y308688D02*
X696608Y315913D01*
G01X696131Y314763D02*
X693510D01*
G01X696608Y315913D02*
X693987D01*
G01X693510Y314763D02*
X690723Y317550D01*
G01X693987Y315913D02*
X691873Y318027D01*
G01X690723Y317550D02*
Y335637D01*
G01X691873Y318027D02*
Y336114D01*
G01X690723Y335637D02*
X681210Y345150D01*
G01X691873Y336114D02*
X687054Y340933D01*
G01X690723Y335637D02*
X681210Y345150D01*
G01X717449Y369649D02*
Y321714D01*
G01X716299Y370126D02*
Y322191D01*
G01X717449Y321714D02*
X708440Y312705D01*
G01X716299Y322191D02*
X707963Y313855D01*
G01X717449Y321714D02*
X708440Y312705D01*
G01D02*
X706234D01*
G01X707963Y313855D02*
X706424D01*
G01X716299Y370126D02*
Y322191D01*
G01X717449Y369649D02*
Y321714D01*
G01X716299Y322191D02*
X707963Y313855D01*
G01D02*
X706424D01*
G01X717449Y321714D02*
X708440Y312705D01*
G01X707963Y313855D02*
X706424D01*
G01X708440Y312705D02*
X706234D01*
G01X710039Y366739D02*
Y332381D01*
G01X708889Y367216D02*
Y332858D01*
G01X710039Y332381D02*
X700033Y322375D01*
G01X708889Y332858D02*
X699556Y323525D01*
G01X710039Y332381D02*
X700033Y322375D01*
G01D02*
X697971D01*
G01X699556Y323525D02*
X697972D01*
G01X708889Y367216D02*
Y332858D01*
G01X710039Y366739D02*
Y332381D01*
G01X708889Y332858D02*
X699556Y323525D01*
G01D02*
X697972D01*
G01X710039Y332381D02*
X700033Y322375D01*
G01X699556Y323525D02*
X697972D01*
G01X700033Y322375D02*
X697971D01*
G01X705111Y339334D02*
Y337984D01*
G01X703961Y366688D02*
Y338461D01*
G01X705111Y337984D02*
X699552Y332425D01*
G01X703961Y338461D02*
X699075Y333575D01*
G01X699552Y332425D02*
X697802D01*
G01X699075Y333575D02*
X697802D01*
G01X703961Y366688D02*
Y338461D01*
G01Y366688D02*
Y338461D01*
G01X705111Y339334D02*
Y337984D01*
G01X703961Y338461D02*
X699075Y333575D01*
G01X705111Y337984D02*
X699552Y332425D01*
G01X699075Y333575D02*
X697802D01*
G01X699552Y332425D02*
X697802D01*
G01X682847Y396794D02*
X697467Y399694D01*
G01X682267Y397852D02*
X689934Y399373D01*
G01X682847Y396794D02*
X697467Y399694D01*
G01X689934Y399373D02*
X696956Y400766D01*
G01X697467Y399694D02*
X702263Y403684D01*
G01X696956Y400766D02*
X701821Y404813D01*
G01X680543Y400070D02*
X695841Y403105D01*
G01X681123Y399012D02*
X696352Y402033D01*
G01D02*
X701510Y406322D01*
G01X682267Y397852D02*
X689934Y399373D01*
G01D02*
X696956Y400766D01*
G01X682847Y396794D02*
X697467Y399694D01*
G01X696956Y400766D02*
X701821Y404813D01*
G01X697467Y399694D02*
X702263Y403684D01*
G01X681123Y399012D02*
X696352Y402033D01*
G01X680543Y400070D02*
X695841Y403105D01*
G01X696352Y402033D02*
X701510Y406322D01*
G01X679332Y401214D02*
X695237Y404373D01*
G01X678752Y402272D02*
X694726Y405444D01*
G01X679332Y401214D02*
X695237Y404373D01*
G01X678752Y402272D02*
X694726Y405444D01*
G01X679332Y401214D02*
X695237Y404373D01*
G01X672068Y347032D02*
Y350418D01*
G01X670918Y346555D02*
Y350298D01*
G01Y346555D02*
Y350298D01*
G01X672068Y347032D02*
Y350418D01*
G01X685180Y342807D02*
X682360Y345627D01*
G01D02*
Y350330D01*
G01X681210Y345150D02*
Y350170D01*
G01X685180Y342807D02*
X682360Y345627D01*
G01X681210Y345150D02*
Y350170D01*
G01X682360Y345627D02*
Y350330D01*
G01X747079Y399279D02*
X717449Y369649D01*
G01X746602Y400429D02*
X716299Y370126D01*
G01X746602Y400429D02*
X716299Y370126D01*
G01X747079Y399279D02*
X717449Y369649D01*
G01X745810Y402510D02*
X710039Y366739D01*
G01X745333Y403660D02*
X708889Y367216D01*
G01X745333Y403660D02*
X708889Y367216D01*
G01X745810Y402510D02*
X710039Y366739D01*
G01X744584Y405684D02*
X705111Y366211D01*
G01X744107Y406834D02*
X703961Y366688D01*
G01X705111Y366211D02*
Y341984D01*
G01X744107Y406834D02*
X703961Y366688D01*
G01X744584Y405684D02*
X705111Y366211D01*
G01D02*
Y341984D01*
G01X702263Y403684D02*
X708553Y404011D01*
G01X701821Y404813D02*
X708380Y405154D01*
G01X708553Y404011D02*
X716124Y405938D01*
G01X708380Y405154D02*
X715633Y407000D01*
G01X716124Y405938D02*
X724620Y411967D01*
G01X715633Y407000D02*
X724192Y413074D01*
G01X724620Y411967D02*
X759270Y416180D01*
G01X724192Y413074D02*
X758864Y417290D01*
G01X732787Y462018D02*
X677750Y437433D01*
G01X677099Y438403D02*
X732569Y463181D01*
G01X677983Y441127D02*
X726265Y462882D01*
G01X725851Y463957D02*
X677331Y442095D01*
G01X675340Y454072D02*
X690773Y461149D01*
G01X675995Y453106D02*
X691252Y460103D01*
G01X690773Y461149D02*
X706782Y468491D01*
G01X691252Y460103D02*
X707261Y467444D01*
G01X675268Y455881D02*
X690848Y462840D01*
G01X674617Y456851D02*
X690378Y463891D01*
G01X690848Y462840D02*
X713120Y472789D01*
G01X690378Y463891D02*
X712720Y473870D01*
G01X695841Y403105D02*
X701069Y407451D01*
G01D02*
X708032Y407813D01*
G01X701510Y406322D02*
X708205Y406670D01*
G01X708032Y407813D02*
X714668Y409502D01*
G01X708205Y406670D02*
X715159Y408440D01*
G01X714668Y409502D02*
X722742Y415228D01*
G01X715159Y408440D02*
X723170Y414121D01*
G01X722742Y415228D02*
X757660Y419475D01*
G01X723170Y414121D02*
X758068Y418365D01*
G01X663673Y417770D02*
X687857Y426207D01*
G01X664293Y416768D02*
X688443Y425192D01*
G01X687873Y426203D02*
X689330Y427044D01*
G01X688448Y425207D02*
X690008Y426107D01*
G01X689330Y427044D02*
X702404Y438732D01*
G01X690008Y426107D02*
X703051Y437767D01*
G01X702404Y438732D02*
X732455Y453339D01*
G01X703051Y437767D02*
X732778Y452217D01*
G01X701821Y404813D02*
X708380Y405154D01*
G01X702263Y403684D02*
X708553Y404011D01*
G01X708380Y405154D02*
X715633Y407000D01*
G01X708553Y404011D02*
X716124Y405938D01*
G01X715633Y407000D02*
X724192Y413074D01*
G01X716124Y405938D02*
X724620Y411967D01*
G01X724192Y413074D02*
X758864Y417290D01*
G01X724620Y411967D02*
X759270Y416180D01*
G01X678572Y434750D02*
X689459Y439574D01*
G01X677922Y435721D02*
X689151Y440696D01*
G01X689459Y439574D02*
X698891Y440702D01*
G01X689151Y440696D02*
X698572Y441823D01*
G01X698891Y440702D02*
X730110Y455215D01*
G01X698572Y441823D02*
X729808Y456344D01*
G01X677099Y438403D02*
X732569Y463181D01*
G01X732787Y462018D02*
X677750Y437433D01*
G01X725851Y463957D02*
X677331Y442095D01*
G01X677983Y441127D02*
X726265Y462882D01*
G01X675995Y453106D02*
X691252Y460103D01*
G01X675340Y454072D02*
X690773Y461149D01*
G01X691252Y460103D02*
X707261Y467444D01*
G01X690773Y461149D02*
X706782Y468491D01*
G01X695841Y403105D02*
X701069Y407451D01*
G01X701510Y406322D02*
X708205Y406670D01*
G01X701069Y407451D02*
X708032Y407813D01*
G01X708205Y406670D02*
X715159Y408440D01*
G01X708032Y407813D02*
X714668Y409502D01*
G01X715159Y408440D02*
X723170Y414121D01*
G01X714668Y409502D02*
X722742Y415228D01*
G01X723170Y414121D02*
X758068Y418365D01*
G01X722742Y415228D02*
X757660Y419475D01*
G01X677110Y410605D02*
X697964Y417880D01*
G01X676470Y411601D02*
X687158Y415330D01*
G01X677110Y410605D02*
X697964Y417880D01*
G01X687158Y415329D02*
X697378Y418894D01*
G01X697964Y417880D02*
X705016Y423966D01*
G01X697378Y418894D02*
X704410Y424963D01*
G01X705016Y423966D02*
X707980Y425153D01*
G01X707982Y425154D02*
X707983D01*
G01X704410Y424963D02*
X707671Y426269D01*
G01X707982Y425154D02*
X707983D01*
G01Y425153D02*
X723566Y427645D01*
G01X707671Y426269D02*
X723500Y428800D01*
G01X723566Y427645D02*
X741467Y426859D01*
G01X723500Y428800D02*
X741569Y428006D01*
G01X664293Y416768D02*
X688443Y425192D01*
G01X663673Y417770D02*
X687857Y426207D01*
G01X688448Y425207D02*
X690008Y426107D01*
G01X687873Y426203D02*
X689330Y427044D01*
G01X690008Y426107D02*
X703051Y437767D01*
G01X689330Y427044D02*
X702404Y438732D01*
G01X703051Y437767D02*
X732778Y452217D01*
G01X702404Y438732D02*
X732455Y453339D01*
G01X677235Y443882D02*
X726640Y465938D01*
G01X676584Y444852D02*
X726238Y467019D01*
G01X673274Y457784D02*
X711599Y474946D01*
G01X672623Y458753D02*
X711199Y476027D01*
G01X670284Y460642D02*
X709116Y477999D01*
G01X670939Y459674D02*
X709516Y476918D01*
G01X674617Y456851D02*
X690378Y463891D01*
G01X675268Y455881D02*
X690848Y462840D01*
G01X690378Y463891D02*
X712720Y473870D01*
G01X690848Y462840D02*
X713120Y472789D01*
G01X672623Y458753D02*
X711199Y476027D01*
G01X673274Y457784D02*
X711599Y474946D01*
G01X670939Y459674D02*
X709516Y476918D01*
G01X670284Y460642D02*
X709116Y477999D01*
G01X677922Y435721D02*
X689151Y440696D01*
G01X678572Y434750D02*
X689459Y439574D01*
G01X689151Y440696D02*
X698572Y441823D01*
G01X689459Y439574D02*
X698891Y440702D01*
G01X698572Y441823D02*
X729808Y456344D01*
G01X698891Y440702D02*
X730110Y455215D01*
G01X695237Y404373D02*
X700337Y408615D01*
G01X694726Y405444D02*
X694725D01*
G01X695237Y404373D02*
X700337Y408615D01*
G01X694725Y405444D02*
X699895Y409745D01*
G01X700337Y408615D02*
X707501Y408987D01*
G01X699895Y409745D02*
X707327Y410130D01*
G01X707501Y408987D02*
X713729Y410571D01*
G01X707327Y410130D02*
X713241Y411636D01*
G01X713729Y410571D02*
X721792Y416290D01*
G01X713241Y411636D02*
X721365Y417398D01*
G01X721792Y416290D02*
X756423Y420501D01*
G01X721365Y417398D02*
X756015Y421611D01*
G01X677234Y404530D02*
X693611Y407782D01*
G01D02*
X693610D01*
G01X677814Y403472D02*
X694122Y406711D01*
G01X693611Y407782D02*
X693610D01*
G01D02*
X698933Y412207D01*
G01X694122Y406711D02*
X699374Y411078D01*
G01X698933Y412207D02*
X706782Y412615D01*
G01X699374Y411078D02*
X706967Y411473D01*
G01X706782Y412615D02*
X711898Y414028D01*
G01X706967Y411473D02*
X712388Y412969D01*
G01X711898Y414028D02*
X720032Y419557D01*
G01X712388Y412969D02*
X720448Y418449D01*
G01X720032Y419557D02*
X755032Y423820D01*
G01X720448Y418449D02*
X755499Y422718D01*
G01X676262Y405722D02*
X684127Y407283D01*
G01Y407285D02*
X691994Y408848D01*
G01X675682Y406780D02*
X691472Y409917D01*
G01X691994Y408848D02*
X707122Y421896D01*
G01X691472Y409917D02*
X706621Y422984D01*
G01X707122Y421896D02*
X721067Y424020D01*
G01X706621Y422984D02*
X720979Y425170D01*
G01X721067Y424020D02*
X746407D01*
G01X720979Y425170D02*
X746309D01*
G01X676470Y411601D02*
X687158Y415330D01*
G01Y415329D02*
X697378Y418894D01*
G01X677110Y410605D02*
X697964Y417880D01*
G01X697378Y418894D02*
X704410Y424963D01*
G01X697964Y417880D02*
X705016Y423966D01*
G01X704410Y424963D02*
X707671Y426269D01*
G01X705016Y423966D02*
X707980Y425153D01*
G01X704410Y424963D02*
X707671Y426269D01*
G01D02*
X723500Y428800D01*
G01X707982Y425154D02*
X707983D01*
G01X707671Y426269D02*
X723500Y428800D01*
G01X707983Y425153D02*
X723566Y427645D01*
G01X723500Y428800D02*
X741569Y428006D01*
G01X723566Y427645D02*
X741467Y426859D01*
G01X675549Y412719D02*
X675550Y412720D01*
G01D02*
X695585Y419708D01*
G01X674910Y413716D02*
X694999Y420723D01*
G01X695585Y419708D02*
X702616Y425774D01*
G01X694999Y420723D02*
X702007Y426768D01*
G01X702616Y425774D02*
X706094Y427195D01*
G01X702007Y426768D02*
X705752Y428298D01*
G01X706094Y427195D02*
X726994Y431738D01*
G01X705752Y428298D02*
X726738Y432860D01*
G01X667382Y413747D02*
X692620Y422552D01*
G01X668004Y412746D02*
X693206Y421537D01*
G01X692620Y422552D02*
X701627Y430322D01*
G01X693206Y421537D02*
X702219Y429313D01*
G01X701627Y430322D02*
X748551Y447440D01*
G01X702219Y429313D02*
X748946Y446360D01*
G01X666097Y414739D02*
X690825Y423365D01*
G01X665477Y415741D02*
X690239Y424380D01*
G01X690825Y423365D02*
X703818Y434572D01*
G01X690239Y424380D02*
X703173Y435536D01*
G01X703818Y434572D02*
X734110Y449869D01*
G01X703173Y435536D02*
X733797Y451000D01*
G01X676584Y444852D02*
X726238Y467019D01*
G01X677235Y443882D02*
X726640Y465938D01*
G01X694726Y405444D02*
X694725D01*
G01X694726D02*
X694725D01*
G01D02*
X699895Y409745D01*
G01X695237Y404373D02*
X700337Y408615D01*
G01X699895Y409745D02*
X707327Y410130D01*
G01X700337Y408615D02*
X707501Y408987D01*
G01X707327Y410130D02*
X713241Y411636D01*
G01X707501Y408987D02*
X713729Y410571D01*
G01X713241Y411636D02*
X721365Y417398D01*
G01X713729Y410571D02*
X721792Y416290D01*
G01X721365Y417398D02*
X756015Y421611D01*
G01X721792Y416290D02*
X756423Y420501D01*
G01X677814Y403472D02*
X694122Y406711D01*
G01X677234Y404530D02*
X693611Y407782D01*
G01X677814Y403472D02*
X694122Y406711D01*
G01D02*
X699374Y411078D01*
G01X693611Y407782D02*
X693610D01*
G01X694122Y406711D02*
X699374Y411078D01*
G01X693610Y407782D02*
X698933Y412207D01*
G01X699374Y411078D02*
X706967Y411473D01*
G01X698933Y412207D02*
X706782Y412615D01*
G01X706967Y411473D02*
X712388Y412969D01*
G01X706782Y412615D02*
X711898Y414028D01*
G01X712388Y412969D02*
X720448Y418449D01*
G01X711898Y414028D02*
X720032Y419557D01*
G01X720448Y418449D02*
X755499Y422718D01*
G01X720032Y419557D02*
X755032Y423820D01*
G01X675682Y406780D02*
X691472Y409917D01*
G01X676262Y405722D02*
X684127Y407283D01*
G01X675682Y406780D02*
X691472Y409917D01*
G01X684127Y407285D02*
X691994Y408848D01*
G01X691472Y409917D02*
X706621Y422984D01*
G01X691994Y408848D02*
X707122Y421896D01*
G01X706621Y422984D02*
X720979Y425170D01*
G01X707122Y421896D02*
X721067Y424020D01*
G01X720979Y425170D02*
X746309D01*
G01X721067Y424020D02*
X746407D01*
G01X675549Y412719D02*
X675550Y412720D01*
G01X674910Y413716D02*
X694999Y420723D01*
G01X675550Y412720D02*
X695585Y419708D01*
G01X694999Y420723D02*
X702007Y426768D01*
G01X695585Y419708D02*
X702616Y425774D01*
G01X702007Y426768D02*
X705752Y428298D01*
G01X702616Y425774D02*
X706094Y427195D01*
G01X705752Y428298D02*
X726738Y432860D01*
G01X706094Y427195D02*
X726994Y431738D01*
G01X668004Y412746D02*
X693206Y421537D01*
G01X667382Y413747D02*
X692620Y422552D01*
G01X693206Y421537D02*
X702219Y429313D01*
G01X692620Y422552D02*
X701627Y430322D01*
G01X702219Y429313D02*
X748946Y446360D01*
G01X701627Y430322D02*
X748551Y447440D01*
G01X665477Y415741D02*
X690239Y424380D01*
G01X666097Y414739D02*
X690825Y423365D01*
G01X690239Y424380D02*
X703173Y435536D01*
G01X690825Y423365D02*
X703818Y434572D01*
G01X703173Y435536D02*
X733797Y451000D01*
G01X703818Y434572D02*
X734110Y449869D01*
G01X674977Y445237D02*
X675452Y445590D01*
G01D02*
X680682Y449485D01*
G01X674233Y446118D02*
X674764Y446513D01*
G01X674977Y445237D02*
X675452Y445590D01*
G01D02*
X680682Y449485D01*
G01X674764Y446513D02*
X680095Y450483D01*
G01X680682Y449485D02*
X683558Y450781D01*
G01X685610Y451706D02*
X686840Y452260D01*
G01X688893Y453185D02*
X690123Y453739D01*
G01X692175Y454662D02*
X715701Y465261D01*
G01X680095Y450483D02*
X715287Y466336D01*
G01X677022Y452204D02*
X714518Y468784D01*
G01X677671Y451233D02*
X714929Y467707D01*
G01X674233Y446118D02*
X674764Y446513D01*
G01D02*
X680095Y450483D01*
G01X674977Y445237D02*
X675452Y445590D01*
G01X674233Y446118D02*
X674764Y446513D01*
G01D02*
X680095Y450483D01*
G01X675452Y445590D02*
X680682Y449485D01*
G01X680095Y450483D02*
X715287Y466336D01*
G01X680682Y449485D02*
X683558Y450781D01*
G01X680095Y450483D02*
X715287Y466336D01*
G01X685610Y451706D02*
X686840Y452260D01*
G01X680095Y450483D02*
X715287Y466336D01*
G01X688893Y453185D02*
X690123Y453739D01*
G01X680095Y450483D02*
X715287Y466336D01*
G01X692175Y454662D02*
X715701Y465261D01*
G01X677671Y451233D02*
X714929Y467707D01*
G01X677022Y452204D02*
X714518Y468784D01*
G01X706782Y468491D02*
X713207Y471437D01*
G01X707261Y467444D02*
X713610Y470356D01*
G01X713207Y471437D02*
X719878Y473382D01*
G01X713610Y470356D02*
X720201Y472278D01*
G01X719878Y473382D02*
X731734Y476839D01*
G01X720201Y472278D02*
X731857Y475676D01*
G01X713120Y472789D02*
X723232Y475784D01*
G01X712720Y473870D02*
X722905Y476887D01*
G01X723232Y475784D02*
X731082Y478110D01*
G01X722905Y476887D02*
X730953Y479272D01*
G01X707261Y467444D02*
X713610Y470356D01*
G01X706782Y468491D02*
X713207Y471437D01*
G01X713610Y470356D02*
X720201Y472278D01*
G01X713207Y471437D02*
X719878Y473382D01*
G01X720201Y472278D02*
X731857Y475676D01*
G01X719878Y473382D02*
X731734Y476839D01*
G01X711599Y474946D02*
X731043Y480711D01*
G01X711199Y476027D02*
X730914Y481873D01*
G01X709116Y477999D02*
X731241Y484559D01*
G01X709516Y476918D02*
X731370Y483397D01*
G01X712720Y473870D02*
X722905Y476887D01*
G01X713120Y472789D02*
X723232Y475784D01*
G01X722905Y476887D02*
X730953Y479272D01*
G01X723232Y475784D02*
X731082Y478110D01*
G01X711199Y476027D02*
X730914Y481873D01*
G01X711599Y474946D02*
X731043Y480711D01*
G01X709516Y476918D02*
X731370Y483397D01*
G01X709116Y477999D02*
X731241Y484559D01*
G01X715701Y465261D02*
X731555Y470375D01*
G01X715287Y466336D02*
X731412Y471538D01*
G01X714518Y468784D02*
X714575Y468802D01*
G01D02*
X731321Y474205D01*
G01X714929Y467707D02*
X731472Y473045D01*
G01X715287Y466336D02*
X731412Y471538D01*
G01X715701Y465261D02*
X731555Y470375D01*
G01X714929Y467707D02*
X731472Y473045D01*
G01X714518Y468784D02*
X714575Y468802D01*
G01X714929Y467707D02*
X731472Y473045D01*
G01X714575Y468802D02*
X731321Y474205D01*
G01X709562Y582500D02*
X720455Y593393D01*
G01X719305Y593870D02*
X709085Y583650D01*
G01X699665Y582500D02*
X709562D01*
G01X709085Y583650D02*
X700142D01*
G01X698165Y584000D02*
X699665Y582500D01*
G01X700142Y583650D02*
X698642Y585150D01*
G01X700142Y583650D02*
X698642Y585150D01*
G01X698165Y584000D02*
X699665Y582500D01*
G01X709085Y583650D02*
X700142D01*
G01X699665Y582500D02*
X709562D01*
G01X719305Y593870D02*
X709085Y583650D01*
G01X709562Y582500D02*
X720455Y593393D01*
G01X723497Y602476D02*
X728015D01*
G01X727538Y603626D02*
X723020D01*
G01X720455Y599434D02*
X723497Y602476D01*
G01X723020Y603626D02*
X719305Y599911D01*
G01X720455Y593393D02*
Y599434D01*
G01X719305Y599911D02*
Y593870D01*
G01Y599911D02*
Y593870D01*
G01X720455Y593393D02*
Y599434D01*
G01X723020Y603626D02*
X719305Y599911D01*
G01X720455Y599434D02*
X723497Y602476D01*
G01X727538Y603626D02*
X723020D01*
G01X723497Y602476D02*
X728015D01*
G01X761111Y123321D02*
X769258Y126080D01*
G01X760898Y124464D02*
X769215Y127280D01*
G01X769258Y126080D02*
X784459Y122111D01*
G01X769215Y127280D02*
X784463Y123299D01*
G01X784459Y122111D02*
X836603Y135319D01*
G01X784463Y123299D02*
X836501Y136480D01*
G01X760431Y121630D02*
X769150Y124316D01*
G01X760628Y120487D02*
X769169Y123118D01*
G01X769150Y124316D02*
X783927Y120276D01*
G01X769169Y123118D02*
X783919Y119085D01*
G01X783927Y120276D02*
X835818Y133717D01*
G01X783919Y119085D02*
X835922Y132555D01*
G01X760898Y124464D02*
X769215Y127280D01*
G01X761111Y123321D02*
X769258Y126080D01*
G01X769215Y127280D02*
X784463Y123299D01*
G01X769258Y126080D02*
X784459Y122111D01*
G01X784463Y123299D02*
X836501Y136480D01*
G01X784459Y122111D02*
X836603Y135319D01*
G01X760628Y120487D02*
X769169Y123118D01*
G01X760431Y121630D02*
X769150Y124316D01*
G01X769169Y123118D02*
X783919Y119085D01*
G01X769150Y124316D02*
X783927Y120276D01*
G01X783919Y119085D02*
X835922Y132555D01*
G01X783927Y120276D02*
X835818Y133717D01*
G01X834432Y157352D02*
X783761Y144430D01*
G01X834343Y158517D02*
X783781Y145623D01*
G01X783761Y144430D02*
X767839Y149077D01*
G01X783781Y145623D02*
X776123Y147858D01*
G01X783761Y144430D02*
X767839Y149077D01*
G01X776123Y147857D02*
X767787Y150291D01*
G01X767839Y149077D02*
X761956Y146803D01*
G01Y146804D02*
X756073Y144529D01*
G01X767787Y150291D02*
X755837Y145671D01*
G01X756073Y144529D02*
X740517Y143918D01*
G01X755837Y145672D02*
X740605Y145073D01*
G01X834643Y154673D02*
X784165Y141632D01*
G01X834542Y155835D02*
X784174Y142823D01*
G01X784165Y141632D02*
X767669Y146149D01*
G01X784174Y142823D02*
X767604Y147360D01*
G01X767669Y146149D02*
X756938Y141928D01*
G01X767604Y147360D02*
X756698Y143070D01*
G01X756938Y141928D02*
X740097Y141256D01*
G01X756698Y143070D02*
X740183Y142411D01*
G01X784100Y140124D02*
X833932Y152835D01*
G01X834034Y151674D02*
X784086Y138933D01*
G01X768025Y144631D02*
X784100Y140124D01*
G01X784086Y138933D02*
X768082Y143420D01*
G01X756810Y140308D02*
X768025Y144631D01*
G01X768082Y143420D02*
X757046Y139166D01*
G01X740130Y139642D02*
X756810Y140308D01*
G01X757046Y139166D02*
X740044Y138487D01*
G01X834693Y149049D02*
X783698Y136222D01*
G01X834594Y150210D02*
X783714Y137412D01*
G01X783698Y136222D02*
X768200Y140559D01*
G01X783714Y137412D02*
X768151Y141768D01*
G01X768200Y140559D02*
X757632Y136648D01*
G01X768151Y141768D02*
X757404Y137790D01*
G01X757632Y136648D02*
X739173Y135911D01*
G01X757404Y137790D02*
X739258Y137066D01*
G01X834661Y147489D02*
X783578Y134712D01*
G01X834759Y146328D02*
X783579Y133526D01*
G01X783578Y134712D02*
X782483Y134985D01*
G01X783579Y133526D02*
X782187Y133873D01*
G01X782483Y134985D02*
X768515Y138960D01*
G01X782187Y133873D02*
X768555Y137752D01*
G01X768515Y138960D02*
X768168Y138836D01*
G01Y138835D02*
X758321Y135307D01*
G01X768555Y137752D02*
X758543Y134164D01*
G01X758321Y135307D02*
X738666Y134526D01*
G01X758543Y134164D02*
X738581Y133371D01*
G01X834788Y144658D02*
X783473Y131963D01*
G01X834886Y143497D02*
X783453Y130773D01*
G01X783473Y131963D02*
X768593Y136179D01*
G01X783453Y130773D02*
X768627Y134974D01*
G01X768593Y136179D02*
X758586Y132730D01*
G01X768627Y134974D02*
X758801Y131587D01*
G01X758586Y132730D02*
X738257Y131921D01*
G01X758801Y131587D02*
X738186Y130767D01*
G01X834988Y140891D02*
X784306Y127920D01*
G01X834898Y142056D02*
X784313Y129110D01*
G01X784306Y127920D02*
X768626Y132140D01*
G01X784313Y129110D02*
X768558Y133350D01*
G01X768626Y132140D02*
X760441Y128912D01*
G01X768558Y133350D02*
X760200Y130054D01*
G01X760441Y128912D02*
X737812Y127990D01*
G01D02*
X737811D01*
G01X760200Y130054D02*
X737853Y129143D01*
G01X737812Y127990D02*
X737811D01*
G01X835083Y139458D02*
X784723Y126253D01*
G01X835188Y138296D02*
X784728Y125065D01*
G01X784723Y126253D02*
X768617Y130340D01*
G01X784728Y125065D02*
X768687Y129135D01*
G01X768617Y130340D02*
X759871Y126997D01*
G01X768687Y129134D02*
X760104Y125854D01*
G01X835467Y168351D02*
X784451Y155852D01*
G01D02*
X750261Y168564D01*
G01X835845Y166920D02*
X784344Y154138D01*
G01X835937Y165757D02*
X784276Y152936D01*
G01X784344Y154138D02*
X751097Y166499D01*
G01X784276Y152936D02*
X751105Y165269D01*
G01X836171Y163189D02*
X784160Y150057D01*
G01X836089Y164355D02*
X784179Y151249D01*
G01X784160Y150057D02*
X765440Y155436D01*
G01X784179Y151249D02*
X765392Y156647D01*
G01X765440Y155436D02*
X754959Y151506D01*
G01X765392Y156647D02*
X754835Y152688D01*
G01X754959Y151506D02*
X743046Y153310D01*
G01X754835Y152688D02*
X743350Y154428D01*
G01X743046Y153310D02*
X740928Y154156D01*
G01X743350Y154428D02*
X741294Y155249D01*
G01X835552Y160226D02*
X784013Y147298D01*
G01X835458Y161389D02*
X784031Y148489D01*
G01X784013Y147298D02*
X767993Y151838D01*
G01X784031Y148489D02*
X767942Y153048D01*
G01X767993Y151838D02*
X755230Y147035D01*
G01X767942Y153048D02*
X754999Y148177D01*
G01X755230Y147035D02*
X741622Y146511D01*
G01X754999Y148177D02*
X741710Y147666D01*
G01X834343Y158517D02*
X783781Y145623D01*
G01X834432Y157352D02*
X783761Y144430D01*
G01X783781Y145623D02*
X776123Y147858D01*
G01Y147857D02*
X767787Y150291D01*
G01X783761Y144430D02*
X767839Y149077D01*
G01X767787Y150291D02*
X755837Y145671D01*
G01X767839Y149077D02*
X761956Y146803D01*
G01X767787Y150291D02*
X755837Y145671D01*
G01X761956Y146804D02*
X756073Y144529D01*
G01X755837Y145672D02*
X740605Y145073D01*
G01X756073Y144529D02*
X740517Y143918D01*
G01X834542Y155835D02*
X784174Y142823D01*
G01X834643Y154673D02*
X784165Y141632D01*
G01X784174Y142823D02*
X767604Y147360D01*
G01X784165Y141632D02*
X767669Y146149D01*
G01X767604Y147360D02*
X756698Y143070D01*
G01X767669Y146149D02*
X756938Y141928D01*
G01X756698Y143070D02*
X740183Y142411D01*
G01X756938Y141928D02*
X740097Y141256D01*
G01X757046Y139166D02*
X740044Y138487D01*
G01X740130Y139642D02*
X756810Y140308D01*
G01X768082Y143420D02*
X757046Y139166D01*
G01X756810Y140308D02*
X768025Y144631D01*
G01X784086Y138933D02*
X768082Y143420D01*
G01X768025Y144631D02*
X784100Y140124D01*
G01X834034Y151674D02*
X784086Y138933D01*
G01X784100Y140124D02*
X833932Y152835D01*
G01X834594Y150210D02*
X783714Y137412D01*
G01X834693Y149049D02*
X783698Y136222D01*
G01X783714Y137412D02*
X768151Y141768D01*
G01X783698Y136222D02*
X768200Y140559D01*
G01X768151Y141768D02*
X757404Y137790D01*
G01X768200Y140559D02*
X757632Y136648D01*
G01X757404Y137790D02*
X739258Y137066D01*
G01X757632Y136648D02*
X739173Y135911D01*
G01X834759Y146328D02*
X783579Y133526D01*
G01X834661Y147489D02*
X783578Y134712D01*
G01X783579Y133526D02*
X782187Y133873D01*
G01X783578Y134712D02*
X782483Y134985D01*
G01X782187Y133873D02*
X768555Y137752D01*
G01X782483Y134985D02*
X768515Y138960D01*
G01X768555Y137752D02*
X758543Y134164D01*
G01X768515Y138960D02*
X768168Y138836D01*
G01X768555Y137752D02*
X758543Y134164D01*
G01X768168Y138835D02*
X758321Y135307D01*
G01X758543Y134164D02*
X738581Y133371D01*
G01X758321Y135307D02*
X738666Y134526D01*
G01X834886Y143497D02*
X783453Y130773D01*
G01X834788Y144658D02*
X783473Y131963D01*
G01X783453Y130773D02*
X768627Y134974D01*
G01X783473Y131963D02*
X768593Y136179D01*
G01X768627Y134974D02*
X758801Y131587D01*
G01X768593Y136179D02*
X758586Y132730D01*
G01X758801Y131587D02*
X738186Y130767D01*
G01X758586Y132730D02*
X738257Y131921D01*
G01X834898Y142056D02*
X784313Y129110D01*
G01X834988Y140891D02*
X784306Y127920D01*
G01X784313Y129110D02*
X768558Y133350D01*
G01X784306Y127920D02*
X768626Y132140D01*
G01X768558Y133350D02*
X760200Y130054D01*
G01X768626Y132140D02*
X760441Y128912D01*
G01X760200Y130054D02*
X737853Y129143D01*
G01X760441Y128912D02*
X737812Y127990D01*
G01X760200Y130054D02*
X737853Y129143D01*
G01X737812Y127990D02*
X737811D01*
G01X835188Y138296D02*
X784728Y125065D01*
G01X835083Y139458D02*
X784723Y126253D01*
G01X784728Y125065D02*
X768687Y129135D01*
G01X784723Y126253D02*
X768617Y130340D01*
G01X768687Y129134D02*
X760104Y125854D01*
G01X768617Y130340D02*
X759871Y126997D01*
G01X835467Y168351D02*
X784451Y155852D01*
G01D02*
X750261Y168564D01*
G01X835937Y165757D02*
X784276Y152936D01*
G01X835845Y166920D02*
X784344Y154138D01*
G01X784276Y152936D02*
X751105Y165269D01*
G01X784344Y154138D02*
X751097Y166499D01*
G01X836089Y164355D02*
X784179Y151249D01*
G01X836171Y163189D02*
X784160Y150057D01*
G01X784179Y151249D02*
X765392Y156647D01*
G01X784160Y150057D02*
X765440Y155436D01*
G01X765392Y156647D02*
X754835Y152688D01*
G01X765440Y155436D02*
X754959Y151506D01*
G01X754835Y152688D02*
X743350Y154428D01*
G01X754959Y151506D02*
X743046Y153310D01*
G01X743350Y154428D02*
X741294Y155249D01*
G01X743046Y153310D02*
X740928Y154156D01*
G01X835458Y161389D02*
X784031Y148489D01*
G01X835552Y160226D02*
X784013Y147298D01*
G01X784031Y148489D02*
X767942Y153048D01*
G01X784013Y147298D02*
X767993Y151838D01*
G01X767942Y153048D02*
X754999Y148177D01*
G01X767993Y151838D02*
X755230Y147035D01*
G01X754999Y148177D02*
X741710Y147666D01*
G01X755230Y147035D02*
X741622Y146511D01*
G01X835375Y169513D02*
X784521Y157054D01*
G01D02*
X750448Y169722D01*
G01X750261Y168564D02*
X725465Y167686D01*
G01X750448Y169722D02*
X725351Y168833D01*
G01X751097Y166499D02*
X739684Y162096D01*
G01X751105Y165269D02*
X739842Y160924D01*
G01X834481Y172143D02*
X784625Y159791D01*
G01X834575Y170981D02*
X784555Y158588D01*
G01X784625Y159791D02*
X751319Y172278D01*
G01X784555Y158588D02*
X751123Y171123D01*
G01X751319Y172278D02*
X725841Y171702D01*
G01X751123Y171123D02*
X725944Y170554D01*
G01X835375Y169513D02*
X784521Y157054D01*
G01D02*
X750448Y169722D01*
G01D02*
X725351Y168833D01*
G01X750261Y168564D02*
X725465Y167686D01*
G01X751105Y165269D02*
X739842Y160924D01*
G01X751097Y166499D02*
X739684Y162096D01*
G01X832611Y184503D02*
X785102Y172144D01*
G01X832513Y185666D02*
X785175Y173352D01*
G01X785102Y172144D02*
X763946Y180459D01*
G01X785175Y173352D02*
X774763Y177444D01*
G01X785102Y172144D02*
X763946Y180459D01*
G01X774763Y177445D02*
X764355Y181535D01*
G01X763946Y180459D02*
X759051Y182256D01*
G01X759050Y182257D02*
X754153Y184054D01*
G01X764355Y181535D02*
X754354Y185206D01*
G01X754153Y184054D02*
X727645Y183882D01*
G01X754354Y185206D02*
X727621Y185032D01*
G01X832859Y181872D02*
X784825Y169423D01*
G01X832761Y183035D02*
X784900Y170631D01*
G01X784825Y169423D02*
X761651Y178622D01*
G01X784900Y170631D02*
X762059Y179698D01*
G01X761651Y178622D02*
X753814Y181452D01*
G01X762059Y179698D02*
X754010Y182604D01*
G01X753814Y181452D02*
X725641Y181204D01*
G01X754010Y182604D02*
X725594Y182354D01*
G01X819749Y177023D02*
X784795Y167927D01*
G01X820026Y175906D02*
X784720Y166719D01*
G01X784795Y167927D02*
X757182Y178699D01*
G01X784720Y166719D02*
X756738Y177635D01*
G01X757182Y178699D02*
X753531Y180007D01*
G01X756738Y177635D02*
X753324Y178857D01*
G01X753531Y180007D02*
X750430D01*
G01X753324Y178857D02*
X750434D01*
G01X750430Y180007D02*
X726431Y179852D01*
G01X750434Y178857D02*
X726496Y178702D01*
G01X750430Y180007D02*
X726431Y179852D01*
G01X726496Y178702D02*
X725865Y178635D01*
G01X834183Y177701D02*
X784544Y165243D01*
G01X834277Y176538D02*
X784468Y164038D01*
G01X784544Y165243D02*
X768917Y171275D01*
G01Y171276D02*
X753290Y177309D01*
G01D02*
X752864Y177460D01*
G01X784468Y164038D02*
X752891Y176229D01*
G01X768917Y171276D02*
X753290Y177309D01*
G01D02*
X752864Y177460D01*
G01X752891Y176229D02*
X752669Y176307D01*
G01X753290Y177309D02*
X752864Y177460D01*
G01D02*
X725603Y177177D01*
G01X752669Y176307D02*
X725689Y176027D01*
G01X834379Y173584D02*
X784404Y161361D01*
G01X834379Y173584D02*
X784404Y161361D01*
G01X833701Y174603D02*
X784481Y162564D01*
G01X784404Y161361D02*
X752119Y173773D01*
G01X784481Y162564D02*
X752322Y174928D01*
G01X752119Y173773D02*
X725559Y173289D01*
G01X752322Y174928D02*
X725453Y174438D01*
G01X834575Y170981D02*
X784555Y158588D01*
G01X834481Y172143D02*
X784625Y159791D01*
G01X784555Y158588D02*
X751123Y171123D01*
G01X784625Y159791D02*
X751319Y172278D01*
G01X751123Y171123D02*
X725944Y170554D01*
G01X751319Y172278D02*
X725841Y171702D01*
G01X832513Y185666D02*
X785175Y173352D01*
G01X832611Y184503D02*
X785102Y172144D01*
G01X785175Y173352D02*
X774763Y177444D01*
G01Y177445D02*
X764355Y181535D01*
G01X785102Y172144D02*
X763946Y180459D01*
G01X764355Y181535D02*
X754354Y185206D01*
G01X763946Y180459D02*
X759051Y182256D01*
G01X764355Y181535D02*
X754354Y185206D01*
G01X759050Y182257D02*
X754153Y184054D01*
G01X754354Y185206D02*
X727621Y185032D01*
G01X754153Y184054D02*
X727645Y183882D01*
G01X832761Y183035D02*
X784900Y170631D01*
G01X832859Y181872D02*
X784825Y169423D01*
G01X784900Y170631D02*
X762059Y179698D01*
G01X784825Y169423D02*
X761651Y178622D01*
G01X762059Y179698D02*
X754010Y182604D01*
G01X761651Y178622D02*
X753814Y181452D01*
G01X754010Y182604D02*
X725594Y182354D01*
G01X753814Y181452D02*
X725641Y181204D01*
G01X820026Y175906D02*
X784720Y166719D01*
G01X819749Y177023D02*
X784795Y167927D01*
G01X784720Y166719D02*
X756738Y177635D01*
G01X784795Y167927D02*
X757182Y178699D01*
G01X756738Y177635D02*
X753324Y178857D01*
G01X757182Y178699D02*
X753531Y180007D01*
G01X753324Y178857D02*
X750434D01*
G01X753531Y180007D02*
X750430D01*
G01X750434Y178857D02*
X726496Y178702D01*
G01D02*
X725865Y178635D01*
G01X750430Y180007D02*
X726431Y179852D01*
G01X726496Y178702D02*
X725865Y178635D01*
G01X834277Y176538D02*
X784468Y164038D01*
G01X834183Y177701D02*
X784544Y165243D01*
G01X784468Y164038D02*
X752891Y176229D01*
G01X784544Y165243D02*
X768917Y171275D01*
G01X784468Y164038D02*
X752891Y176229D01*
G01D02*
X752669Y176307D01*
G01X768917Y171276D02*
X753290Y177309D01*
G01X784468Y164038D02*
X752891Y176229D01*
G01D02*
X752669Y176307D01*
G01D02*
X725689Y176027D01*
G01X753290Y177309D02*
X752864Y177460D01*
G01X752669Y176307D02*
X725689Y176027D01*
G01X752864Y177460D02*
X725603Y177177D01*
G01X833701Y174603D02*
X784481Y162564D01*
G01X834379Y173584D02*
X784404Y161361D01*
G01X784481Y162564D02*
X752322Y174928D01*
G01X784404Y161361D02*
X752119Y173773D01*
G01X752322Y174928D02*
X725453Y174438D01*
G01X752119Y173773D02*
X725559Y173289D01*
G01X796901Y184650D02*
X786609Y194942D01*
G01X796424Y183500D02*
X786132Y193792D01*
G01X786609Y194942D02*
X766492D01*
G01X786132Y193792D02*
X766969D01*
G01X766492Y194942D02*
X765200Y193650D01*
G01X766969Y193792D02*
X765677Y192500D01*
G01X765200Y193650D02*
X740505D01*
G01X765677Y192500D02*
X740028D01*
G01X740505Y193650D02*
X725400Y208755D01*
G01D02*
Y229162D01*
G01X796424Y183500D02*
X786132Y193792D01*
G01X796901Y184650D02*
X786609Y194942D01*
G01X786132Y193792D02*
X766969D01*
G01X786609Y194942D02*
X766492D01*
G01X766969Y193792D02*
X765677Y192500D01*
G01X766492Y194942D02*
X765200Y193650D01*
G01X765677Y192500D02*
X740028D01*
G01X765200Y193650D02*
X740505D01*
G01D02*
X725400Y208755D01*
G01D02*
Y229162D01*
G01X788241Y198220D02*
X763393D01*
G01X787764Y197070D02*
X763870D01*
G01X763393Y198220D02*
X762073Y196900D01*
G01X763870Y197070D02*
X762550Y195750D01*
G01X762073Y196900D02*
X744321D01*
G01X762550Y195750D02*
X743844D01*
G01X744321Y196900D02*
X728500Y212721D01*
G01X743844Y195750D02*
X727350Y212244D01*
G01X728500Y212721D02*
Y231394D01*
G01X727350Y212244D02*
Y230917D01*
G01X787764Y197070D02*
X763870D01*
G01X788241Y198220D02*
X763393D01*
G01X763870Y197070D02*
X762550Y195750D01*
G01X763393Y198220D02*
X762073Y196900D01*
G01X762550Y195750D02*
X743844D01*
G01X762073Y196900D02*
X744321D01*
G01X743844Y195750D02*
X727350Y212244D01*
G01X744321Y196900D02*
X728500Y212721D01*
G01X727350Y212244D02*
Y230917D01*
G01X728500Y212721D02*
Y231394D01*
G01X789568Y201507D02*
X761280D01*
G01X789091Y200357D02*
X761757D01*
G01X761280Y201507D02*
X759773Y200000D01*
G01X761757Y200357D02*
X760250Y198850D01*
G01X759773Y200000D02*
X745723D01*
G01X760250Y198850D02*
X745246D01*
G01X745723Y200000D02*
X731600Y214123D01*
G01X745246Y198850D02*
X730450Y213646D01*
G01X731600Y214123D02*
Y228423D01*
G01X730450Y213646D02*
Y228900D01*
G01X789091Y200357D02*
X761757D01*
G01X789568Y201507D02*
X761280D01*
G01X761757Y200357D02*
X760250Y198850D01*
G01X761280Y201507D02*
X759773Y200000D01*
G01X760250Y198850D02*
X745246D01*
G01X759773Y200000D02*
X745723D01*
G01X745246Y198850D02*
X730450Y213646D01*
G01X745723Y200000D02*
X731600Y214123D01*
G01X730450Y213646D02*
Y228900D01*
G01X731600Y214123D02*
Y228423D01*
G01X725417Y245418D02*
X726380D01*
G01X724940Y246568D02*
X725903D01*
G01X726380Y245418D02*
X729352Y248390D01*
G01X725903Y246568D02*
X728202Y248867D01*
G01X729352Y248390D02*
Y251505D01*
G01X728202Y248867D02*
Y251028D01*
G01X729352Y251505D02*
X725237Y255620D01*
G01X724940Y246568D02*
X725903D01*
G01X725417Y245418D02*
X726380D01*
G01X725903Y246568D02*
X728202Y248867D01*
G01X726380Y245418D02*
X729352Y248390D01*
G01X728202Y248867D02*
Y251028D01*
G01X729352Y248390D02*
Y251505D01*
G01D02*
X725237Y255620D01*
G01X731600Y228423D02*
X732892Y229715D01*
G01X730450Y228900D02*
X731742Y230192D01*
G01X732892Y229715D02*
Y243095D01*
G01X731742Y230192D02*
Y243572D01*
G01X732892Y243095D02*
X734470Y244673D01*
G01X731742Y243572D02*
X733320Y245150D01*
G01X734470Y244673D02*
Y255030D01*
G01X733320Y245150D02*
Y254553D01*
G01X734470Y255030D02*
X726230Y263270D01*
G01X733320Y254553D02*
X725753Y262120D01*
G01X730450Y228900D02*
X731742Y230192D01*
G01X731600Y228423D02*
X732892Y229715D01*
G01X731742Y230192D02*
Y243572D01*
G01X732892Y229715D02*
Y243095D01*
G01X731742Y243572D02*
X733320Y245150D01*
G01X732892Y243095D02*
X734470Y244673D01*
G01X733320Y245150D02*
Y254553D01*
G01X734470Y244673D02*
Y255030D01*
G01X733320Y254553D02*
X725753Y262120D01*
G01X734470Y255030D02*
X726230Y263270D01*
G01X790537Y402710D02*
X776064D01*
G01D02*
X773424Y405350D01*
G01X771150D02*
X768143Y402343D01*
G01D02*
X762607D01*
G01D02*
X759543Y399279D01*
G01X762130Y403493D02*
X759066Y400429D01*
G01X759543Y399279D02*
X747079D01*
G01X759066Y400429D02*
X746602D01*
G01X790537Y402710D02*
X776064D01*
G01D02*
X773424Y405350D01*
G01X771150D02*
X768143Y402343D01*
G01D02*
X762607D01*
G01X762130Y403493D02*
X759066Y400429D01*
G01X762607Y402343D02*
X759543Y399279D01*
G01X759066Y400429D02*
X746602D01*
G01X759543Y399279D02*
X747079D01*
G01X761455Y405696D02*
X758269Y402510D01*
G01D02*
X745810D01*
G01X761455Y405696D02*
X758269Y402510D01*
G01D02*
X745810D01*
G01X759270Y416180D02*
X776178Y427261D01*
G01X758864Y417290D02*
X775716Y428334D01*
G01X776178Y427261D02*
X787395Y429927D01*
G01X775716Y428334D02*
X787329Y431094D01*
G01X768422Y460219D02*
X732787Y462018D01*
G01X732569Y463181D02*
X768520Y461366D01*
G01X897511Y444737D02*
X768422Y460219D01*
G01X768520Y461366D02*
X897482Y445899D01*
G01X769013Y462667D02*
X897219Y447234D01*
G01X897191Y448396D02*
X769121Y463813D01*
G01X733140Y465096D02*
X769013Y462667D01*
G01X769121Y463813D02*
X732997Y466259D01*
G01X726265Y462882D02*
X733140Y465096D01*
G01X732997Y466259D02*
X725851Y463957D01*
G01X757660Y419475D02*
X775042Y430933D01*
G01X758068Y418365D02*
X775506Y429861D01*
G01X775042Y430933D02*
X787022Y433781D01*
G01X775506Y429861D02*
X787088Y432614D01*
G01X732455Y453339D02*
X761253Y456485D01*
G01X732778Y452217D02*
X761277Y455330D01*
G01X761253Y456485D02*
X774170Y455615D01*
G01X761277Y455330D02*
X774062Y454469D01*
G01X774170Y455615D02*
X897378Y440788D01*
G01X774062Y454469D02*
X897406Y439626D01*
G01X758864Y417290D02*
X775716Y428334D01*
G01X759270Y416180D02*
X776178Y427261D01*
G01X775716Y428334D02*
X787329Y431094D01*
G01X776178Y427261D02*
X787395Y429927D01*
G01X730110Y455215D02*
X760336Y457845D01*
G01X729808Y456344D02*
X745123Y457676D01*
G01X730110Y455215D02*
X760336Y457845D01*
G01X745123Y457676D02*
X760321Y458999D01*
G01X760336Y457845D02*
X774397Y456978D01*
G01X760321Y458999D02*
X774502Y458124D01*
G01X774397Y456978D02*
X897414Y442174D01*
G01X774502Y458124D02*
X897386Y443336D01*
G01X768520Y461366D02*
X897482Y445899D01*
G01X897511Y444737D02*
X768422Y460219D01*
G01X732569Y463181D02*
X768520Y461366D01*
G01X768422Y460219D02*
X732787Y462018D01*
G01X732997Y466259D02*
X725851Y463957D01*
G01X726265Y462882D02*
X733140Y465096D01*
G01X769121Y463813D02*
X732997Y466259D01*
G01X733140Y465096D02*
X769013Y462667D01*
G01X897191Y448396D02*
X769121Y463813D01*
G01X769013Y462667D02*
X897219Y447234D01*
G01X758068Y418365D02*
X775506Y429861D01*
G01X757660Y419475D02*
X775042Y430933D01*
G01X775506Y429861D02*
X787088Y432614D01*
G01X775042Y430933D02*
X787022Y433781D01*
G01X741467Y426859D02*
X745525Y426312D01*
G01D02*
X746210Y426323D01*
G01X741569Y428006D02*
X745593Y427464D01*
G01X741467Y426859D02*
X745525Y426312D01*
G01D02*
X746210Y426323D01*
G01D02*
X753191Y427518D01*
G01X745593Y427464D02*
X746103Y427472D01*
G01X745525Y426312D02*
X746210Y426323D01*
G01D02*
X753191Y427518D01*
G01X746103Y427472D02*
X752698Y428601D01*
G01X753191Y427518D02*
X770880Y441978D01*
G01X752698Y428601D02*
X770233Y442936D01*
G01X770880Y441978D02*
X773245Y443277D01*
G01X770233Y442936D02*
X772846Y444370D01*
G01X773245Y443277D02*
X776879Y444006D01*
G01X772846Y444370D02*
X776833Y445170D01*
G01X776879Y444006D02*
X897637Y429479D01*
G01X776833Y445170D02*
X837221Y437906D01*
G01X776879Y444006D02*
X897637Y429479D01*
G01X732778Y452217D02*
X761277Y455330D01*
G01X732455Y453339D02*
X761253Y456485D01*
G01X761277Y455330D02*
X774062Y454469D01*
G01X761253Y456485D02*
X774170Y455615D01*
G01X774062Y454469D02*
X897406Y439626D01*
G01X774170Y455615D02*
X897378Y440788D01*
G01X766653Y465482D02*
X897157Y449770D01*
G01X766761Y466628D02*
X897129Y450932D01*
G01X729808Y456344D02*
X745123Y457676D01*
G01D02*
X760321Y458999D01*
G01X730110Y455215D02*
X760336Y457845D01*
G01X760321Y458999D02*
X774502Y458124D01*
G01X760336Y457845D02*
X774397Y456978D01*
G01X774502Y458124D02*
X897386Y443336D01*
G01X774397Y456978D02*
X897414Y442174D01*
G01X756423Y420501D02*
X773655Y431860D01*
G01X756015Y421611D02*
X773191Y432933D01*
G01X773655Y431860D02*
X787337Y435112D01*
G01X773191Y432933D02*
X787271Y436279D01*
G01X755032Y423820D02*
X773425Y438689D01*
G01X755499Y422718D02*
X773945Y437630D01*
G01X773425Y438689D02*
X778420Y439874D01*
G01X773945Y437630D02*
X778486Y438707D01*
G01X778420Y439874D02*
X897576Y425542D01*
G01X778486Y438707D02*
X838046Y431543D01*
G01X778420Y439874D02*
X897576Y425542D01*
G01X746407Y424020D02*
X754729Y425434D01*
G01X746309Y425170D02*
X754240Y426518D01*
G01X754729Y425434D02*
X773514Y440615D01*
G01X754240Y426518D02*
X772999Y441679D01*
G01X773514Y440615D02*
X777209Y441447D01*
G01X772999Y441679D02*
X777150Y442613D01*
G01X777209Y441447D02*
X897542Y426916D01*
G01X777150Y442613D02*
X897514Y428078D01*
G01X741569Y428006D02*
X745593Y427464D01*
G01D02*
X746103Y427472D01*
G01X741467Y426859D02*
X745525Y426312D01*
G01X741569Y428006D02*
X745593Y427464D01*
G01D02*
X746103Y427472D01*
G01D02*
X752698Y428601D01*
G01X745525Y426312D02*
X746210Y426323D01*
G01X745593Y427464D02*
X746103Y427472D01*
G01D02*
X752698Y428601D01*
G01X746210Y426323D02*
X753191Y427518D01*
G01X752698Y428601D02*
X770233Y442936D01*
G01X753191Y427518D02*
X770880Y441978D01*
G01X770233Y442936D02*
X772846Y444370D01*
G01X770880Y441978D02*
X773245Y443277D01*
G01X772846Y444370D02*
X776833Y445170D01*
G01X773245Y443277D02*
X776879Y444006D01*
G01X776833Y445170D02*
X837221Y437906D01*
G01X776879Y444006D02*
X897637Y429479D01*
G01X726994Y431738D02*
X744814Y435981D01*
G01X726738Y432860D02*
X744811Y437163D01*
G01X744814Y435981D02*
X749225Y434956D01*
G01X744811Y437163D02*
X749315Y436116D01*
G01X749225Y434956D02*
X753474Y435267D01*
G01X749315Y436116D02*
X753140Y436396D01*
G01X753474Y435267D02*
X772756Y445875D01*
G01X753140Y436396D02*
X772367Y446975D01*
G01X772756Y445875D02*
X776637Y446568D01*
G01X772367Y446975D02*
X776604Y447731D01*
G01X776637Y446568D02*
X897593Y432018D01*
G01X776604Y447731D02*
X897565Y433180D01*
G01X748551Y447440D02*
X751122Y448378D01*
G01X748946Y446360D02*
X751389Y447251D01*
G01X751122Y448378D02*
X771987Y450812D01*
G01X751389Y447251D02*
X771985Y449653D01*
G01X771987Y450812D02*
X897209Y435666D01*
G01X771985Y449653D02*
X897237Y434504D01*
G01X734110Y449869D02*
X767525Y452281D01*
G01X733797Y451000D02*
X767521Y453434D01*
G01X767525Y452281D02*
X775519Y451762D01*
G01X767521Y453434D02*
X775625Y452908D01*
G01X775519Y451762D02*
X897468Y437090D01*
G01X775625Y452908D02*
X897440Y438252D01*
G01X766761Y466628D02*
X897129Y450932D01*
G01X766653Y465482D02*
X897157Y449770D01*
G01X756015Y421611D02*
X773191Y432933D01*
G01X756423Y420501D02*
X773655Y431860D01*
G01X773191Y432933D02*
X787271Y436279D01*
G01X773655Y431860D02*
X787337Y435112D01*
G01X755499Y422718D02*
X773945Y437630D01*
G01X755032Y423820D02*
X773425Y438689D01*
G01X773945Y437630D02*
X778486Y438707D01*
G01X773425Y438689D02*
X778420Y439874D01*
G01X778486Y438707D02*
X838046Y431543D01*
G01X778420Y439874D02*
X897576Y425542D01*
G01X746309Y425170D02*
X754240Y426518D01*
G01X746407Y424020D02*
X754729Y425434D01*
G01X754240Y426518D02*
X772999Y441679D01*
G01X754729Y425434D02*
X773514Y440615D01*
G01X772999Y441679D02*
X777150Y442613D01*
G01X773514Y440615D02*
X777209Y441447D01*
G01X777150Y442613D02*
X897514Y428078D01*
G01X777209Y441447D02*
X897542Y426916D01*
G01X726738Y432860D02*
X744811Y437163D01*
G01X726994Y431738D02*
X744814Y435981D01*
G01X744811Y437163D02*
X749315Y436116D01*
G01X744814Y435981D02*
X749225Y434956D01*
G01X749315Y436116D02*
X753140Y436396D01*
G01X749225Y434956D02*
X753474Y435267D01*
G01X753140Y436396D02*
X772367Y446975D01*
G01X753474Y435267D02*
X772756Y445875D01*
G01X772367Y446975D02*
X776604Y447731D01*
G01X772756Y445875D02*
X776637Y446568D01*
G01X776604Y447731D02*
X897565Y433180D01*
G01X776637Y446568D02*
X897593Y432018D01*
G01X748946Y446360D02*
X751389Y447251D01*
G01X748551Y447440D02*
X751122Y448378D01*
G01X751389Y447251D02*
X771985Y449653D01*
G01X751122Y448378D02*
X771987Y450812D01*
G01X771985Y449653D02*
X897237Y434504D01*
G01X771987Y450812D02*
X897209Y435666D01*
G01X733797Y451000D02*
X767521Y453434D01*
G01X734110Y449869D02*
X767525Y452281D01*
G01X767521Y453434D02*
X775625Y452908D01*
G01X767525Y452281D02*
X775519Y451762D01*
G01X775625Y452908D02*
X897440Y438252D01*
G01X775519Y451762D02*
X897468Y437090D01*
G01X790060Y403860D02*
X776541D01*
G01D02*
X773901Y406500D01*
G01X773424Y405350D02*
X771150D01*
G01X773901Y406500D02*
X770673D01*
G01D02*
X767666Y403493D01*
G01D02*
X762130D01*
G01X790060Y403860D02*
X776541D01*
G01D02*
X773901Y406500D01*
G01D02*
X770673D01*
G01X773424Y405350D02*
X771150D01*
G01X770673Y406500D02*
X767666Y403493D01*
G01D02*
X762130D01*
G01X788799Y405810D02*
X777463D01*
G01X788322Y406960D02*
X777940D01*
G01X777463Y405810D02*
X774423Y408850D01*
G01X777940Y406960D02*
X774900Y410000D01*
G01X774423Y408850D02*
X770056D01*
G01X774900Y410000D02*
X769579D01*
G01X770056Y408850D02*
X766902Y405696D01*
G01X769579Y410000D02*
X766425Y406846D01*
G01X766902Y405696D02*
X761455D01*
G01X766425Y406846D02*
X760978D01*
G01D02*
X757792Y403660D01*
G01D02*
X745333D01*
G01X788322Y406960D02*
X777940D01*
G01X788799Y405810D02*
X777463D01*
G01X777940Y406960D02*
X774900Y410000D01*
G01X777463Y405810D02*
X774423Y408850D01*
G01X774900Y410000D02*
X769579D01*
G01X774423Y408850D02*
X770056D01*
G01X769579Y410000D02*
X766425Y406846D01*
G01X770056Y408850D02*
X766902Y405696D01*
G01X766425Y406846D02*
X760978D01*
G01X766902Y405696D02*
X761455D01*
G01X760978Y406846D02*
X757792Y403660D01*
G01D02*
X745333D01*
G01X787514Y408910D02*
X778780D01*
G01X787037Y410060D02*
X779257D01*
G01X778780Y408910D02*
X775690Y412000D01*
G01X779257Y410060D02*
X776167Y413150D01*
G01X775690Y412000D02*
X768821D01*
G01X776167Y413150D02*
X768344D01*
G01X768821Y412000D02*
X765617Y408796D01*
G01X768344Y413150D02*
X765140Y409946D01*
G01X765617Y408796D02*
X760074D01*
G01X765140Y409946D02*
X759597D01*
G01X760074Y408796D02*
X756962Y405684D01*
G01X759597Y409946D02*
X756485Y406834D01*
G01X756962Y405684D02*
X744584D01*
G01X756485Y406834D02*
X744107D01*
G01X787037Y410060D02*
X779257D01*
G01X787514Y408910D02*
X778780D01*
G01X779257Y410060D02*
X776167Y413150D01*
G01X778780Y408910D02*
X775690Y412000D01*
G01X776167Y413150D02*
X768344D01*
G01X775690Y412000D02*
X768821D01*
G01X768344Y413150D02*
X765140Y409946D01*
G01X768821Y412000D02*
X765617Y408796D01*
G01X765140Y409946D02*
X759597D01*
G01X765617Y408796D02*
X760074D01*
G01X759597Y409946D02*
X756485Y406834D01*
G01X760074Y408796D02*
X756962Y405684D01*
G01X756485Y406834D02*
X744107D01*
G01X756962Y405684D02*
X744584D01*
G01X731734Y476839D02*
X764915Y474438D01*
G01D02*
X764923Y474437D01*
G01D02*
X764943Y474435D01*
G01X731857Y475676D02*
X764805Y473292D01*
G01X764915Y474438D02*
X764923Y474437D01*
G01D02*
X764943Y474435D01*
G01D02*
X896942Y458540D01*
G01X764805Y473292D02*
X896970Y457378D01*
G01X731082Y478110D02*
X765700Y475762D01*
G01X730953Y479272D02*
X765808Y476908D01*
G01X765700Y475762D02*
X897086Y459944D01*
G01X765808Y476908D02*
X897058Y461106D01*
G01X731857Y475676D02*
X764805Y473292D01*
G01X731734Y476839D02*
X764915Y474438D01*
G01X731857Y475676D02*
X764805Y473292D01*
G01D02*
X896970Y457378D01*
G01X764915Y474438D02*
X764923Y474437D01*
G01X731857Y475676D02*
X764805Y473292D01*
G01D02*
X896970Y457378D01*
G01X764923Y474437D02*
X764943Y474435D01*
G01X764805Y473292D02*
X896970Y457378D01*
G01X764943Y474435D02*
X896942Y458540D01*
G01X726640Y465938D02*
X732753Y467775D01*
G01D02*
X733564Y467720D01*
G01X726238Y467019D02*
X732622Y468937D01*
G01X732753Y467775D02*
X733564Y467720D01*
G01D02*
X750225Y466593D01*
G01X732622Y468937D02*
X750302Y467741D01*
G01X750225Y466593D02*
X766653Y465482D01*
G01X750302Y467741D02*
X766761Y466628D01*
G01X731043Y480711D02*
X763460Y478509D01*
G01X730914Y481873D02*
X763568Y479655D01*
G01X763460Y478509D02*
X896846Y462450D01*
G01X763568Y479655D02*
X896818Y463612D01*
G01X731241Y484559D02*
X761606Y482493D01*
G01X731370Y483397D02*
X761498Y481347D01*
G01X761606Y482493D02*
X829308Y474343D01*
G01X761498Y481347D02*
X897041Y465030D01*
G01X730953Y479272D02*
X765808Y476908D01*
G01X731082Y478110D02*
X765700Y475762D01*
G01X765808Y476908D02*
X897058Y461106D01*
G01X765700Y475762D02*
X897086Y459944D01*
G01X730914Y481873D02*
X763568Y479655D01*
G01X731043Y480711D02*
X763460Y478509D01*
G01X763568Y479655D02*
X896818Y463612D01*
G01X763460Y478509D02*
X896846Y462450D01*
G01X731370Y483397D02*
X761498Y481347D01*
G01X731241Y484559D02*
X761606Y482493D01*
G01X761498Y481347D02*
X897041Y465030D01*
G01X761606Y482493D02*
X829308Y474343D01*
G01X761498Y481347D02*
X897041Y465030D01*
G01X761498Y481347D02*
X897041Y465030D01*
G01X726238Y467019D02*
X732622Y468937D01*
G01X726640Y465938D02*
X732753Y467775D01*
G01X726238Y467019D02*
X732622Y468937D01*
G01D02*
X750302Y467741D01*
G01X732753Y467775D02*
X733564Y467720D01*
G01X732622Y468937D02*
X750302Y467741D01*
G01X733564Y467720D02*
X750225Y466593D01*
G01X750302Y467741D02*
X766761Y466628D01*
G01X750225Y466593D02*
X766653Y465482D01*
G01X731555Y470375D02*
X763497Y468201D01*
G01X731412Y471538D02*
X763594Y469348D01*
G01X763497Y468201D02*
X775652Y466975D01*
G01X763594Y469348D02*
X775779Y468119D01*
G01X775652Y466975D02*
X897258Y452334D01*
G01X775779Y468119D02*
X897230Y453496D01*
G01X731321Y474205D02*
X740636Y473712D01*
G01D02*
X740650Y473711D01*
G01X731472Y473045D02*
X740575Y472563D01*
G01X740636Y473712D02*
X740650Y473711D01*
G01D02*
X766169Y471720D01*
G01X740575Y472563D02*
X766056Y470575D01*
G01X766169Y471720D02*
X897004Y456004D01*
G01X766056Y470575D02*
X897033Y454842D01*
G01X731412Y471538D02*
X763594Y469348D01*
G01X731555Y470375D02*
X763497Y468201D01*
G01X763594Y469348D02*
X775779Y468119D01*
G01X763497Y468201D02*
X775652Y466975D01*
G01X775779Y468119D02*
X897230Y453496D01*
G01X775652Y466975D02*
X897258Y452334D01*
G01X731472Y473045D02*
X740575Y472563D01*
G01X731321Y474205D02*
X740636Y473712D01*
G01X731472Y473045D02*
X740575Y472563D01*
G01D02*
X766056Y470575D01*
G01X740636Y473712D02*
X740650Y473711D01*
G01X740575Y472563D02*
X766056Y470575D01*
G01X740650Y473711D02*
X766169Y471720D01*
G01X766056Y470575D02*
X897033Y454842D01*
G01X766169Y471720D02*
X897004Y456004D01*
G01X753775Y519496D02*
X756852D01*
G01X753375Y520646D02*
X757329D01*
G01X756852Y519496D02*
X757500Y518848D01*
G01X757329Y520646D02*
X758650Y519325D01*
G01X757500Y518848D02*
Y517130D01*
G01Y514430D02*
Y513030D01*
G01Y510330D02*
Y508930D01*
G01Y506230D02*
Y504830D01*
G01X758650Y519325D02*
Y505307D01*
G01X757500Y504830D02*
X760081Y502248D01*
G01X758650Y505307D02*
X760642Y503315D01*
G01X760081Y502248D02*
X764863Y501368D01*
G01X760642Y503315D02*
X764969Y502518D01*
G01X764863Y501368D02*
X834706D01*
G01X764969Y502518D02*
X834626D01*
G01X753375Y520646D02*
X757329D01*
G01X753775Y519496D02*
X756852D01*
G01X757329Y520646D02*
X758650Y519325D01*
G01X756852Y519496D02*
X757500Y518848D01*
G01X758650Y519325D02*
Y505307D01*
G01X757500Y518848D02*
Y517130D01*
G01X758650Y519325D02*
Y505307D01*
G01X757500Y514430D02*
Y513030D01*
G01X758650Y519325D02*
Y505307D01*
G01X757500Y510330D02*
Y508930D01*
G01X758650Y519325D02*
Y505307D01*
G01X757500Y506230D02*
Y504830D01*
G01X758650Y505307D02*
X760642Y503315D01*
G01X757500Y504830D02*
X760081Y502248D01*
G01X760642Y503315D02*
X764969Y502518D01*
G01X760081Y502248D02*
X764863Y501368D01*
G01X764969Y502518D02*
X834626D01*
G01X764863Y501368D02*
X834706D01*
G01X740007Y600650D02*
X1298506D01*
G01X1298983Y601800D02*
X740484D01*
G01X734462Y606195D02*
X740007Y600650D01*
G01X740484Y601800D02*
X734939Y607345D01*
G01X731734Y606195D02*
X734462D01*
G01X734939Y607345D02*
X731257D01*
G01X728015Y602476D02*
X731734Y606195D01*
G01X731257Y607345D02*
X727538Y603626D01*
G01X731257Y607345D02*
X727538Y603626D01*
G01X728015Y602476D02*
X731734Y606195D01*
G01X734939Y607345D02*
X731257D01*
G01X731734Y606195D02*
X734462D01*
G01X740484Y601800D02*
X734939Y607345D01*
G01X734462Y606195D02*
X740007Y600650D01*
G01X1298983Y601800D02*
X740484D01*
G01X740007Y600650D02*
X1298506D01*
G01X836603Y135319D02*
X875578Y132398D01*
G01X836501Y136480D02*
X875578Y133552D01*
G01X835818Y133717D02*
X875578Y130766D01*
G01X835922Y132556D02*
X875578Y129612D01*
G01X836501Y136480D02*
X875578Y133552D01*
G01X836603Y135319D02*
X875578Y132398D01*
G01X835922Y132556D02*
X875578Y129612D01*
G01X835818Y133717D02*
X875578Y130766D01*
G01Y151408D02*
X834643Y154673D01*
G01X875578Y152562D02*
X834542Y155835D01*
G01X833932Y152835D02*
X875578Y149725D01*
G01Y148571D02*
X834034Y151674D01*
G01X875578Y145944D02*
X834693Y149049D01*
G01X875578Y147098D02*
X834594Y150210D01*
G01X875578Y144344D02*
X834661Y147489D01*
G01X875578Y144344D02*
X834661Y147489D01*
G01X875288Y143212D02*
X834759Y146328D01*
G01X875578Y141637D02*
X834788Y144658D01*
G01X875578Y140483D02*
X834886Y143497D01*
G01X875578Y137789D02*
X837527Y140646D01*
G01X875578Y138943D02*
X837626Y141792D01*
G01X837527Y140646D02*
X834988Y140891D01*
G01X837626Y141792D02*
X834898Y142056D01*
G01X932214Y132095D02*
X835083Y139458D01*
G01X932214Y132095D02*
X835083Y139458D01*
G01X932193Y130943D02*
X835188Y138296D01*
G01X875578Y152562D02*
X834542Y155835D01*
G01X875578Y151408D02*
X834643Y154673D01*
G01X875578Y148571D02*
X834034Y151674D01*
G01X833932Y152835D02*
X875578Y149725D01*
G01Y147098D02*
X834594Y150210D01*
G01X875578Y145944D02*
X834693Y149049D01*
G01X875288Y143212D02*
X834759Y146328D01*
G01X875578Y144344D02*
X834661Y147489D01*
G01X875578Y140483D02*
X834886Y143497D01*
G01X875578Y141637D02*
X834788Y144658D01*
G01X875578Y138943D02*
X837626Y141792D01*
G01X875578Y137789D02*
X837527Y140646D01*
G01X837626Y141792D02*
X834898Y142056D01*
G01X837527Y140646D02*
X834988Y140891D01*
G01X932193Y130943D02*
X835188Y138296D01*
G01X932193Y130943D02*
X835188Y138296D01*
G01X932214Y132095D02*
X835083Y139458D01*
G01X875578Y154006D02*
X834432Y157352D01*
G01X875578Y155162D02*
X834343Y158517D01*
G01X875578Y165030D02*
X835467Y168351D01*
G01X875578Y166184D02*
X835375Y169513D01*
G01X875578Y163503D02*
X835845Y166920D01*
G01X875578Y162348D02*
X835937Y165757D01*
G01X931600Y154706D02*
X840742Y162699D01*
G01X931567Y155864D02*
X840854Y163844D01*
G01X840742Y162699D02*
X836171Y163189D01*
G01X840854Y163844D02*
X836089Y164355D01*
G01X875578Y156837D02*
X835552Y160226D01*
G01X875578Y157992D02*
X835458Y161389D01*
G01X875578Y155162D02*
X834343Y158517D01*
G01X875578Y154006D02*
X834432Y157352D01*
G01X875578Y168774D02*
X834481Y172143D01*
G01X875578Y167620D02*
X834575Y170981D01*
G01X875578Y166184D02*
X835375Y169513D01*
G01X875578Y165030D02*
X835467Y168351D01*
G01X875578Y162348D02*
X835937Y165757D01*
G01X875578Y163503D02*
X835845Y166920D01*
G01X931567Y155864D02*
X840854Y163844D01*
G01X931600Y154706D02*
X840742Y162699D01*
G01X840854Y163844D02*
X836089Y164355D01*
G01X840742Y162699D02*
X836171Y163189D01*
G01X875578Y157992D02*
X835458Y161389D01*
G01X875578Y156837D02*
X835552Y160226D01*
G01X875578Y180781D02*
X832611Y184503D01*
G01X875578Y181936D02*
X832513Y185666D01*
G01X875578Y178189D02*
X832859Y181872D01*
G01X875578Y179344D02*
X832761Y183035D01*
G01X875578Y176742D02*
X833887Y180353D01*
G01X875578Y175587D02*
X833971Y179191D01*
G01X833887Y180353D02*
X819749Y177023D01*
G01X833971Y179191D02*
X820026Y175906D01*
G01X875578Y174158D02*
X834183Y177701D01*
G01X875578Y173003D02*
X834277Y176538D01*
G01X875578Y170200D02*
X834379Y173584D01*
G01X875578Y171354D02*
X834287Y174746D01*
G01X875578Y170200D02*
X834379Y173584D01*
G01X834287Y174746D02*
X833701Y174603D01*
G01X875578Y167620D02*
X834575Y170981D01*
G01X875578Y168774D02*
X834481Y172143D01*
G01X875578Y181936D02*
X832513Y185666D01*
G01X875578Y180781D02*
X832611Y184503D01*
G01X875578Y179344D02*
X832761Y183035D01*
G01X875578Y178189D02*
X832859Y181872D01*
G01X875578Y175587D02*
X833971Y179191D01*
G01X875578Y176742D02*
X833887Y180353D01*
G01X833971Y179191D02*
X820026Y175906D01*
G01X833887Y180353D02*
X819749Y177023D01*
G01X875578Y173003D02*
X834277Y176538D01*
G01X875578Y174158D02*
X834183Y177701D01*
G01X875578Y171354D02*
X834287Y174746D01*
G01D02*
X833701Y174603D01*
G01X875578Y170200D02*
X834379Y173584D01*
G01X834287Y174746D02*
X833701Y174603D01*
G01X952486Y189424D02*
X821490D01*
G01X952963Y188274D02*
X821967D01*
G01X821490Y189424D02*
X818973Y186907D01*
G01X821967Y188274D02*
X819450Y185757D01*
G01X818973Y186907D02*
X808519D01*
G01X819450Y185757D02*
X808996D01*
G01X808519Y186907D02*
X806262Y184650D01*
G01X808996Y185757D02*
X806739Y183500D01*
G01X806262Y184650D02*
X796901D01*
G01X806739Y183500D02*
X796424D01*
G01X952963Y188274D02*
X821967D01*
G01X952486Y189424D02*
X821490D01*
G01X821967Y188274D02*
X819450Y185757D01*
G01X821490Y189424D02*
X818973Y186907D01*
G01X819450Y185757D02*
X808996D01*
G01X818973Y186907D02*
X808519D01*
G01X808996Y185757D02*
X806739Y183500D01*
G01X808519Y186907D02*
X806262Y184650D01*
G01X806739Y183500D02*
X796424D01*
G01X806262Y184650D02*
X796901D01*
G01X952051Y192900D02*
X820801D01*
G01X952528Y191750D02*
X821278D01*
G01X820801Y192900D02*
X818019Y190118D01*
G01X821278Y191750D02*
X818496Y188968D01*
G01X818019Y190118D02*
X796343D01*
G01X818496Y188968D02*
X795866D01*
G01X796343Y190118D02*
X788241Y198220D01*
G01X795866Y188968D02*
X787764Y197070D01*
G01X952528Y191750D02*
X821278D01*
G01X952051Y192900D02*
X820801D01*
G01X821278Y191750D02*
X818496Y188968D01*
G01X820801Y192900D02*
X818019Y190118D01*
G01X818496Y188968D02*
X795866D01*
G01X818019Y190118D02*
X796343D01*
G01X795866Y188968D02*
X787764Y197070D01*
G01X796343Y190118D02*
X788241Y198220D01*
G01X926788Y196386D02*
X818635D01*
G01X940959Y195236D02*
X819112D01*
G01X818635Y196386D02*
X815519Y193270D01*
G01X819112Y195236D02*
X815996Y192120D01*
G01X815519Y193270D02*
X797805D01*
G01X815996Y192120D02*
X797328D01*
G01X797805Y193270D02*
X789568Y201507D01*
G01X797328Y192120D02*
X789091Y200357D01*
G01X940959Y195236D02*
X819112D01*
G01X940959D02*
X819112D01*
G01X940959D02*
X819112D01*
G01X940959D02*
X819112D01*
G01X926788Y196386D02*
X818635D01*
G01X819112Y195236D02*
X815996Y192120D01*
G01X818635Y196386D02*
X815519Y193270D01*
G01X815996Y192120D02*
X797328D01*
G01X815519Y193270D02*
X797805D01*
G01X797328Y192120D02*
X789091Y200357D01*
G01X797805Y193270D02*
X789568Y201507D01*
G01X794677Y406850D02*
X790537Y402710D01*
G01X794677Y406850D02*
X790537Y402710D01*
G01X787395Y429927D02*
X897379Y416702D01*
G01X787329Y431094D02*
X897351Y417864D01*
G01X787022Y433781D02*
X897705Y420471D01*
G01X787088Y432614D02*
X897733Y419309D01*
G01X787329Y431094D02*
X897351Y417864D01*
G01X787395Y429927D02*
X897379Y416702D01*
G01X787088Y432614D02*
X897733Y419309D01*
G01X787022Y433781D02*
X897705Y420471D01*
G01X837221Y437906D02*
X897609Y430641D01*
G01X787337Y435112D02*
X897671Y421845D01*
G01X787271Y436279D02*
X897643Y423007D01*
G01X838046Y431542D02*
X897604Y424380D01*
G01X837221Y437906D02*
X897609Y430641D01*
G01X787271Y436279D02*
X897643Y423007D01*
G01X787337Y435112D02*
X897671Y421845D01*
G01X838046Y431542D02*
X897604Y424380D01*
G01X888195Y400020D02*
X840425Y411560D01*
G01X888195Y400020D02*
X840425Y411560D01*
G01X888195Y400020D02*
X840425Y411560D01*
G01X864580Y406908D02*
X840562Y412710D01*
G01X840425Y411560D02*
X804539D01*
G01X840562Y412710D02*
X804062D01*
G01X804539Y411560D02*
X799829Y406850D01*
G01X804062Y412710D02*
X799352Y408000D01*
G01X799829Y406850D02*
X794677D01*
G01X799352Y408000D02*
X794200D01*
G01D02*
X790060Y403860D01*
G01X864580Y406908D02*
X840562Y412710D01*
G01X888195Y400020D02*
X840425Y411560D01*
G01X840562Y412710D02*
X804062D01*
G01X840425Y411560D02*
X804539D01*
G01X804062Y412710D02*
X799352Y408000D01*
G01X804539Y411560D02*
X799829Y406850D01*
G01X799352Y408000D02*
X794200D01*
G01X799829Y406850D02*
X794677D01*
G01X794200Y408000D02*
X790060Y403860D01*
G01X890677Y403493D02*
X829144Y417600D01*
G01X891257Y404541D02*
X829275Y418750D01*
G01X829144Y417600D02*
X800589D01*
G01X829275Y418750D02*
X800112D01*
G01X800589Y417600D02*
X788799Y405810D01*
G01X800112Y418750D02*
X788322Y406960D01*
G01X891257Y404541D02*
X829275Y418750D01*
G01X890677Y403493D02*
X829144Y417600D01*
G01X829275Y418750D02*
X800112D01*
G01X829144Y417600D02*
X800589D01*
G01X800112Y418750D02*
X788322Y406960D01*
G01X800589Y417600D02*
X788799Y405810D01*
G01X882266Y408946D02*
X830985Y420700D01*
G01X882397Y410096D02*
X831116Y421850D01*
G01X830985Y420700D02*
X799304D01*
G01X831116Y421850D02*
X798827D01*
G01X799304Y420700D02*
X787514Y408910D01*
G01X798827Y421850D02*
X787037Y410060D01*
G01X882397Y410096D02*
X831116Y421850D01*
G01X882266Y408946D02*
X830985Y420700D01*
G01X831116Y421850D02*
X798827D01*
G01X830985Y420700D02*
X799304D01*
G01X798827Y421850D02*
X787037Y410060D01*
G01X799304Y420700D02*
X787514Y408910D01*
G01X829308Y474343D02*
X829309D01*
G01D02*
X897013Y466192D01*
G01X829308Y474343D02*
X829309D01*
G01D02*
X897013Y466192D01*
G01X834706Y501368D02*
X873693Y506799D01*
G01X834626Y502518D02*
X873613Y507949D01*
G01X834626Y502518D02*
X873613Y507949D01*
G01X834706Y501368D02*
X873693Y506799D01*
G01X1109045Y-49950D02*
X909850D01*
G01X1109045Y-51100D02*
X909373D01*
G01X909850Y-49950D02*
X906382Y-46482D01*
G01X909373Y-51100D02*
X905905Y-47632D01*
G01X906382Y-46482D02*
X863409D01*
G01X905905Y-47632D02*
X863409D01*
G01X1109045Y-51100D02*
X909373D01*
G01X1109045Y-49950D02*
X909850D01*
G01X909373Y-51100D02*
X905905Y-47632D01*
G01X909850Y-49950D02*
X906382Y-46482D01*
G01X905905Y-47632D02*
X863409D01*
G01X906382Y-46482D02*
X863409D01*
G01X875578Y132398D02*
X932584Y128126D01*
G01X875578Y133552D02*
X932603Y129278D01*
G01X875578Y132398D02*
X932584Y128126D01*
G01X875578Y130766D02*
X933260Y126484D01*
G01X875578Y129612D02*
X933264Y125330D01*
G01X875578Y130766D02*
X933260Y126484D01*
G01X875578Y133552D02*
X932603Y129278D01*
G01X875578Y132398D02*
X932584Y128126D01*
G01X875578Y133552D02*
X932603Y129278D01*
G01X875578Y129612D02*
X933264Y125330D01*
G01X875578Y130766D02*
X933260Y126484D01*
G01X875578Y129612D02*
X933264Y125330D01*
G01X931265Y149477D02*
X875578Y154006D01*
G01X931237Y150634D02*
X875578Y155162D01*
G01X931496Y146948D02*
X875578Y151408D01*
G01X931475Y148104D02*
X875578Y152562D01*
G01Y149725D02*
X931879Y145521D01*
G01X931903Y144365D02*
X875578Y148571D01*
G01X932179Y141646D02*
X875578Y145944D01*
G01X932158Y142801D02*
X875578Y147098D01*
G01X931885Y140016D02*
X875578Y144344D01*
G01X931909Y138860D02*
X875578Y143190D01*
G01X931885Y140016D02*
X875578Y144344D01*
G01Y143190D02*
X875288Y143212D01*
G01X931947Y137462D02*
X875578Y141637D01*
G01X931972Y136306D02*
X875578Y140483D01*
G01X932059Y133549D02*
X875578Y137789D01*
G01X932033Y134705D02*
X875578Y138943D01*
G01X931307Y152118D02*
X875578Y156837D01*
G01X931279Y153275D02*
X875578Y157992D01*
G01X931237Y150634D02*
X875578Y155162D01*
G01X931265Y149477D02*
X875578Y154006D01*
G01X931475Y148104D02*
X875578Y152562D01*
G01X931496Y146948D02*
X875578Y151408D01*
G01X931903Y144365D02*
X875578Y148571D01*
G01Y149725D02*
X931879Y145521D01*
G01X932158Y142801D02*
X875578Y147098D01*
G01X932179Y141646D02*
X875578Y145944D01*
G01X931909Y138860D02*
X875578Y143190D01*
G01D02*
X875288Y143212D01*
G01X931885Y140016D02*
X875578Y144344D01*
G01Y143190D02*
X875288Y143212D01*
G01X931972Y136306D02*
X875578Y140483D01*
G01X931947Y137462D02*
X875578Y141637D01*
G01X932033Y134705D02*
X875578Y138943D01*
G01X932059Y133549D02*
X875578Y137789D01*
G01X931279Y153275D02*
X875578Y157992D01*
G01X931307Y152118D02*
X875578Y156837D01*
G01X933408Y160241D02*
X875578Y165030D01*
G01X933166Y161415D02*
X875578Y166184D01*
G01X932586Y158601D02*
X875578Y163503D01*
G01X932624Y157443D02*
X875578Y162348D01*
G01X932767Y164087D02*
X875578Y168774D01*
G01X933009Y162913D02*
X875578Y167620D01*
G01X933166Y161415D02*
X875578Y166184D01*
G01X933408Y160241D02*
X875578Y165030D01*
G01X932624Y157443D02*
X875578Y162348D01*
G01X932586Y158601D02*
X875578Y163503D01*
G01X929602Y176101D02*
X875578Y180781D01*
G01X929362Y177277D02*
X875578Y181936D01*
G01X930196Y173480D02*
X875578Y178189D01*
G01X929956Y174656D02*
X875578Y179344D01*
G01X930596Y171977D02*
X875578Y176742D01*
G01X930836Y170801D02*
X875578Y175587D01*
G01X931592Y169364D02*
X875578Y174158D01*
G01X931592Y169364D02*
X875578Y174158D01*
G01X931832Y168189D02*
X875578Y173003D01*
G01X932474Y165527D02*
X875578Y170200D01*
G01X932232Y166701D02*
X875578Y171354D01*
G01X933009Y162913D02*
X875578Y167620D01*
G01X932767Y164087D02*
X875578Y168774D01*
G01X929362Y177277D02*
X875578Y181936D01*
G01X929602Y176101D02*
X875578Y180781D01*
G01X929956Y174656D02*
X875578Y179344D01*
G01X930196Y173480D02*
X875578Y178189D01*
G01X930836Y170801D02*
X875578Y175587D01*
G01X930596Y171977D02*
X875578Y176742D01*
G01X931832Y168189D02*
X875578Y173003D01*
G01X931592Y169364D02*
X875578Y174158D01*
G01X932232Y166701D02*
X875578Y171354D01*
G01X932474Y165527D02*
X875578Y170200D01*
G01X911418Y395586D02*
X901511D01*
G01X910941Y396736D02*
X901034D01*
G01X901511Y395586D02*
X901061Y395136D01*
G01X901034Y396736D02*
X899911Y395613D01*
G01X901061Y395136D02*
Y393986D01*
G01X899911Y395613D02*
Y393509D01*
G01X901061Y393986D02*
X901511Y393536D01*
G01X899911Y393509D02*
X901034Y392386D01*
G01X901511Y393536D02*
X909622D01*
G01X901034Y392386D02*
X909145D01*
G01X909622Y393536D02*
X910745Y392413D01*
G01X909145Y392386D02*
X909595Y391936D01*
G01D02*
Y390786D01*
G01X910745Y390309D02*
X909622Y389186D01*
G01X909595Y390786D02*
X909145Y390336D01*
G01X909622Y389186D02*
X899030D01*
G01X909145Y390336D02*
X899507D01*
G01X899030Y389186D02*
X888195Y400020D01*
G01X899507Y390336D02*
X888780Y401063D01*
G01D02*
X864581Y406908D01*
G01X910941Y396736D02*
X901034D01*
G01X911418Y395586D02*
X901511D01*
G01X901034Y396736D02*
X899911Y395613D01*
G01X901511Y395586D02*
X901061Y395136D01*
G01X899911Y395613D02*
Y393509D01*
G01X901061Y395136D02*
Y393986D01*
G01X899911Y393509D02*
X901034Y392386D01*
G01X901061Y393986D02*
X901511Y393536D01*
G01X901034Y392386D02*
X909145D01*
G01X901511Y393536D02*
X909622D01*
G01X909145Y392386D02*
X909595Y391936D01*
G01X909622Y393536D02*
X910745Y392413D01*
G01X909595Y391936D02*
Y390786D01*
G01D02*
X909145Y390336D01*
G01X910745Y390309D02*
X909622Y389186D01*
G01X909145Y390336D02*
X899507D01*
G01X909622Y389186D02*
X899030D01*
G01X899507Y390336D02*
X888780Y401063D01*
G01X899030Y389186D02*
X888195Y400020D01*
G01X888780Y401063D02*
X864581Y406908D01*
G01X896949Y403458D02*
X898072Y402335D01*
G01D02*
X908490D01*
G01X908967Y403485D02*
X910090Y402362D01*
G01X908490Y402335D02*
X908940Y401885D01*
G01D02*
Y400735D01*
G01X910090Y400258D02*
X908967Y399135D01*
G01X908940Y400735D02*
X908490Y400285D01*
G01X908967Y399135D02*
X895036D01*
G01X908490Y400285D02*
X895514D01*
G01X895036Y399135D02*
X890677Y403493D01*
G01X895514Y400285D02*
X891257Y404541D01*
G01X896949Y403458D02*
X898072Y402335D01*
G01D02*
X908490D01*
G01D02*
X908940Y401885D01*
G01X908967Y403485D02*
X910090Y402362D01*
G01X908940Y401885D02*
Y400735D01*
G01D02*
X908490Y400285D01*
G01X910090Y400258D02*
X908967Y399135D01*
G01X908490Y400285D02*
X895514D01*
G01X908967Y399135D02*
X895036D01*
G01X895514Y400285D02*
X891257Y404541D01*
G01X895036Y399135D02*
X890677Y403493D01*
G01X897379Y416702D02*
X919778Y420514D01*
G01X897351Y417864D02*
X919795Y421684D01*
G01X976237Y458141D02*
X897511Y444737D01*
G01X897482Y445899D02*
X976274Y459314D01*
G01X897219Y447234D02*
X976317Y460702D01*
G01X976354Y461875D02*
X897191Y448396D01*
G01X896942Y458540D02*
X936808Y465330D01*
G01X896970Y457378D02*
X976637Y470946D01*
G01X897086Y459944D02*
X976716Y473507D01*
G01X897058Y461106D02*
X976753Y474680D01*
G01X897705Y420471D02*
X919823Y424235D01*
G01X897733Y419309D02*
X919807Y423065D01*
G01X897378Y440788D02*
X976114Y454192D01*
G01X897406Y439626D02*
X976077Y453019D01*
G01X897351Y417864D02*
X919795Y421684D01*
G01X897379Y416702D02*
X919778Y420514D01*
G01X897414Y442174D02*
X976157Y455580D01*
G01X897386Y443336D02*
X976194Y456753D01*
G01X897482Y445899D02*
X976274Y459314D01*
G01X976237Y458141D02*
X897511Y444737D01*
G01X976354Y461875D02*
X897191Y448396D01*
G01X897219Y447234D02*
X976317Y460702D01*
G01X896970Y457378D02*
X976637Y470946D01*
G01X896942Y458540D02*
X936808Y465330D01*
G01X896970Y457378D02*
X976637Y470946D01*
G01X897733Y419309D02*
X919807Y423065D01*
G01X897705Y420471D02*
X919823Y424235D01*
G01X897637Y429479D02*
X919935Y433274D01*
G01X897609Y430641D02*
X919951Y434444D01*
G01X897406Y439626D02*
X976077Y453019D01*
G01X897378Y440788D02*
X976114Y454192D01*
G01X897157Y449770D02*
X976397Y463263D01*
G01X897129Y450932D02*
X976434Y464436D01*
G01X896846Y462450D02*
X976799Y476068D01*
G01X896818Y463612D02*
X976836Y477241D01*
G01X897058Y461106D02*
X976753Y474680D01*
G01X897086Y459944D02*
X976716Y473507D01*
G01X896818Y463612D02*
X976836Y477241D01*
G01X896846Y462450D02*
X976799Y476068D01*
G01X897386Y443336D02*
X976194Y456753D01*
G01X897414Y442174D02*
X976157Y455580D01*
G01X897671Y421845D02*
X919824Y425615D01*
G01X897643Y423007D02*
X908556Y424864D01*
G01X897671Y421845D02*
X919824Y425615D01*
G01X908556Y424866D02*
X919840Y426785D01*
G01X897576Y425542D02*
X919882Y429338D01*
G01X897604Y424380D02*
X919866Y428168D01*
G01X897542Y426916D02*
X919897Y430721D01*
G01X897514Y428078D02*
X919913Y431891D01*
G01X897609Y430641D02*
X919951Y434444D01*
G01X897637Y429479D02*
X919935Y433274D01*
G01X897593Y432018D02*
X919972Y435827D01*
G01X897565Y433180D02*
X919988Y436997D01*
G01X897209Y435666D02*
X920021Y439550D01*
G01X897237Y434504D02*
X920005Y438380D01*
G01X897468Y437090D02*
X975997Y450458D01*
G01X897440Y438252D02*
X976034Y451631D01*
G01X897129Y450932D02*
X976434Y464436D01*
G01X897157Y449770D02*
X976397Y463263D01*
G01X897643Y423007D02*
X908556Y424864D01*
G01Y424866D02*
X919840Y426785D01*
G01X897671Y421845D02*
X919824Y425615D01*
G01X897604Y424380D02*
X919866Y428168D01*
G01X897576Y425542D02*
X919882Y429338D01*
G01X897514Y428078D02*
X919913Y431891D01*
G01X897542Y426916D02*
X919897Y430721D01*
G01X897565Y433180D02*
X919988Y436997D01*
G01X897593Y432018D02*
X919972Y435827D01*
G01X897237Y434504D02*
X920005Y438380D01*
G01X897209Y435666D02*
X920021Y439550D01*
G01X897440Y438252D02*
X976034Y451631D01*
G01X897468Y437090D02*
X975997Y450458D01*
G01X897258Y452334D02*
X976477Y465824D01*
G01X897230Y453496D02*
X976514Y466997D01*
G01X897004Y456004D02*
X976594Y469558D01*
G01X897033Y454842D02*
X976557Y468385D01*
G01X897230Y453496D02*
X976514Y466997D01*
G01X897258Y452334D02*
X976477Y465824D01*
G01X897033Y454842D02*
X976557Y468385D01*
G01X897004Y456004D02*
X976594Y469558D01*
G01X864581Y406908D02*
X864580D01*
G01X864581D02*
X864580D01*
G01X953398Y405535D02*
X898549D01*
G01X953627Y406685D02*
X898072D01*
G01X898549Y405535D02*
X898099Y405085D01*
G01X898072Y406685D02*
X896949Y405562D01*
G01X898099Y405085D02*
Y403935D01*
G01X896949Y405562D02*
Y403458D01*
G01X898099Y403935D02*
X898549Y403485D01*
G01D02*
X908967D01*
G01X953627Y406685D02*
X898072D01*
G01X953398Y405535D02*
X898549D01*
G01X898072Y406685D02*
X896949Y405562D01*
G01X898549Y405535D02*
X898099Y405085D01*
G01X896949Y405562D02*
Y403458D01*
G01X898099Y405085D02*
Y403935D01*
G01D02*
X898549Y403485D01*
G01D02*
X908967D01*
G01X954070Y408946D02*
X882266D01*
G01X954299Y410096D02*
X882397D01*
G01X954299D02*
X882397D01*
G01X954070Y408946D02*
X882266D01*
G01X897013Y466192D02*
X977055Y479825D01*
G01X897041Y465030D02*
X977018Y478652D01*
G01X897041Y465030D02*
X977018Y478652D01*
G01X897013Y466192D02*
X977055Y479825D01*
G01X873693Y506799D02*
X968338D01*
G01X873613Y507949D02*
X968815D01*
G01X873613D02*
X968815D01*
G01X873693Y506799D02*
X968338D01*
G01X1109136Y-42550D02*
X914500D01*
G01X1109136Y-43700D02*
X914500D01*
G01Y-42550D02*
G03Y-47400I0J-2425D01*
G01Y-43700D02*
G03Y-46250I0J-1275D01*
G01Y-47400D02*
X1109045D01*
G01X914500Y-46250D02*
X1109045D01*
G01X1109136Y-43700D02*
X914500D01*
G01X1109136Y-42550D02*
X914500D01*
G01Y-43700D02*
G03Y-46250I0J-1275D01*
G01Y-42550D02*
G03Y-47400I0J-2425D01*
G01Y-46250D02*
X1109045D01*
G01X914500Y-47400D02*
X1109045D01*
G01X932584Y128126D02*
X933405Y128161D01*
G01X932584Y128126D02*
X933405Y128161D01*
G01D02*
X950719Y130377D01*
G01X932603Y129278D02*
X933307Y129308D01*
G01X932584Y128126D02*
X933405Y128161D01*
G01D02*
X950719Y130377D01*
G01X933307Y129308D02*
X950891Y131559D01*
G01X950719Y130377D02*
X964404Y124320D01*
G01X950891Y131559D02*
X964648Y125470D01*
G01X964404Y124320D02*
X990529D01*
G01X964648Y125470D02*
X990300D01*
G01X933260Y126484D02*
X934023Y126546D01*
G01X933260Y126484D02*
X934023Y126546D01*
G01D02*
X950335Y128758D01*
G01X933264Y125330D02*
X934147Y125402D01*
G01X933260Y126484D02*
X934023Y126546D01*
G01D02*
X950335Y128758D01*
G01X934147Y125402D02*
X950171Y127575D01*
G01X950335Y128758D02*
X963634Y122970D01*
G01X950171Y127575D02*
X963394Y121820D01*
G01X963634Y122970D02*
X991414D01*
G01X963394Y121820D02*
X991643D01*
G01X932603Y129278D02*
X933307Y129308D01*
G01X932603Y129278D02*
X933307Y129308D01*
G01D02*
X950891Y131559D01*
G01X932584Y128126D02*
X933405Y128161D01*
G01X932603Y129278D02*
X933307Y129308D01*
G01D02*
X950891Y131559D01*
G01X933405Y128161D02*
X950719Y130377D01*
G01X950891Y131559D02*
X964648Y125470D01*
G01X950719Y130377D02*
X964404Y124320D01*
G01X964648Y125470D02*
X990300D01*
G01X964404Y124320D02*
X990529D01*
G01X933264Y125330D02*
X934147Y125402D01*
G01X933264Y125330D02*
X934147Y125402D01*
G01D02*
X950171Y127575D01*
G01X933260Y126484D02*
X934023Y126546D01*
G01X933264Y125330D02*
X934147Y125402D01*
G01D02*
X950171Y127575D01*
G01X934023Y126546D02*
X950335Y128758D01*
G01X950171Y127575D02*
X963394Y121820D01*
G01X950335Y128758D02*
X963634Y122970D01*
G01X963394Y121820D02*
X991643D01*
G01X963634Y122970D02*
X991414D01*
G01X982973Y144442D02*
X970640D01*
G01X982744Y145592D02*
X970942D01*
G01X970640Y144442D02*
X955950Y152702D01*
G01X970942Y145592D02*
X956180Y153893D01*
G01X955950Y152702D02*
X931265Y149477D01*
G01X956180Y153893D02*
X931237Y150634D01*
G01X984036Y141918D02*
X969993D01*
G01X983807Y143068D02*
X970285D01*
G01X969993Y141918D02*
X955572Y149735D01*
G01X970285Y143068D02*
X955801Y150920D01*
G01X955572Y149735D02*
X931496Y146948D01*
G01X955801Y150920D02*
X931475Y148104D01*
G01X969679Y140545D02*
X984492D01*
G01X984721Y139395D02*
X969402D01*
G01X954711Y148193D02*
X969679Y140545D01*
G01X969402Y139395D02*
X954498Y147010D01*
G01X931879Y145521D02*
X954711Y148193D01*
G01X954498Y147010D02*
X931903Y144365D01*
G01X985667Y136858D02*
X968840D01*
G01X985438Y138008D02*
X969104D01*
G01X968840Y136858D02*
X953896Y144076D01*
G01X969104Y138008D02*
X954098Y145256D01*
G01X953896Y144076D02*
X932179Y141646D01*
G01X954098Y145256D02*
X932158Y142801D01*
G01X986610Y135470D02*
X968605D01*
G01X986840Y134320D02*
X968346D01*
G01X968605Y135470D02*
X953599Y142585D01*
G01X968346Y134320D02*
X953405Y141404D01*
G01X953599Y142585D02*
X931885Y140016D01*
G01X953405Y141404D02*
X931909Y138860D01*
G01X987313Y132970D02*
X967483D01*
G01X987542Y131820D02*
X967218D01*
G01X967483Y132970D02*
X953093Y139945D01*
G01X967218Y131820D02*
X952893Y138763D01*
G01X953093Y139945D02*
X931947Y137462D01*
G01X952893Y138763D02*
X931972Y136306D01*
G01X987980Y129320D02*
X966596D01*
G01X987755Y130470D02*
X966843D01*
G01X966596Y129320D02*
X951880Y135930D01*
G01X966843Y130470D02*
X952060Y137110D01*
G01X951880Y135930D02*
X932059Y133549D01*
G01X952060Y137110D02*
X932033Y134705D01*
G01X988888Y127970D02*
X965670D01*
G01X989117Y126820D02*
X965415D01*
G01X965670Y127970D02*
X951678Y134470D01*
G01X965415Y126820D02*
X951492Y133288D01*
G01X951678Y134470D02*
X932589Y132110D01*
G01D02*
X932214Y132095D01*
G01X951492Y133288D02*
X932681Y130962D01*
G01X951678Y134470D02*
X932589Y132110D01*
G01D02*
X932214Y132095D01*
G01X932681Y130962D02*
X932193Y130943D01*
G01X932589Y132110D02*
X932214Y132095D01*
G01X973200Y153133D02*
X957916Y162461D01*
G01X972876Y151983D02*
X957675Y161260D01*
G01X972061Y149474D02*
X957171Y158440D01*
G01X972381Y150624D02*
X957412Y159638D01*
G01X957171Y158440D02*
X931600Y154706D01*
G01X957412Y159638D02*
X931567Y155864D01*
G01X981666Y146951D02*
X971334D01*
G01X981437Y148101D02*
X971647D01*
G01X971334Y146951D02*
X956418Y155689D01*
G01X971647Y148101D02*
X956645Y156889D01*
G01X956418Y155689D02*
X947363Y154262D01*
G01X956645Y156889D02*
X947197Y155401D01*
G01X947363Y154262D02*
X931307Y152118D01*
G01X947197Y155401D02*
X931279Y153275D01*
G01X982744Y145592D02*
X970942D01*
G01X982973Y144442D02*
X970640D01*
G01X970942Y145592D02*
X956180Y153893D01*
G01X970640Y144442D02*
X955950Y152702D01*
G01X956180Y153893D02*
X931237Y150634D01*
G01X955950Y152702D02*
X931265Y149477D01*
G01X983807Y143068D02*
X970285D01*
G01X984036Y141918D02*
X969993D01*
G01X970285Y143068D02*
X955801Y150920D01*
G01X969993Y141918D02*
X955572Y149735D01*
G01X955801Y150920D02*
X931475Y148104D01*
G01X955572Y149735D02*
X931496Y146948D01*
G01X954498Y147010D02*
X931903Y144365D01*
G01X931879Y145521D02*
X954711Y148193D01*
G01X969402Y139395D02*
X954498Y147010D01*
G01X954711Y148193D02*
X969679Y140545D01*
G01X984721Y139395D02*
X969402D01*
G01X969679Y140545D02*
X984492D01*
G01X985438Y138008D02*
X969104D01*
G01X985667Y136858D02*
X968840D01*
G01X969104Y138008D02*
X954098Y145256D01*
G01X968840Y136858D02*
X953896Y144076D01*
G01X954098Y145256D02*
X932158Y142801D01*
G01X953896Y144076D02*
X932179Y141646D01*
G01X986840Y134320D02*
X968346D01*
G01X986610Y135470D02*
X968605D01*
G01X968346Y134320D02*
X953405Y141404D01*
G01X968605Y135470D02*
X953599Y142585D01*
G01X953405Y141404D02*
X931909Y138860D01*
G01X953599Y142585D02*
X931885Y140016D01*
G01X987542Y131820D02*
X967218D01*
G01X987313Y132970D02*
X967483D01*
G01X967218Y131820D02*
X952893Y138763D01*
G01X967483Y132970D02*
X953093Y139945D01*
G01X952893Y138763D02*
X931972Y136306D01*
G01X953093Y139945D02*
X931947Y137462D01*
G01X987755Y130470D02*
X966843D01*
G01X987980Y129320D02*
X966596D01*
G01X966843Y130470D02*
X952060Y137110D01*
G01X966596Y129320D02*
X951880Y135930D01*
G01X952060Y137110D02*
X932033Y134705D01*
G01X951880Y135930D02*
X932059Y133549D01*
G01X989117Y126820D02*
X965415D01*
G01X988888Y127970D02*
X965670D01*
G01X965415Y126820D02*
X951492Y133288D01*
G01X965670Y127970D02*
X951678Y134470D01*
G01X951492Y133288D02*
X932681Y130962D01*
G01D02*
X932193Y130943D01*
G01X951678Y134470D02*
X932589Y132110D01*
G01X951492Y133288D02*
X932681Y130962D01*
G01D02*
X932193Y130943D01*
G01X932589Y132110D02*
X932214Y132095D01*
G01X932681Y130962D02*
X932193Y130943D01*
G01X972876Y151983D02*
X957675Y161260D01*
G01X973200Y153133D02*
X957916Y162461D01*
G01X972381Y150624D02*
X957412Y159638D01*
G01X972061Y149474D02*
X957171Y158440D01*
G01X957412Y159638D02*
X931567Y155864D01*
G01X957171Y158440D02*
X931600Y154706D01*
G01X981437Y148101D02*
X971647D01*
G01X981666Y146951D02*
X971334D01*
G01X971647Y148101D02*
X956645Y156889D01*
G01X971334Y146951D02*
X956418Y155689D01*
G01X956645Y156889D02*
X947197Y155401D01*
G01X956418Y155689D02*
X947363Y154262D01*
G01X947197Y155401D02*
X931279Y153275D01*
G01X947363Y154262D02*
X931307Y152118D01*
G01X976246Y174209D02*
X949198Y168644D01*
G01X976222Y175379D02*
X948804Y169738D01*
G01X949198Y168644D02*
X948691Y168374D01*
G01D02*
X933408Y160241D01*
G01X948804Y169738D02*
X933166Y161415D01*
G01X957916Y162461D02*
X932586Y158601D01*
G01X957675Y161260D02*
X932624Y157443D01*
G01X976161Y177922D02*
X948093Y172244D01*
G01X976185Y176753D02*
X948486Y171149D01*
G01X948093Y172244D02*
X932767Y164087D01*
G01X948486Y171149D02*
X933009Y162913D01*
G01X976222Y175379D02*
X948804Y169738D01*
G01X976246Y174209D02*
X949198Y168644D01*
G01X948804Y169738D02*
X933166Y161415D01*
G01X949198Y168644D02*
X948691Y168374D01*
G01X948804Y169738D02*
X933166Y161415D01*
G01X948691Y168374D02*
X933408Y160241D01*
G01X957675Y161260D02*
X932624Y157443D01*
G01X957916Y162461D02*
X932586Y158601D01*
G01X975568Y189730D02*
X942485Y182944D01*
G01X975551Y190901D02*
X942091Y184038D01*
G01X942485Y182944D02*
X929602Y176101D01*
G01X942091Y184038D02*
X929362Y177277D01*
G01X975920Y187076D02*
X943116Y180339D01*
G01X975891Y188245D02*
X942722Y181433D01*
G01X943116Y180339D02*
X930196Y173480D01*
G01X942722Y181433D02*
X929956Y174656D01*
G01X976059Y185683D02*
X943985Y179090D01*
G01X976086Y184514D02*
X944379Y177996D01*
G01X943985Y179090D02*
X930596Y171977D01*
G01X944379Y177996D02*
X930836Y170801D01*
G01X975738Y183056D02*
X945774Y176894D01*
G01X975768Y181887D02*
X946168Y175800D01*
G01X945774Y176894D02*
X931592Y169364D01*
G01X946168Y175800D02*
X932180Y168374D01*
G01X945774Y176894D02*
X931592Y169364D01*
G01X932180Y168374D02*
X931832Y168189D01*
G01X976137Y179297D02*
X947437Y173489D01*
G01X976110Y180465D02*
X947044Y174584D01*
G01X947437Y173489D02*
X932474Y165527D01*
G01X947044Y174584D02*
X932232Y166701D01*
G01X976185Y176753D02*
X948486Y171149D01*
G01X976161Y177922D02*
X948093Y172244D01*
G01X948486Y171149D02*
X933009Y162913D01*
G01X948093Y172244D02*
X932767Y164087D01*
G01X975551Y190901D02*
X942091Y184038D01*
G01X975568Y189730D02*
X942485Y182944D01*
G01X942091Y184038D02*
X929362Y177277D01*
G01X942485Y182944D02*
X929602Y176101D01*
G01X975891Y188245D02*
X942722Y181433D01*
G01X975920Y187076D02*
X943116Y180339D01*
G01X942722Y181433D02*
X929956Y174656D01*
G01X943116Y180339D02*
X930196Y173480D01*
G01X976086Y184514D02*
X944379Y177996D01*
G01X976059Y185683D02*
X943985Y179090D01*
G01X944379Y177996D02*
X930836Y170801D01*
G01X943985Y179090D02*
X930596Y171977D01*
G01X975768Y181887D02*
X946168Y175800D01*
G01X975738Y183056D02*
X945774Y176894D01*
G01X946168Y175800D02*
X932180Y168374D01*
G01D02*
X931832Y168189D01*
G01X945774Y176894D02*
X931592Y169364D01*
G01X932180Y168374D02*
X931832Y168189D01*
G01X976110Y180465D02*
X947044Y174584D01*
G01X976137Y179297D02*
X947437Y173489D01*
G01X947044Y174584D02*
X932232Y166701D01*
G01X947437Y173489D02*
X932474Y165527D01*
G01X978050Y196400D02*
X959462D01*
G01X977573Y195250D02*
X959939D01*
G01X959462Y196400D02*
X952486Y189424D01*
G01X959939Y195250D02*
X952963Y188274D01*
G01X977573Y195250D02*
X959939D01*
G01X978050Y196400D02*
X959462D01*
G01X959939Y195250D02*
X952963Y188274D01*
G01X959462Y196400D02*
X952486Y189424D01*
G01X979800Y199600D02*
X958751D01*
G01X979323Y198450D02*
X959228D01*
G01X958751Y199600D02*
X952051Y192900D01*
G01X959228Y198450D02*
X952528Y191750D01*
G01X979323Y198450D02*
X959228D01*
G01X979800Y199600D02*
X958751D01*
G01X959228Y198450D02*
X952528Y191750D01*
G01X958751Y199600D02*
X952051Y192900D01*
G01X981476Y206300D02*
X966823D01*
G01X980999Y205150D02*
X967300D01*
G01X966823Y206300D02*
X963973Y203450D01*
G01X967300Y205150D02*
X964450Y202300D01*
G01X963973Y203450D02*
X961727D01*
G01X964450Y202300D02*
X961250D01*
G01X961727Y203450D02*
X961077Y204100D01*
G01X961250Y202300D02*
X960600Y202950D01*
G01X961077Y204100D02*
X955073D01*
G01X960600Y202950D02*
X955550D01*
G01X955073Y204100D02*
X946723Y195750D01*
G01X955550Y202950D02*
X947200Y194600D01*
G01X946723Y195750D02*
X942072D01*
G01X947200Y194600D02*
X941595D01*
G01X942072Y195750D02*
X941436Y196386D01*
G01X941595Y194600D02*
X940959Y195236D01*
G01X941436Y196386D02*
X937438D01*
G01X934788D02*
X933438D01*
G01X930788D02*
X929438D01*
G01X980999Y205150D02*
X967300D01*
G01X981476Y206300D02*
X966823D01*
G01X967300Y205150D02*
X964450Y202300D01*
G01X966823Y206300D02*
X963973Y203450D01*
G01X964450Y202300D02*
X961250D01*
G01X963973Y203450D02*
X961727D01*
G01X961250Y202300D02*
X960600Y202950D01*
G01X961727Y203450D02*
X961077Y204100D01*
G01X960600Y202950D02*
X955550D01*
G01X961077Y204100D02*
X955073D01*
G01X955550Y202950D02*
X947200Y194600D01*
G01X955073Y204100D02*
X946723Y195750D01*
G01X947200Y194600D02*
X941595D01*
G01X946723Y195750D02*
X942072D01*
G01X941595Y194600D02*
X940959Y195236D01*
G01X942072Y195750D02*
X941436Y196386D01*
G01D02*
X937438D01*
G01X934788D02*
X933438D01*
G01X930788D02*
X929438D01*
G01X993473Y393400D02*
X971501D01*
G01D02*
X968701Y396200D01*
G01X971978Y394550D02*
X969178Y397350D01*
G01X968701Y396200D02*
X959477D01*
G01X969178Y397350D02*
X959706D01*
G01X959477Y396200D02*
X944420Y402424D01*
G01X959706Y397350D02*
X944649Y403574D01*
G01X944420Y402424D02*
X918256D01*
G01D02*
X911418Y395586D01*
G01X917779Y403574D02*
X910941Y396736D01*
G01X910745Y392413D02*
Y390309D01*
G01X993473Y393400D02*
X971501D01*
G01X971978Y394550D02*
X969178Y397350D01*
G01X971501Y393400D02*
X968701Y396200D01*
G01X969178Y397350D02*
X959706D01*
G01X968701Y396200D02*
X959477D01*
G01X959706Y397350D02*
X944649Y403574D01*
G01X959477Y396200D02*
X944420Y402424D01*
G01D02*
X918256D01*
G01X917779Y403574D02*
X910941Y396736D01*
G01X918256Y402424D02*
X911418Y395586D01*
G01X910745Y392413D02*
Y390309D01*
G01X972285Y397714D02*
X953398Y405535D01*
G01X972936Y398690D02*
X953627Y406685D01*
G01X910090Y402362D02*
Y400258D01*
G01X972936Y398690D02*
X953627Y406685D01*
G01X972285Y397714D02*
X953398Y405535D01*
G01X910090Y402362D02*
Y400258D01*
G01X919778Y420514D02*
X976451Y409194D01*
G01X919795Y421684D02*
X976447Y410368D01*
G01X919823Y424235D02*
X976515Y412944D01*
G01X919807Y423065D02*
X976519Y411770D01*
G01X919795Y421684D02*
X976447Y410368D01*
G01X919778Y420514D02*
X976451Y409194D01*
G01X919807Y423065D02*
X976519Y411770D01*
G01X919823Y424235D02*
X976515Y412944D01*
G01X919935Y433274D02*
X976502Y422025D01*
G01X919951Y434444D02*
X976498Y423199D01*
G01X919824Y425615D02*
X976530Y414339D01*
G01X919840Y426785D02*
X976526Y415513D01*
G01X919882Y429338D02*
X976517Y418075D01*
G01X919866Y428168D02*
X976521Y416901D01*
G01X919897Y430721D02*
X976511Y419463D01*
G01X919913Y431891D02*
X976507Y420637D01*
G01X919951Y434444D02*
X976498Y423199D01*
G01X919935Y433274D02*
X976502Y422025D01*
G01X919972Y435827D02*
X976492Y424588D01*
G01X919988Y436997D02*
X976488Y425762D01*
G01X920021Y439550D02*
X976412Y428337D01*
G01X920005Y438380D02*
X976416Y427163D01*
G01X919840Y426785D02*
X976526Y415513D01*
G01X919824Y425615D02*
X976530Y414339D01*
G01X919866Y428168D02*
X976521Y416901D01*
G01X919882Y429338D02*
X976517Y418075D01*
G01X919913Y431891D02*
X976507Y420637D01*
G01X919897Y430721D02*
X976511Y419463D01*
G01X919988Y436997D02*
X976488Y425762D01*
G01X919972Y435827D02*
X976492Y424588D01*
G01X920005Y438380D02*
X976416Y427163D01*
G01X920021Y439550D02*
X976412Y428337D01*
G01X944649Y403574D02*
X917779D01*
G01X944649D02*
X917779D01*
G01X991514Y404807D02*
X964069D01*
G01X991037Y405957D02*
X964298D01*
G01X964069Y404807D02*
X954070Y408946D01*
G01X964298Y405957D02*
X954299Y410096D01*
G01X991037Y405957D02*
X964298D01*
G01X991514Y404807D02*
X964069D01*
G01X964298Y405957D02*
X954299Y410096D01*
G01X964069Y404807D02*
X954070Y408946D01*
G01X936808Y465330D02*
X976674Y472119D01*
G01X936808Y465330D02*
X976674Y472119D01*
G01X968338Y506799D02*
X971385Y503752D01*
G01X968815Y507949D02*
X971920Y504844D01*
G01X971385Y503752D02*
X1011762Y498663D01*
G01X968815Y507949D02*
X971920Y504844D01*
G01X968338Y506799D02*
X971385Y503752D01*
G01D02*
X1011762Y498663D01*
G01X990529Y124320D02*
X1012653Y133487D01*
G01X990300Y125470D02*
X1012267Y134572D01*
G01X1012653Y133487D02*
X1021349Y136094D01*
G01X1012267Y134572D02*
X1021074Y137213D01*
G01X1021349Y136094D02*
X1029719Y137702D01*
G01X1021074Y137213D02*
X1029779Y138885D01*
G01X1029719Y137702D02*
X1041687Y134118D01*
G01X1029779Y138885D02*
X1041766Y135295D01*
G01X991414Y122970D02*
X1007322Y129561D01*
G01X991643Y121820D02*
X1007728Y128484D01*
G01X1007322Y129561D02*
X1020008Y133883D01*
G01X1007728Y128484D02*
X1020327Y132776D01*
G01X1020008Y133883D02*
X1029564Y136143D01*
G01X1020327Y132776D02*
X1029535Y134954D01*
G01X1029564Y136143D02*
X1041781Y132623D01*
G01X1029535Y134954D02*
X1041707Y131447D01*
G01X990300Y125470D02*
X1012267Y134572D01*
G01X990529Y124320D02*
X1012653Y133487D01*
G01X1012267Y134572D02*
X1021074Y137213D01*
G01X1012653Y133487D02*
X1021349Y136094D01*
G01X1021074Y137213D02*
X1029779Y138885D01*
G01X1021349Y136094D02*
X1029719Y137702D01*
G01X1029779Y138885D02*
X1041766Y135295D01*
G01X1029719Y137702D02*
X1041687Y134118D01*
G01X991643Y121820D02*
X1007728Y128484D01*
G01X991414Y122970D02*
X1007322Y129561D01*
G01X1007728Y128484D02*
X1020327Y132776D01*
G01X1007322Y129561D02*
X1020008Y133883D01*
G01X1020327Y132776D02*
X1029535Y134954D01*
G01X1020008Y133883D02*
X1029564Y136143D01*
G01X1029535Y134954D02*
X1041707Y131447D01*
G01X1029564Y136143D02*
X1041781Y132623D01*
G01X1015950Y158093D02*
X982973Y144442D01*
G01X1015647Y159213D02*
X982744Y145592D01*
G01X1030441Y157092D02*
X1016902Y155200D01*
G01D02*
X1003468Y149967D01*
G01X1016610Y156321D02*
X1003039Y151035D01*
G01X1003468Y149967D02*
X984036Y141918D01*
G01X1003039Y151035D02*
X983807Y143068D01*
G01X1030767Y155474D02*
X1041079Y151991D01*
G01X1041029Y150794D02*
X1030656Y154297D01*
G01X1017111Y153582D02*
X1030767Y155474D01*
G01X1030656Y154297D02*
X1017399Y152460D01*
G01X1002414Y147968D02*
X1017111Y153582D01*
G01X1017399Y152460D02*
X1002839Y146899D01*
G01X984492Y140545D02*
X1002414Y147968D01*
G01X1002839Y146899D02*
X984721Y139395D01*
G01X1041066Y148047D02*
X1030358Y151634D01*
G01X1041114Y149244D02*
X1030470Y152810D01*
G01X1030358Y151634D02*
X1018238Y150009D01*
G01X1030470Y152810D02*
X1017950Y151131D01*
G01X1018238Y150009D02*
X1005180Y144941D01*
G01X1017950Y151131D02*
X1004751Y146009D01*
G01X1005180Y144941D02*
X985667Y136858D01*
G01X1004751Y146009D02*
X985438Y138008D01*
G01X1041269Y146314D02*
X1030043Y150057D01*
G01X1041168Y145135D02*
X1029935Y148880D01*
G01X1030043Y150057D02*
X1017552Y148309D01*
G01X1029935Y148880D02*
X1017857Y147190D01*
G01X1017552Y148309D02*
X986610Y135470D01*
G01X1017857Y147190D02*
X986840Y134320D01*
G01X1041525Y143423D02*
X1029447Y147363D01*
G01X1041429Y142244D02*
X1029356Y146183D01*
G01X1029447Y147363D02*
X1017287Y145383D01*
G01X1029356Y146183D02*
X1017604Y144269D01*
G01X1017287Y145383D02*
X987313Y132970D01*
G01X1017604Y144269D02*
X987542Y131820D01*
G01X1041258Y139579D02*
X1029274Y143516D01*
G01X1041355Y140759D02*
X1029363Y144698D01*
G01X1029274Y143516D02*
X1018487Y141694D01*
G01X1029363Y144698D02*
X1018171Y142807D01*
G01X1018487Y141694D02*
X987980Y129320D01*
G01X1018171Y142807D02*
X987755Y130470D01*
G01X1041608Y138006D02*
X1030076Y141702D01*
G01X1041517Y136827D02*
X1029994Y140520D01*
G01X1030076Y141702D02*
X1018295Y139660D01*
G01X1029994Y140520D02*
X1018592Y138544D01*
G01X1018295Y139660D02*
X1008452Y136076D01*
G01X1018592Y138544D02*
X1008869Y135003D01*
G01X1008452Y136076D02*
X988888Y127970D01*
G01X1008869Y135003D02*
X989117Y126820D01*
G01X1012615Y166817D02*
X979576Y153133D01*
G01X1012917Y165697D02*
X979805Y151983D01*
G01X979576Y153133D02*
X973200D01*
G01X979805Y151983D02*
X972876D01*
G01X1013613Y163028D02*
X980886Y149474D01*
G01X1013309Y164147D02*
X980657Y150624D01*
G01X980886Y149474D02*
X972061D01*
G01X980657Y150624D02*
X972381D01*
G01X1014568Y160577D02*
X981666Y146951D01*
G01X1014265Y161697D02*
X981437Y148101D01*
G01X1015647Y159213D02*
X982744Y145592D01*
G01X1015950Y158093D02*
X982973Y144442D01*
G01X1030441Y157092D02*
X1016902Y155200D01*
G01X1016610Y156321D02*
X1003039Y151035D01*
G01X1016902Y155200D02*
X1003468Y149967D01*
G01X1003039Y151035D02*
X983807Y143068D01*
G01X1003468Y149967D02*
X984036Y141918D01*
G01X1002839Y146899D02*
X984721Y139395D01*
G01X984492Y140545D02*
X1002414Y147968D01*
G01X1017399Y152460D02*
X1002839Y146899D01*
G01X1002414Y147968D02*
X1017111Y153582D01*
G01X1030656Y154297D02*
X1017399Y152460D01*
G01X1017111Y153582D02*
X1030767Y155474D01*
G01X1041029Y150794D02*
X1030656Y154297D01*
G01X1030767Y155474D02*
X1041079Y151991D01*
G01X1041114Y149244D02*
X1030470Y152810D01*
G01X1041066Y148047D02*
X1030358Y151634D01*
G01X1030470Y152810D02*
X1017950Y151131D01*
G01X1030358Y151634D02*
X1018238Y150009D01*
G01X1017950Y151131D02*
X1004751Y146009D01*
G01X1018238Y150009D02*
X1005180Y144941D01*
G01X1004751Y146009D02*
X985438Y138008D01*
G01X1005180Y144941D02*
X985667Y136858D01*
G01X1041168Y145135D02*
X1029935Y148880D01*
G01X1041269Y146314D02*
X1030043Y150057D01*
G01X1029935Y148880D02*
X1017857Y147190D01*
G01X1030043Y150057D02*
X1017552Y148309D01*
G01X1017857Y147190D02*
X986840Y134320D01*
G01X1017552Y148309D02*
X986610Y135470D01*
G01X1041429Y142244D02*
X1029356Y146183D01*
G01X1041525Y143423D02*
X1029447Y147363D01*
G01X1029356Y146183D02*
X1017604Y144269D01*
G01X1029447Y147363D02*
X1017287Y145383D01*
G01X1017604Y144269D02*
X987542Y131820D01*
G01X1017287Y145383D02*
X987313Y132970D01*
G01X1041355Y140759D02*
X1029363Y144698D01*
G01X1041258Y139579D02*
X1029274Y143516D01*
G01X1029363Y144698D02*
X1018171Y142807D01*
G01X1029274Y143516D02*
X1018487Y141694D01*
G01X1018171Y142807D02*
X987755Y130470D01*
G01X1018487Y141694D02*
X987980Y129320D01*
G01X1041517Y136827D02*
X1029994Y140520D01*
G01X1041608Y138006D02*
X1030076Y141702D01*
G01X1029994Y140520D02*
X1018592Y138544D01*
G01X1030076Y141702D02*
X1018295Y139660D01*
G01X1018592Y138544D02*
X1008869Y135003D01*
G01X1018295Y139660D02*
X1008452Y136076D01*
G01X1008869Y135003D02*
X989117Y126820D01*
G01X1008452Y136076D02*
X988888Y127970D01*
G01X1012917Y165697D02*
X979805Y151983D01*
G01X1012615Y166817D02*
X979576Y153133D01*
G01X979805Y151983D02*
X972876D01*
G01X979576Y153133D02*
X973200D01*
G01X1013309Y164147D02*
X980657Y150624D01*
G01X1013613Y163028D02*
X980886Y149474D01*
G01X980657Y150624D02*
X972381D01*
G01X980886Y149474D02*
X972061D01*
G01X1014265Y161697D02*
X981437Y148101D01*
G01X1014568Y160577D02*
X981666Y146951D01*
G01X1041191Y156429D02*
X1029692Y159968D01*
G01X1041227Y157622D02*
X1029788Y161142D01*
G01X1029692Y159968D02*
X1015950Y158093D01*
G01X1029788Y161142D02*
X1015647Y159213D01*
G01X1041118Y153629D02*
X1030441Y157092D01*
G01X1041162Y154824D02*
X1030544Y158268D01*
G01D02*
X1016610Y156321D01*
G01X1041482Y167755D02*
X1031062Y170705D01*
G01X1041509Y168943D02*
X1031164Y171872D01*
G01X1031062Y170705D02*
X1011458Y168696D01*
G01D02*
X1010545Y168635D01*
G01X1031164Y171872D02*
X1011361Y169843D01*
G01X1031062Y170705D02*
X1011458Y168696D01*
G01D02*
X1010545Y168635D01*
G01D02*
X976246Y174209D01*
G01X1011361Y169843D02*
X1010600Y169792D01*
G01X1010545Y168635D02*
X976246Y174209D01*
G01X1010600Y169792D02*
X976222Y175379D01*
G01X1041900Y166188D02*
X1030477Y169224D01*
G01X1041885Y165002D02*
X1030403Y168053D01*
G01X1030477Y169224D02*
X1012615Y166817D01*
G01X1030403Y168053D02*
X1012917Y165697D01*
G01X1041179Y162152D02*
X1031034Y165095D01*
G01D02*
X1030293Y165332D01*
G01X1041208Y163342D02*
X1031370Y166196D01*
G01X1031034Y165095D02*
X1030293Y165332D01*
G01X1031370Y166196D02*
X1030394Y166508D01*
G01X1030293Y165332D02*
X1013613Y163028D01*
G01X1030394Y166508D02*
X1013309Y164147D01*
G01X1041733Y159371D02*
X1030051Y162680D01*
G01X1041757Y160560D02*
X1030134Y163852D01*
G01X1030051Y162680D02*
X1014568Y160577D01*
G01X1030134Y163852D02*
X1014265Y161697D01*
G01X1041227Y157622D02*
X1029788Y161142D01*
G01X1041191Y156429D02*
X1029692Y159968D01*
G01X1029788Y161142D02*
X1015647Y159213D01*
G01X1029692Y159968D02*
X1015950Y158093D01*
G01X1041162Y154824D02*
X1030544Y158268D01*
G01X1041118Y153629D02*
X1030441Y157092D01*
G01X1030544Y158268D02*
X1016610Y156321D01*
G01X1041992Y171647D02*
X1031484Y174520D01*
G01X1041972Y170460D02*
X1031384Y173355D01*
G01X1031484Y174520D02*
X1010199Y172497D01*
G01X1031384Y173355D02*
X1010162Y171338D01*
G01X1010199Y172497D02*
X976161Y177922D01*
G01X1010162Y171338D02*
X976185Y176753D01*
G01X1041509Y168943D02*
X1031164Y171872D01*
G01X1041482Y167755D02*
X1031062Y170705D01*
G01X1031164Y171872D02*
X1011361Y169843D01*
G01D02*
X1010600Y169792D01*
G01X1031062Y170705D02*
X1011458Y168696D01*
G01X1031164Y171872D02*
X1011361Y169843D01*
G01D02*
X1010600Y169792D01*
G01X1011458Y168696D02*
X1010545Y168635D01*
G01X1011361Y169843D02*
X1010600Y169792D01*
G01D02*
X976222Y175379D01*
G01X1010545Y168635D02*
X976246Y174209D01*
G01X1041885Y165002D02*
X1030403Y168053D01*
G01X1041900Y166188D02*
X1030477Y169224D01*
G01X1030403Y168053D02*
X1012917Y165697D01*
G01X1030477Y169224D02*
X1012615Y166817D01*
G01X1041208Y163342D02*
X1031370Y166196D01*
G01X1041179Y162152D02*
X1031034Y165095D01*
G01X1041208Y163342D02*
X1031370Y166196D01*
G01D02*
X1030394Y166508D01*
G01X1031034Y165095D02*
X1030293Y165332D01*
G01X1030394Y166508D02*
X1013309Y164147D01*
G01X1030293Y165332D02*
X1013613Y163028D01*
G01X1041757Y160560D02*
X1030134Y163852D01*
G01X1041733Y159371D02*
X1030051Y162680D01*
G01X1030134Y163852D02*
X1014265Y161697D01*
G01X1030051Y162680D02*
X1014568Y160577D01*
G01X1042247Y184044D02*
X1033021Y186652D01*
G01X1042263Y185235D02*
X1033128Y187817D01*
G01X1033021Y186652D02*
X1011274Y184642D01*
G01X1033128Y187817D02*
X1011184Y185789D01*
G01X1011274Y184642D02*
X1008771Y184480D01*
G01X1011184Y185789D02*
X1008821Y185636D01*
G01X1008771Y184480D02*
X984303Y188200D01*
G01X1008821Y185636D02*
X984489Y189335D01*
G01X984303Y188200D02*
X975568Y189730D01*
G01X984489Y189335D02*
X975551Y190901D01*
G01X1042669Y181175D02*
X1032450Y183944D01*
G01X1042675Y182365D02*
X1032554Y185108D01*
G01X1032450Y183944D02*
X1009284Y181940D01*
G01X1032554Y185108D02*
X1009322Y183098D01*
G01X1009284Y181940D02*
X975920Y187076D01*
G01X1009322Y183098D02*
X975891Y188245D01*
G01X1042890Y179572D02*
X1031985Y182447D01*
G01X1042879Y178385D02*
X1031884Y181284D01*
G01X1031985Y182447D02*
X1010225Y180593D01*
G01X1031884Y181284D02*
X1010311Y179446D01*
G01X1010225Y180593D02*
X1008864Y180505D01*
G01X1010311Y179446D02*
X1008811Y179349D01*
G01X1008864Y180505D02*
X976059Y185683D01*
G01X1008811Y179349D02*
X976086Y184514D01*
G01X1042121Y177121D02*
X1031879Y179761D01*
G01X1042454Y175848D02*
X1031783Y178598D01*
G01X1031879Y179761D02*
X1009794Y177832D01*
G01X1031783Y178598D02*
X1009756Y176674D01*
G01X1009794Y177832D02*
X975738Y183056D01*
G01X1009756Y176674D02*
X975768Y181887D01*
G01X1042161Y173109D02*
X1031444Y176040D01*
G01X1042179Y174297D02*
X1031548Y177204D01*
G01X1031444Y176040D02*
X1010595Y174188D01*
G01X1031548Y177204D02*
X1010506Y175335D01*
G01X1031444Y176040D02*
X1010595Y174188D01*
G01D02*
X1009517Y174117D01*
G01D02*
X976137Y179297D01*
G01X1010506Y175335D02*
X1009568Y175273D01*
G01X1009517Y174117D02*
X976137Y179297D01*
G01X1009568Y175273D02*
X976110Y180465D01*
G01X1041972Y170460D02*
X1031384Y173355D01*
G01X1041992Y171647D02*
X1031484Y174520D01*
G01X1031384Y173355D02*
X1010162Y171338D01*
G01X1031484Y174520D02*
X1010199Y172497D01*
G01X1010162Y171338D02*
X976185Y176753D01*
G01X1010199Y172497D02*
X976161Y177922D01*
G01X1042263Y185235D02*
X1033128Y187817D01*
G01X1042247Y184044D02*
X1033021Y186652D01*
G01X1033128Y187817D02*
X1011184Y185789D01*
G01X1033021Y186652D02*
X1011274Y184642D01*
G01X1011184Y185789D02*
X1008821Y185636D01*
G01X1011274Y184642D02*
X1008771Y184480D01*
G01X1008821Y185636D02*
X984489Y189335D01*
G01X1008771Y184480D02*
X984303Y188200D01*
G01X984489Y189335D02*
X975551Y190901D01*
G01X984303Y188200D02*
X975568Y189730D01*
G01X1042675Y182365D02*
X1032554Y185108D01*
G01X1042669Y181175D02*
X1032450Y183944D01*
G01X1032554Y185108D02*
X1009322Y183098D01*
G01X1032450Y183944D02*
X1009284Y181940D01*
G01X1009322Y183098D02*
X975891Y188245D01*
G01X1009284Y181940D02*
X975920Y187076D01*
G01X1042879Y178385D02*
X1031884Y181284D01*
G01X1042890Y179572D02*
X1031985Y182447D01*
G01X1031884Y181284D02*
X1010311Y179446D01*
G01X1031985Y182447D02*
X1010225Y180593D01*
G01X1010311Y179446D02*
X1008811Y179349D01*
G01X1010225Y180593D02*
X1008864Y180505D01*
G01X1008811Y179349D02*
X976086Y184514D01*
G01X1008864Y180505D02*
X976059Y185683D01*
G01X1042454Y175848D02*
X1031783Y178598D01*
G01X1042454Y175848D02*
X1031783Y178598D01*
G01X1042121Y177121D02*
X1031879Y179761D01*
G01X1031783Y178598D02*
X1009756Y176674D01*
G01X1031879Y179761D02*
X1009794Y177832D01*
G01X1009756Y176674D02*
X975768Y181887D01*
G01X1009794Y177832D02*
X975738Y183056D01*
G01X1042179Y174297D02*
X1031548Y177204D01*
G01X1042161Y173109D02*
X1031444Y176040D01*
G01X1031548Y177204D02*
X1010506Y175335D01*
G01D02*
X1009568Y175273D01*
G01X1031444Y176040D02*
X1010595Y174188D01*
G01X1010506Y175335D02*
X1009568Y175273D01*
G01X1010595Y174188D02*
X1009517Y174117D01*
G01X1010506Y175335D02*
X1009568Y175273D01*
G01D02*
X976110Y180465D01*
G01X1009517Y174117D02*
X976137Y179297D01*
G01X1025378Y198050D02*
X1024898Y197221D01*
G01X1026374Y197475D02*
X1025819Y196514D01*
G01X1024898Y197221D02*
X1018612Y190935D01*
G01D02*
X1017597D01*
G01X1025819Y196514D02*
X1019089Y189785D01*
G01X1018612Y190935D02*
X1017597D01*
G01X1014947D02*
X1013597D01*
G01X1010947D02*
X1009597D01*
G01X1006947D02*
X1006083D01*
G01X1019089Y189785D02*
X1005606D01*
G01X1006083Y190935D02*
X1002854Y194164D01*
G01X1005606Y189785D02*
X1002377Y193014D01*
G01X1002854Y194164D02*
X980286D01*
G01X1002377Y193014D02*
X979809D01*
G01X980286Y194164D02*
X978050Y196400D01*
G01X979809Y193014D02*
X977573Y195250D01*
G01X1026374Y197475D02*
X1025819Y196514D01*
G01X1025378Y198050D02*
X1024898Y197221D01*
G01X1025819Y196514D02*
X1019089Y189785D01*
G01X1024898Y197221D02*
X1018612Y190935D01*
G01X1025819Y196514D02*
X1019089Y189785D01*
G01D02*
X1005606D01*
G01X1018612Y190935D02*
X1017597D01*
G01X1019089Y189785D02*
X1005606D01*
G01X1014947Y190935D02*
X1013597D01*
G01X1019089Y189785D02*
X1005606D01*
G01X1010947Y190935D02*
X1009597D01*
G01X1019089Y189785D02*
X1005606D01*
G01X1006947Y190935D02*
X1006083D01*
G01X1005606Y189785D02*
X1002377Y193014D01*
G01X1006083Y190935D02*
X1002854Y194164D01*
G01X1002377Y193014D02*
X979809D01*
G01X1002854Y194164D02*
X980286D01*
G01X979809Y193014D02*
X977573Y195250D01*
G01X980286Y194164D02*
X978050Y196400D01*
G01X1027666Y204340D02*
X1025926Y203033D01*
G01X1028357Y203420D02*
X1026310Y201883D01*
G01X1025926Y203033D02*
X1018769D01*
G01X1026310Y201883D02*
X1019246D01*
G01X1018769Y203033D02*
X1013186Y197450D01*
G01X1019246Y201883D02*
X1013663Y196300D01*
G01X1013186Y197450D02*
X1011836D01*
G01X1009186D02*
X1007836D01*
G01X1005186D02*
X1003836D01*
G01X1001186D02*
X999836D01*
G01X997186D02*
X981950D01*
G01X1013663Y196300D02*
X981473D01*
G01X981950Y197450D02*
X979800Y199600D01*
G01X981473Y196300D02*
X979323Y198450D01*
G01X1028357Y203420D02*
X1026310Y201883D01*
G01X1027666Y204340D02*
X1025926Y203033D01*
G01X1026310Y201883D02*
X1019246D01*
G01X1025926Y203033D02*
X1018769D01*
G01X1019246Y201883D02*
X1013663Y196300D01*
G01X1018769Y203033D02*
X1013186Y197450D01*
G01X1013663Y196300D02*
X981473D01*
G01X1013186Y197450D02*
X1011836D01*
G01X1013663Y196300D02*
X981473D01*
G01X1009186Y197450D02*
X1007836D01*
G01X1013663Y196300D02*
X981473D01*
G01X1005186Y197450D02*
X1003836D01*
G01X1013663Y196300D02*
X981473D01*
G01X1001186Y197450D02*
X999836D01*
G01X1013663Y196300D02*
X981473D01*
G01X997186Y197450D02*
X981950D01*
G01X981473Y196300D02*
X979323Y198450D01*
G01X981950Y197450D02*
X979800Y199600D01*
G01X1004783Y202966D02*
X1000318D01*
G01X1004783Y201816D02*
X1000795D01*
G01X1000318Y202966D02*
X998921Y201569D01*
G01X1000795Y201816D02*
X999398Y200419D01*
G01X998921Y201569D02*
X986207D01*
G01X999398Y200419D02*
X985730D01*
G01X986207Y201569D02*
X981476Y206300D01*
G01X985730Y200419D02*
X980999Y205150D01*
G01X1004783Y201816D02*
X1000795D01*
G01X1004783Y202966D02*
X1000318D01*
G01X1000795Y201816D02*
X999398Y200419D01*
G01X1000318Y202966D02*
X998921Y201569D01*
G01X999398Y200419D02*
X985730D01*
G01X998921Y201569D02*
X986207D01*
G01X985730Y200419D02*
X980999Y205150D01*
G01X986207Y201569D02*
X981476Y206300D01*
G01X1047400Y398000D02*
X998073D01*
G01X1046923Y399150D02*
X997596D01*
G01X998073Y398000D02*
X993473Y393400D01*
G01X997596Y399150D02*
X992996Y394550D01*
G01D02*
X971978D01*
G01X1046923Y399150D02*
X997596D01*
G01X1047400Y398000D02*
X998073D01*
G01X997596Y399150D02*
X992996Y394550D01*
G01X998073Y398000D02*
X993473Y393400D01*
G01X992996Y394550D02*
X971978D01*
G01X995851Y404495D02*
X987656Y396300D01*
G01X995374Y405645D02*
X987179Y397450D01*
G01X987656Y396300D02*
X973700D01*
G01X987179Y397450D02*
X974177D01*
G01X973700Y396300D02*
X972285Y397714D01*
G01X974177Y397450D02*
X972936Y398690D01*
G01X995374Y405645D02*
X987179Y397450D01*
G01X995851Y404495D02*
X987656Y396300D01*
G01X987179Y397450D02*
X974177D01*
G01X987656Y396300D02*
X973700D01*
G01X974177Y397450D02*
X972936Y398690D01*
G01X973700Y396300D02*
X972285Y397714D01*
G01X976451Y409194D02*
X1036847Y421657D01*
G01X976447Y410368D02*
X1036702Y422802D01*
G01X1017730Y448369D02*
X976237Y458141D01*
G01X976274Y459314D02*
X1017836Y449526D01*
G01X1051954Y450053D02*
X1017730Y448369D01*
G01X1017836Y449526D02*
X1051981Y451206D01*
G01X1017961Y450894D02*
X1052013Y452570D01*
G01X1052040Y453723D02*
X1018067Y452051D01*
G01X976317Y460702D02*
X1017961Y450894D01*
G01X1018067Y452051D02*
X976354Y461875D01*
G01X976674Y472119D02*
X1018991Y462151D01*
G01X976637Y470946D02*
X1018885Y460994D01*
G01X1018991Y462151D02*
X1052276Y463791D01*
G01X1018885Y460994D02*
X1052249Y462638D01*
G01X976716Y473507D02*
X1019116Y463519D01*
G01X976753Y474680D02*
X1019222Y464676D01*
G01X1019116Y463519D02*
X1052308Y465155D01*
G01X1019222Y464676D02*
X1052335Y466308D01*
G01X976515Y412944D02*
X1036363Y425299D01*
G01X976519Y411770D02*
X1036508Y424154D01*
G01X976114Y454192D02*
X1017374Y444476D01*
G01X976077Y453019D02*
X1017268Y443319D01*
G01X1017374Y444476D02*
X1051863Y446172D01*
G01X1017268Y443319D02*
X1051836Y445019D01*
G01X976447Y410368D02*
X1036702Y422802D01*
G01X976451Y409194D02*
X1036847Y421657D01*
G01X976157Y455580D02*
X1017499Y445844D01*
G01X976194Y456753D02*
X1017605Y447001D01*
G01X1017499Y445844D02*
X1051895Y447536D01*
G01X1017605Y447001D02*
X1051922Y448689D01*
G01X1017836Y449526D02*
X1051981Y451206D01*
G01X1051954Y450053D02*
X1017730Y448369D01*
G01X976274Y459314D02*
X1017836Y449526D01*
G01X1017730Y448369D02*
X976237Y458141D01*
G01X1018067Y452051D02*
X976354Y461875D01*
G01X976317Y460702D02*
X1017961Y450894D01*
G01X1052040Y453723D02*
X1018067Y452051D01*
G01X1017961Y450894D02*
X1052013Y452570D01*
G01X976637Y470946D02*
X1018885Y460994D01*
G01X976674Y472119D02*
X1018991Y462151D01*
G01X1018885Y460994D02*
X1052249Y462638D01*
G01X1018991Y462151D02*
X1052276Y463791D01*
G01X976519Y411770D02*
X1036508Y424154D01*
G01X976515Y412944D02*
X1036363Y425299D01*
G01X976502Y422025D02*
X1035216Y434146D01*
G01X976498Y423199D02*
X1035071Y435291D01*
G01X976077Y453019D02*
X1017268Y443319D01*
G01X976114Y454192D02*
X1017374Y444476D01*
G01X1017268Y443319D02*
X1051836Y445019D01*
G01X1017374Y444476D02*
X1051863Y446172D01*
G01X976397Y463263D02*
X1018192Y453419D01*
G01X976434Y464436D02*
X1018298Y454576D01*
G01X1018192Y453419D02*
X1052072Y455087D01*
G01X1018298Y454576D02*
X1052099Y456240D01*
G01X976753Y474680D02*
X1019222Y464676D01*
G01X976716Y473507D02*
X1019116Y463519D01*
G01X1019222Y464676D02*
X1052335Y466308D01*
G01X1019116Y463519D02*
X1052308Y465155D01*
G01X976194Y456753D02*
X1017605Y447001D01*
G01X976157Y455580D02*
X1017499Y445844D01*
G01X1017605Y447001D02*
X1051922Y448689D01*
G01X1017499Y445844D02*
X1051895Y447536D01*
G01X976530Y414339D02*
X1036250Y426655D01*
G01X976526Y415513D02*
X1036105Y427800D01*
G01X976517Y418075D02*
X1035763Y430297D01*
G01X976521Y416901D02*
X1035908Y429152D01*
G01X976511Y419463D02*
X1035575Y431649D01*
G01X976507Y420637D02*
X1035430Y432794D01*
G01X976498Y423199D02*
X1035071Y435291D01*
G01X976502Y422025D02*
X1035216Y434146D01*
G01X976492Y424588D02*
X1034806Y436640D01*
G01X976488Y425762D02*
X1034660Y437785D01*
G01X976412Y428337D02*
X1034351Y440284D01*
G01X976416Y427163D02*
X1034496Y439139D01*
G01X975997Y450458D02*
X1017037Y440794D01*
G01X976034Y451631D02*
X1017143Y441951D01*
G01X1017037Y440794D02*
X1051777Y442502D01*
G01X1017143Y441951D02*
X1051804Y443655D01*
G01X976434Y464436D02*
X1018298Y454576D01*
G01X976397Y463263D02*
X1018192Y453419D01*
G01X1018298Y454576D02*
X1052099Y456240D01*
G01X1018192Y453419D02*
X1052072Y455087D01*
G01X976526Y415513D02*
X1036105Y427800D01*
G01X976530Y414339D02*
X1036250Y426655D01*
G01X976521Y416901D02*
X1035908Y429152D01*
G01X976517Y418075D02*
X1035763Y430297D01*
G01X976507Y420637D02*
X1035430Y432794D01*
G01X976511Y419463D02*
X1035575Y431649D01*
G01X976488Y425762D02*
X1034660Y437785D01*
G01X976492Y424588D02*
X1034806Y436640D01*
G01X976416Y427163D02*
X1034496Y439139D01*
G01X976412Y428337D02*
X1034351Y440284D01*
G01X976034Y451631D02*
X1017143Y441951D01*
G01X975997Y450458D02*
X1017037Y440794D01*
G01X1017143Y441951D02*
X1051804Y443655D01*
G01X1017037Y440794D02*
X1051777Y442502D01*
G01X976477Y465824D02*
X1018423Y455944D01*
G01X976514Y466997D02*
X1018529Y457101D01*
G01X1018423Y455944D02*
X1052131Y457604D01*
G01X1018529Y457101D02*
X1052158Y458757D01*
G01X976594Y469558D02*
X1018760Y459626D01*
G01X976557Y468385D02*
X1018654Y458469D01*
G01X1018760Y459626D02*
X1052217Y461274D01*
G01X1018654Y458469D02*
X1052190Y460121D01*
G01X976514Y466997D02*
X1018529Y457101D01*
G01X976477Y465824D02*
X1018423Y455944D01*
G01X1018529Y457101D02*
X1052158Y458757D01*
G01X1018423Y455944D02*
X1052131Y457604D01*
G01X976557Y468385D02*
X1018654Y458469D01*
G01X976594Y469558D02*
X1018760Y459626D01*
G01X1018654Y458469D02*
X1052190Y460121D01*
G01X1018760Y459626D02*
X1052217Y461274D01*
G01X1046207Y404495D02*
X995851D01*
G01X1045730Y405645D02*
X995374D01*
G01X1045730D02*
X995374D01*
G01X1046207Y404495D02*
X995851D01*
G01X1043851Y408423D02*
X995130D01*
G01X1043374Y409573D02*
X994653D01*
G01X995130Y408423D02*
X991514Y404807D01*
G01X994653Y409573D02*
X991037Y405957D01*
G01X1043374Y409573D02*
X994653D01*
G01X1043851Y408423D02*
X995130D01*
G01X994653Y409573D02*
X991037Y405957D01*
G01X995130Y408423D02*
X991514Y404807D01*
G01X976799Y476068D02*
X1019347Y466044D01*
G01X976836Y477241D02*
X1019453Y467201D01*
G01X1019347Y466044D02*
X1052367Y467672D01*
G01X1019453Y467201D02*
X1052394Y468825D01*
G01X977055Y479825D02*
X1019880Y469736D01*
G01X977018Y478652D02*
X1019774Y468579D01*
G01X1019880Y469736D02*
X1052453Y471342D01*
G01X1019774Y468579D02*
X1052426Y470189D01*
G01X976836Y477241D02*
X1019453Y467201D01*
G01X976799Y476068D02*
X1019347Y466044D01*
G01X1019453Y467201D02*
X1052394Y468825D01*
G01X1019347Y466044D02*
X1052367Y467672D01*
G01X977018Y478652D02*
X1019774Y468579D01*
G01X977055Y479825D02*
X1019880Y469736D01*
G01X1019774Y468579D02*
X1052426Y470189D01*
G01X1019880Y469736D02*
X1052453Y471342D01*
G01X971920Y504844D02*
X1011835Y499813D01*
G01X1011762Y498663D02*
X1041209D01*
G01X1011835Y499813D02*
X1041289D01*
G01X971920Y504844D02*
X1011835Y499813D01*
G01D02*
X1041289D01*
G01X1011762Y498663D02*
X1041209D01*
G01X1041687Y134118D02*
X1110860Y145007D01*
G01X1041766Y135295D02*
X1110681Y146143D01*
G01X1041687Y134118D02*
X1110860Y145007D01*
G01X1041781Y132623D02*
X1110930Y143466D01*
G01X1041707Y131447D02*
X1110931Y142302D01*
G01X1041766Y135295D02*
X1110681Y146143D01*
G01X1041687Y134118D02*
X1110860Y145007D01*
G01X1041707Y131447D02*
X1110931Y142302D01*
G01X1041781Y132623D02*
X1110930Y143466D01*
G01X1134687Y176520D02*
X1041118Y153629D01*
G01X1134400Y177634D02*
X1041162Y154824D01*
G01X1041079Y151991D02*
X1143045Y177171D01*
G01X1143369Y176066D02*
X1041029Y150794D01*
G01X1145758Y173937D02*
X1041066Y148047D01*
G01X1145436Y175043D02*
X1041114Y149244D01*
G01X1111329Y156824D02*
X1041270Y146314D01*
G01X1111315Y155659D02*
X1041168Y145135D01*
G01X1111506Y154176D02*
X1041525Y143423D01*
G01X1111493Y153010D02*
X1041429Y142244D01*
G01X1110822Y150313D02*
X1041258Y139579D01*
G01X1110833Y151479D02*
X1041355Y140758D01*
G01X1110571Y148867D02*
X1041608Y138006D01*
G01X1110562Y147701D02*
X1041517Y136827D01*
G01X1134400Y177634D02*
X1041162Y154824D01*
G01X1134400Y177634D02*
X1041162Y154824D01*
G01X1134687Y176520D02*
X1041118Y153629D01*
G01X1143369Y176066D02*
X1041029Y150794D01*
G01X1041079Y151991D02*
X1143045Y177171D01*
G01X1145436Y175043D02*
X1041114Y149244D01*
G01X1145758Y173937D02*
X1041066Y148047D01*
G01X1111315Y155659D02*
X1041168Y145135D01*
G01X1111329Y156824D02*
X1041270Y146314D01*
G01X1111493Y153010D02*
X1041429Y142244D01*
G01X1111506Y154176D02*
X1041525Y143423D01*
G01X1110833Y151479D02*
X1041355Y140758D01*
G01X1110822Y150313D02*
X1041258Y139579D01*
G01X1110562Y147701D02*
X1041517Y136827D01*
G01X1110571Y148867D02*
X1041608Y138006D01*
G01X1129319Y177778D02*
X1041191Y156429D01*
G01X1129036Y178893D02*
X1041227Y157622D01*
G01X1125484Y187528D02*
X1041482Y167755D01*
G01X1125129Y188626D02*
X1041509Y168943D01*
G01X1126897Y186471D02*
X1041900Y166188D01*
G01X1127226Y185367D02*
X1041885Y165002D01*
G01X1127491Y182737D02*
X1041179Y162152D01*
G01X1127177Y183845D02*
X1041208Y163342D01*
G01X1118356Y177813D02*
X1041733Y159371D01*
G01X1118077Y178929D02*
X1041757Y160560D01*
G01X1129036Y178893D02*
X1041227Y157622D01*
G01X1129319Y177778D02*
X1041191Y156429D01*
G01X1123690Y191050D02*
X1041992Y171647D01*
G01X1124045Y189952D02*
X1041972Y170460D01*
G01X1125129Y188626D02*
X1041509Y168943D01*
G01X1125484Y187528D02*
X1041482Y167755D01*
G01X1127226Y185367D02*
X1041885Y165002D01*
G01X1126897Y186471D02*
X1041900Y166188D01*
G01X1127177Y183845D02*
X1041208Y163342D01*
G01X1127491Y182737D02*
X1041179Y162152D01*
G01X1118077Y178929D02*
X1041757Y160560D01*
G01X1118356Y177813D02*
X1041733Y159371D01*
G01X1096250Y197723D02*
X1042247Y184044D01*
G01X1095660Y198761D02*
X1042263Y185235D01*
G01X1098522Y195680D02*
X1042669Y181175D01*
G01X1097978Y196727D02*
X1042675Y182365D01*
G01X1113574Y196845D02*
X1042890Y179572D01*
G01X1114108Y195791D02*
X1043549Y178549D01*
G01X1113574Y196845D02*
X1042890Y179572D01*
G01X1043549Y178549D02*
X1042879Y178385D01*
G01X1122791Y196257D02*
X1042464Y177033D01*
G01X1123184Y195168D02*
X1042454Y175848D01*
G01X1042464Y177033D02*
X1042121Y177121D01*
G01X1124299Y192867D02*
X1042161Y173109D01*
G01X1123932Y193962D02*
X1042179Y174297D01*
G01X1124045Y189952D02*
X1041972Y170460D01*
G01X1123690Y191050D02*
X1041992Y171647D01*
G01X1095660Y198761D02*
X1042263Y185235D01*
G01X1096250Y197723D02*
X1042247Y184044D01*
G01X1097978Y196727D02*
X1042675Y182365D01*
G01X1098522Y195680D02*
X1042669Y181175D01*
G01X1114108Y195791D02*
X1043549Y178549D01*
G01D02*
X1042879Y178385D01*
G01X1113574Y196845D02*
X1042890Y179572D01*
G01X1123184Y195168D02*
X1042454Y175848D01*
G01X1123184Y195168D02*
X1042454Y175848D01*
G01X1122791Y196257D02*
X1042464Y177033D01*
G01D02*
X1042121Y177121D01*
G01X1123932Y193962D02*
X1042179Y174297D01*
G01X1124299Y192867D02*
X1042161Y173109D01*
G01X1088002Y400614D02*
X1084366Y404250D01*
G01X1088815Y401429D02*
X1084844Y405400D01*
G01X1053650Y404250D02*
X1047400Y398000D01*
G01X1053173Y405400D02*
X1046923Y399150D01*
G01X1088815Y401429D02*
X1084844Y405400D01*
G01X1088002Y400614D02*
X1084366Y404250D01*
G01X1053173Y405400D02*
X1046923Y399150D01*
G01X1053650Y404250D02*
X1047400Y398000D01*
G01X1036847Y421657D02*
X1051305Y422366D01*
G01X1036702Y422802D02*
X1051332Y423519D01*
G01X1051305Y422366D02*
X1094974Y418173D01*
G01X1051332Y423519D02*
X1094963Y419330D01*
G01X1094974Y418173D02*
X1107050Y419573D01*
G01X1094963Y419330D02*
X1107215Y420750D01*
G01X1094712Y445947D02*
X1051954Y450053D01*
G01X1051981Y451206D02*
X1094701Y447104D01*
G01X1146163Y451912D02*
X1094712Y445947D01*
G01X1094701Y447104D02*
X1150603Y453585D01*
G01X1094688Y448472D02*
X1146163Y454440D01*
G01Y455598D02*
X1094677Y449629D01*
G01X1052013Y452570D02*
X1094688Y448472D01*
G01X1094677Y449629D02*
X1052040Y453723D01*
G01X1052276Y463791D02*
X1094584Y459729D01*
G01X1052249Y462638D02*
X1094595Y458572D01*
G01X1094584Y459729D02*
X1146163Y465710D01*
G01X1094595Y458572D02*
X1146163Y464552D01*
G01X1052308Y465155D02*
X1094571Y461097D01*
G01X1052335Y466308D02*
X1094560Y462254D01*
G01X1094571Y461097D02*
X1146163Y467081D01*
G01X1094560Y462254D02*
X1122836Y465534D01*
G01X1094571Y461097D02*
X1146163Y467081D01*
G01X1036363Y425299D02*
X1051391Y426036D01*
G01X1036508Y424154D02*
X1051364Y424883D01*
G01X1051391Y426036D02*
X1094939Y421854D01*
G01X1051364Y424883D02*
X1094950Y420697D01*
G01X1094939Y421854D02*
X1107574Y423318D01*
G01X1094950Y420697D02*
X1107409Y422141D01*
G01X1051863Y446172D02*
X1094749Y442054D01*
G01X1051836Y445019D02*
X1094760Y440897D01*
G01X1094749Y442054D02*
X1110430Y443872D01*
G01X1094760Y440897D02*
X1110265Y442695D01*
G01X1036702Y422802D02*
X1051332Y423519D01*
G01X1036847Y421657D02*
X1051305Y422366D01*
G01X1051332Y423519D02*
X1094963Y419330D01*
G01X1051305Y422366D02*
X1094974Y418173D01*
G01X1094963Y419330D02*
X1107215Y420750D01*
G01X1094974Y418173D02*
X1107050Y419573D01*
G01X1051895Y447536D02*
X1069820Y445815D01*
G01D02*
X1069826Y445814D01*
G01D02*
X1069831D01*
G01D02*
X1069839Y445813D01*
G01X1069844Y445812D02*
X1069855D01*
G01X1051922Y448689D02*
X1069909Y446962D01*
G01X1051895Y447536D02*
X1069820Y445815D01*
G01X1069855Y445812D02*
X1094734Y443422D01*
G01X1069909Y446962D02*
X1069911D01*
G01X1051895Y447536D02*
X1069820Y445815D01*
G01X1069855Y445812D02*
X1094734Y443422D01*
G01X1069911Y446962D02*
X1069930Y446961D01*
G01X1051895Y447536D02*
X1069820Y445815D01*
G01X1069855Y445812D02*
X1094734Y443422D01*
G01X1069930Y446961D02*
X1069935D01*
G01X1051895Y447536D02*
X1069820Y445815D01*
G01X1069855Y445812D02*
X1094734Y443422D01*
G01X1069935Y446961D02*
X1069941Y446960D01*
G01X1051895Y447536D02*
X1069820Y445815D01*
G01X1069855Y445812D02*
X1094734Y443422D01*
G01X1069941Y446960D02*
X1069949Y446959D01*
G01X1051895Y447536D02*
X1069820Y445815D01*
G01X1069855Y445812D02*
X1094734Y443422D01*
G01X1069949Y446959D02*
X1069954D01*
G01X1051895Y447536D02*
X1069820Y445815D01*
G01X1069855Y445812D02*
X1094734Y443422D01*
G01X1069959Y446958D02*
X1069965Y446957D01*
G01X1069820Y445815D02*
X1069826Y445814D01*
G01D02*
X1069831D01*
G01D02*
X1069839Y445813D01*
G01X1069844Y445812D02*
X1069855D01*
G01D02*
X1094734Y443422D01*
G01X1069965Y446957D02*
X1094723Y444579D01*
G01X1094734Y443422D02*
X1119552Y446298D01*
G01X1094723Y444579D02*
X1150450Y451039D01*
G01X1094701Y447104D02*
X1150603Y453585D01*
G01X1094701Y447104D02*
X1150603Y453585D01*
G01X1146163Y451912D02*
X1094712Y445947D01*
G01X1051981Y451206D02*
X1094701Y447104D01*
G01X1094712Y445947D02*
X1051954Y450053D01*
G01X1094677Y449629D02*
X1052040Y453723D01*
G01X1052013Y452570D02*
X1094688Y448472D01*
G01X1146163Y455598D02*
X1094677Y449629D01*
G01X1094688Y448472D02*
X1146163Y454440D01*
G01X1052249Y462638D02*
X1094595Y458572D01*
G01X1052276Y463791D02*
X1094584Y459729D01*
G01X1094595Y458572D02*
X1146163Y464552D01*
G01X1094584Y459729D02*
X1146163Y465710D01*
G01X1036508Y424154D02*
X1051364Y424883D01*
G01X1036363Y425299D02*
X1051391Y426036D01*
G01X1051364Y424883D02*
X1094950Y420697D01*
G01X1051391Y426036D02*
X1094939Y421854D01*
G01X1094950Y420697D02*
X1107409Y422141D01*
G01X1094939Y421854D02*
X1107574Y423318D01*
G01X1035216Y434146D02*
X1051600Y434951D01*
G01X1035071Y435291D02*
X1047446Y435899D01*
G01X1035216Y434146D02*
X1051600Y434951D01*
G01X1047446Y435898D02*
X1051627Y436104D01*
G01X1051600Y434951D02*
X1094856Y430797D01*
G01X1051627Y436104D02*
X1094845Y431954D01*
G01X1094856Y430797D02*
X1108835Y432418D01*
G01X1094845Y431954D02*
X1109000Y433595D01*
G01X1051836Y445019D02*
X1094760Y440897D01*
G01X1051863Y446172D02*
X1094749Y442054D01*
G01X1094760Y440897D02*
X1110265Y442695D01*
G01X1094749Y442054D02*
X1110430Y443872D01*
G01X1052072Y455087D02*
X1094663Y450997D01*
G01X1052099Y456240D02*
X1094652Y452154D01*
G01X1094663Y450997D02*
X1146163Y456968D01*
G01X1094652Y452154D02*
X1146163Y458126D01*
G01X1052367Y467672D02*
X1094545Y463622D01*
G01D02*
X1151504Y470227D01*
G01X1052335Y466308D02*
X1094560Y462254D01*
G01X1052308Y465155D02*
X1094571Y461097D01*
G01X1094560Y462254D02*
X1122836Y465534D01*
G01X1094571Y461097D02*
X1146163Y467081D01*
G01X1052367Y467672D02*
X1094545Y463622D01*
G01D02*
X1151504Y470227D01*
G01X1051922Y448689D02*
X1069909Y446962D01*
G01D02*
X1069911D01*
G01D02*
X1069930Y446961D01*
G01D02*
X1069935D01*
G01D02*
X1069941Y446960D01*
G01D02*
X1069949Y446959D01*
G01D02*
X1069954D01*
G01X1069959Y446958D02*
X1069965Y446957D01*
G01X1051895Y447536D02*
X1069820Y445815D01*
G01X1051922Y448689D02*
X1069909Y446962D01*
G01X1069965Y446957D02*
X1094723Y444579D01*
G01X1069820Y445815D02*
X1069826Y445814D01*
G01X1051922Y448689D02*
X1069909Y446962D01*
G01X1069965Y446957D02*
X1094723Y444579D01*
G01X1069826Y445814D02*
X1069831D01*
G01X1051922Y448689D02*
X1069909Y446962D01*
G01X1069965Y446957D02*
X1094723Y444579D01*
G01X1069831Y445814D02*
X1069839Y445813D01*
G01X1051922Y448689D02*
X1069909Y446962D01*
G01X1069965Y446957D02*
X1094723Y444579D01*
G01X1069844Y445812D02*
X1069855D01*
G01X1069909Y446962D02*
X1069911D01*
G01D02*
X1069930Y446961D01*
G01D02*
X1069935D01*
G01D02*
X1069941Y446960D01*
G01D02*
X1069949Y446959D01*
G01D02*
X1069954D01*
G01X1069959Y446958D02*
X1069965Y446957D01*
G01D02*
X1094723Y444579D01*
G01X1069855Y445812D02*
X1094734Y443422D01*
G01X1094723Y444579D02*
X1150450Y451039D01*
G01X1094734Y443422D02*
X1119552Y446298D01*
G01X1094723Y444579D02*
X1150450Y451039D01*
G01X1036250Y426655D02*
X1051423Y427400D01*
G01X1036105Y427800D02*
X1051450Y428553D01*
G01X1051423Y427400D02*
X1094926Y423222D01*
G01X1051450Y428553D02*
X1094915Y424379D01*
G01X1094926Y423222D02*
X1107766Y424711D01*
G01X1094915Y424379D02*
X1107931Y425888D01*
G01X1035763Y430297D02*
X1051509Y431070D01*
G01X1035908Y429152D02*
X1051482Y429917D01*
G01X1051509Y431070D02*
X1094892Y426904D01*
G01X1051482Y429917D02*
X1094903Y425747D01*
G01X1094892Y426904D02*
X1108290Y428457D01*
G01X1094903Y425747D02*
X1108125Y427280D01*
G01X1035575Y431649D02*
X1043557Y432040D01*
G01Y432041D02*
X1051541Y432434D01*
G01X1035430Y432794D02*
X1049488Y433486D01*
G01X1043557Y432041D02*
X1051541Y432434D01*
G01X1049488Y433485D02*
X1051568Y433587D01*
G01X1051541Y432434D02*
X1094880Y428272D01*
G01X1051568Y433587D02*
X1094869Y429429D01*
G01X1094880Y428272D02*
X1108481Y429849D01*
G01X1094869Y429429D02*
X1108646Y431026D01*
G01X1035071Y435291D02*
X1047446Y435899D01*
G01Y435898D02*
X1051627Y436104D01*
G01X1035216Y434146D02*
X1051600Y434951D01*
G01X1051627Y436104D02*
X1094845Y431954D01*
G01X1051600Y434951D02*
X1094856Y430797D01*
G01X1094845Y431954D02*
X1109000Y433595D01*
G01X1094856Y430797D02*
X1108835Y432418D01*
G01X1034806Y436640D02*
X1051659Y437468D01*
G01X1034660Y437785D02*
X1051686Y438621D01*
G01X1051659Y437468D02*
X1094830Y433322D01*
G01X1051686Y438621D02*
X1094819Y434479D01*
G01X1094830Y433322D02*
X1109196Y434987D01*
G01X1094819Y434479D02*
X1109361Y436164D01*
G01X1034351Y440284D02*
X1051745Y441138D01*
G01X1034496Y439139D02*
X1051718Y439985D01*
G01X1051745Y441138D02*
X1094797Y437004D01*
G01X1051718Y439985D02*
X1094808Y435847D01*
G01X1094797Y437004D02*
X1109706Y438732D01*
G01X1094808Y435847D02*
X1109541Y437555D01*
G01X1051777Y442502D02*
X1094783Y438372D01*
G01X1051804Y443655D02*
X1094772Y439529D01*
G01X1094783Y438372D02*
X1109904Y440125D01*
G01X1094772Y439529D02*
X1110069Y441302D01*
G01X1052099Y456240D02*
X1094652Y452154D01*
G01X1052072Y455087D02*
X1094663Y450997D01*
G01X1094652Y452154D02*
X1146163Y458126D01*
G01X1094663Y450997D02*
X1146163Y456968D01*
G01X1036105Y427800D02*
X1051450Y428553D01*
G01X1036250Y426655D02*
X1051423Y427400D01*
G01X1051450Y428553D02*
X1094915Y424379D01*
G01X1051423Y427400D02*
X1094926Y423222D01*
G01X1094915Y424379D02*
X1107931Y425888D01*
G01X1094926Y423222D02*
X1107766Y424711D01*
G01X1035908Y429152D02*
X1051482Y429917D01*
G01X1035763Y430297D02*
X1051509Y431070D01*
G01X1051482Y429917D02*
X1094903Y425747D01*
G01X1051509Y431070D02*
X1094892Y426904D01*
G01X1094903Y425747D02*
X1108125Y427280D01*
G01X1094892Y426904D02*
X1108290Y428457D01*
G01X1035430Y432794D02*
X1049488Y433486D01*
G01X1035575Y431649D02*
X1043557Y432040D01*
G01X1035430Y432794D02*
X1049488Y433486D01*
G01Y433485D02*
X1051568Y433587D01*
G01X1043557Y432041D02*
X1051541Y432434D01*
G01X1051568Y433587D02*
X1094869Y429429D01*
G01X1051541Y432434D02*
X1094880Y428272D01*
G01X1094869Y429429D02*
X1108646Y431026D01*
G01X1094880Y428272D02*
X1108481Y429849D01*
G01X1034660Y437785D02*
X1051686Y438621D01*
G01X1034806Y436640D02*
X1051659Y437468D01*
G01X1051686Y438621D02*
X1094819Y434479D01*
G01X1051659Y437468D02*
X1094830Y433322D01*
G01X1094819Y434479D02*
X1109361Y436164D01*
G01X1094830Y433322D02*
X1109196Y434987D01*
G01X1034496Y439139D02*
X1051718Y439985D01*
G01X1034351Y440284D02*
X1051745Y441138D01*
G01X1051718Y439985D02*
X1094808Y435847D01*
G01X1051745Y441138D02*
X1094797Y437004D01*
G01X1094808Y435847D02*
X1109541Y437555D01*
G01X1094797Y437004D02*
X1109706Y438732D01*
G01X1051804Y443655D02*
X1094772Y439529D01*
G01X1051777Y442502D02*
X1094783Y438372D01*
G01X1094772Y439529D02*
X1110069Y441302D01*
G01X1094783Y438372D02*
X1109904Y440125D01*
G01X1052131Y457604D02*
X1094639Y453522D01*
G01X1052158Y458757D02*
X1094628Y454679D01*
G01X1094639Y453522D02*
X1146163Y459496D01*
G01X1094628Y454679D02*
X1146163Y460654D01*
G01X1052217Y461274D02*
X1094607Y457204D01*
G01X1052190Y460121D02*
X1094618Y456047D01*
G01X1094607Y457204D02*
X1122721Y460466D01*
G01X1094618Y456047D02*
X1146163Y462026D01*
G01X1052158Y458757D02*
X1094628Y454679D01*
G01X1052131Y457604D02*
X1094639Y453522D01*
G01X1094628Y454679D02*
X1146163Y460654D01*
G01X1094639Y453522D02*
X1146163Y459496D01*
G01X1052190Y460121D02*
X1094618Y456047D01*
G01X1052217Y461274D02*
X1094607Y457204D01*
G01X1094618Y456047D02*
X1146163Y462026D01*
G01X1094607Y457204D02*
X1122721Y460466D01*
G01X1094618Y456047D02*
X1146163Y462026D01*
G01X1084366Y404250D02*
X1082966D01*
G01X1080266D02*
X1078866D01*
G01X1076166D02*
X1053650D01*
G01X1084844Y405400D02*
X1053173D01*
G01X1084844D02*
X1053173D01*
G01X1084366Y404250D02*
X1082966D01*
G01X1084844Y405400D02*
X1053173D01*
G01X1080266Y404250D02*
X1078866D01*
G01X1084844Y405400D02*
X1053173D01*
G01X1076166Y404250D02*
X1053650D01*
G01X1098695Y409600D02*
X1090972D01*
G01X1088322D02*
X1086972D01*
G01X1084322D02*
X1051312D01*
G01X1099172Y410750D02*
X1050835D01*
G01X1051312Y409600D02*
X1046207Y404495D01*
G01X1050835Y410750D02*
X1045730Y405645D01*
G01X1099172Y410750D02*
X1050835D01*
G01X1098695Y409600D02*
X1090972D01*
G01X1099172Y410750D02*
X1050835D01*
G01X1088322Y409600D02*
X1086972D01*
G01X1099172Y410750D02*
X1050835D01*
G01X1084322Y409600D02*
X1051312D01*
G01X1050835Y410750D02*
X1045730Y405645D01*
G01X1051312Y409600D02*
X1046207Y404495D01*
G01X1101356Y412789D02*
X1048217D01*
G01X1101833Y413939D02*
X1047740D01*
G01X1048217Y412789D02*
X1043851Y408423D01*
G01X1047740Y413939D02*
X1043374Y409573D01*
G01X1101833Y413939D02*
X1047740D01*
G01X1101356Y412789D02*
X1048217D01*
G01X1047740Y413939D02*
X1043374Y409573D01*
G01X1048217Y412789D02*
X1043851Y408423D01*
G01X1052394Y468825D02*
X1094534Y464779D01*
G01D02*
X1151567Y471393D01*
G01X1052453Y471342D02*
X1094505Y467304D01*
G01X1052426Y470189D02*
X1094516Y466147D01*
G01X1094505Y467304D02*
X1122947Y470603D01*
G01X1094516Y466147D02*
X1146163Y472136D01*
G01X1052394Y468825D02*
X1094534Y464779D01*
G01D02*
X1151567Y471393D01*
G01X1052426Y470189D02*
X1094516Y466147D01*
G01X1052453Y471342D02*
X1094505Y467304D01*
G01X1094516Y466147D02*
X1146163Y472136D01*
G01X1094505Y467304D02*
X1122947Y470603D01*
G01X1094516Y466147D02*
X1146163Y472136D01*
G01X1041209Y498663D02*
X1080496Y493180D01*
G01X1041289Y499813D02*
X1080576Y494330D01*
G01X1080496Y493180D02*
X1085067D01*
G01X1080576Y494330D02*
X1084895D01*
G01X1085067Y493180D02*
X1131216Y507300D01*
G01X1084895Y494330D02*
X1131044Y508450D01*
G01X1041289Y499813D02*
X1080576Y494330D01*
G01X1041209Y498663D02*
X1080496Y493180D01*
G01X1080576Y494330D02*
X1084895D01*
G01X1080496Y493180D02*
X1085067D01*
G01X1084895Y494330D02*
X1131044Y508450D01*
G01X1085067Y493180D02*
X1131216Y507300D01*
G01X1109045Y-47400D02*
G02Y-49950I0J-1275D01*
G01Y-46250D02*
G02Y-51100I0J-2425D01*
G01Y-46250D02*
G02Y-51100I0J-2425D01*
G01Y-47400D02*
G02Y-49950I0J-1275D01*
G01X1110860Y145007D02*
X1142901Y139415D01*
G01X1110681Y146144D02*
X1110870Y146173D01*
G01X1110860Y145007D02*
X1142901Y139415D01*
G01X1110870Y146173D02*
X1142885Y140586D01*
G01X1142901Y139415D02*
X1158577Y142600D01*
G01X1142885Y140586D02*
X1158125Y143682D01*
G01X1110930Y143466D02*
X1112418Y143236D01*
G01X1110931Y142302D02*
X1112226Y142101D01*
G01X1112418Y143236D02*
X1142010Y137747D01*
G01X1112226Y142101D02*
X1142018Y136575D01*
G01X1142010Y137747D02*
X1158914Y141122D01*
G01X1142018Y136575D02*
X1159364Y140039D01*
G01X1110681Y146144D02*
X1110870Y146173D01*
G01X1110681Y146144D02*
X1110870Y146173D01*
G01D02*
X1142885Y140586D01*
G01X1110860Y145007D02*
X1142901Y139415D01*
G01X1142885Y140586D02*
X1158125Y143682D01*
G01X1142901Y139415D02*
X1158577Y142600D01*
G01X1110931Y142302D02*
X1112226Y142101D01*
G01X1110930Y143466D02*
X1112418Y143236D01*
G01X1112226Y142101D02*
X1142018Y136575D01*
G01X1112418Y143236D02*
X1142010Y137747D01*
G01X1142018Y136575D02*
X1159364Y140039D01*
G01X1142010Y137747D02*
X1158914Y141122D01*
G01X1158813Y156598D02*
X1154236Y153597D01*
G01X1159640Y155765D02*
X1154662Y152501D01*
G01X1154236Y153597D02*
X1141585Y151544D01*
G01X1154662Y152501D02*
X1141578Y150377D01*
G01X1141585Y151544D02*
X1111329Y156824D01*
G01X1141578Y150377D02*
X1111315Y155659D01*
G01X1161466Y155239D02*
X1155226Y151058D01*
G01X1162297Y154410D02*
X1155666Y149968D01*
G01X1155226Y151058D02*
X1142369Y148752D01*
G01X1155666Y149968D02*
X1142371Y147584D01*
G01X1142369Y148752D02*
X1111506Y154176D01*
G01X1142371Y147584D02*
X1111493Y153010D01*
G01X1165403Y153457D02*
X1156553Y147533D01*
G01X1164572Y154286D02*
X1156112Y148622D01*
G01X1156553Y147533D02*
X1141945Y144881D01*
G01X1156112Y148622D02*
X1141941Y146050D01*
G01X1141945Y144881D02*
X1110822Y150313D01*
G01X1141941Y146050D02*
X1110833Y151479D01*
G01X1166520Y152501D02*
X1156835Y146011D01*
G01D02*
X1142436Y143365D01*
G01X1157278Y144922D02*
X1142442Y142196D01*
G01X1142436Y143365D02*
X1110571Y148867D01*
G01X1142442Y142196D02*
X1110562Y147701D01*
G01X1159640Y155765D02*
X1154662Y152501D01*
G01X1158813Y156598D02*
X1154236Y153597D01*
G01X1154662Y152501D02*
X1141578Y150377D01*
G01X1154236Y153597D02*
X1141585Y151544D01*
G01X1141578Y150377D02*
X1111315Y155659D01*
G01X1141585Y151544D02*
X1111329Y156824D01*
G01X1162297Y154410D02*
X1155666Y149968D01*
G01X1161466Y155239D02*
X1155226Y151058D01*
G01X1155666Y149968D02*
X1142371Y147584D01*
G01X1155226Y151058D02*
X1142369Y148752D01*
G01X1142371Y147584D02*
X1111493Y153010D01*
G01X1142369Y148752D02*
X1111506Y154176D01*
G01X1164572Y154286D02*
X1156112Y148622D01*
G01X1165403Y153457D02*
X1156553Y147533D01*
G01X1156112Y148622D02*
X1141941Y146050D01*
G01X1156553Y147533D02*
X1141945Y144881D01*
G01X1141941Y146050D02*
X1110833Y151479D01*
G01X1141945Y144881D02*
X1110822Y150313D01*
G01X1166520Y152501D02*
X1156835Y146011D01*
G01X1157278Y144922D02*
X1142442Y142196D01*
G01X1156835Y146011D02*
X1142436Y143365D01*
G01X1142442Y142196D02*
X1110562Y147701D01*
G01X1142436Y143365D02*
X1110571Y148867D01*
G01X1163741Y201522D02*
X1155080Y189485D01*
G01X1162591Y201893D02*
X1154254Y190308D01*
G01X1155080Y189485D02*
X1146172Y183027D01*
G01X1154254Y190308D02*
X1145641Y184064D01*
G01X1146172Y183027D02*
X1134819Y179280D01*
G01X1145641Y184064D02*
X1134819Y180492D01*
G01X1146172Y183027D02*
X1134819Y179280D01*
G01D02*
X1134224Y179084D01*
G01X1134819Y180492D02*
X1133896Y180187D01*
G01X1134224Y179084D02*
X1129319Y177778D01*
G01X1133896Y180187D02*
X1129036Y178893D01*
G01X1166574Y198666D02*
X1156867Y186686D01*
G01X1165424Y199074D02*
X1156081Y187543D01*
G01X1156867Y186686D02*
X1148056Y180721D01*
G01X1156081Y187543D02*
X1147540Y181762D01*
G01X1148056Y180721D02*
X1139178Y177733D01*
G01X1147540Y181762D02*
X1138844Y178834D01*
G01X1139178Y177733D02*
X1134819Y176556D01*
G01D02*
X1134687Y176520D01*
G01X1138844Y178834D02*
X1134400Y177634D01*
G01X1134819Y176556D02*
X1134687Y176520D01*
G01X1148098Y178895D02*
X1158909Y185631D01*
G01X1159630Y184724D02*
X1148594Y177849D01*
G01X1143045Y177171D02*
X1148098Y178895D01*
G01X1148594Y177849D02*
X1143369Y176066D01*
G01X1163696Y183386D02*
X1149591Y175227D01*
G01X1162932Y184273D02*
X1149115Y176281D01*
G01X1149591Y175227D02*
X1145758Y173937D01*
G01X1149115Y176281D02*
X1145436Y175043D01*
G01X1146434Y207769D02*
Y198315D01*
G01X1145284Y207769D02*
Y206879D01*
G01X1146434Y207769D02*
Y198315D01*
G01X1145284Y204589D02*
Y203699D01*
G01X1146434Y207769D02*
Y198315D01*
G01X1145284Y201409D02*
Y198916D01*
G01X1146434Y198315D02*
X1139076Y193196D01*
G01X1145284Y198916D02*
X1138520Y194211D01*
G01X1139076Y193196D02*
X1125484Y187528D01*
G01X1138520Y194211D02*
X1125129Y188626D01*
G01X1151475Y208465D02*
Y206645D01*
G01X1152625Y208465D02*
Y206442D01*
G01X1151475Y206645D02*
X1151014Y205377D01*
G01X1150141Y202980D02*
X1149680Y201712D01*
G01X1148806Y199312D02*
X1148094Y197354D01*
G01X1152625Y206442D02*
X1149048Y196608D01*
G01X1148084Y197326D02*
X1139641Y191051D01*
G01X1149048Y196608D02*
X1140327Y190128D01*
G01X1139641Y191051D02*
X1126897Y186471D01*
G01X1140030Y189967D02*
X1127226Y185367D01*
G01X1156035Y209371D02*
Y201509D01*
G01X1154885Y209371D02*
Y205785D01*
G01X1156035Y209371D02*
Y201509D01*
G01X1154885Y203235D02*
Y201885D01*
G01X1156035Y201509D02*
X1151438Y195210D01*
G01X1154885Y201885D02*
X1154090Y200795D01*
G01X1156035Y201509D02*
X1151438Y195210D01*
G01X1152586Y198734D02*
X1150528Y195914D01*
G01X1151438Y195210D02*
X1150110Y193589D01*
G01X1150528Y195914D02*
X1149293Y194408D01*
G01X1150110Y193589D02*
X1143118Y187893D01*
G01X1149293Y194408D02*
X1147967Y193328D01*
G01X1150110Y193589D02*
X1143118Y187893D01*
G01X1147967Y193328D02*
X1147123Y193414D01*
G01X1150110Y193589D02*
X1143118Y187893D01*
G01X1145989Y191716D02*
X1142556Y188919D01*
G01X1143118Y187893D02*
X1127491Y182737D01*
G01X1142556Y188919D02*
X1127177Y183845D01*
G01X1159429Y200854D02*
X1153510Y192953D01*
G01X1158279Y201237D02*
X1152599Y193657D01*
G01X1153510Y192953D02*
X1151966Y191016D01*
G01X1152599Y193657D02*
X1151159Y191849D01*
G01X1151966Y191016D02*
X1144191Y185218D01*
G01X1151159Y191849D02*
X1143653Y186252D01*
G01X1144191Y185218D02*
X1134819Y182123D01*
G01D02*
X1134339Y181964D01*
G01X1143653Y186252D02*
X1134014Y183068D01*
G01X1134339Y181964D02*
X1118356Y177813D01*
G01X1134014Y183068D02*
X1118077Y178929D01*
G01X1162591Y201893D02*
X1154254Y190308D01*
G01X1163741Y201522D02*
X1155080Y189485D01*
G01X1154254Y190308D02*
X1145641Y184064D01*
G01X1155080Y189485D02*
X1146172Y183027D01*
G01X1145641Y184064D02*
X1134819Y180492D01*
G01D02*
X1133896Y180187D01*
G01X1146172Y183027D02*
X1134819Y179280D01*
G01Y180492D02*
X1133896Y180187D01*
G01X1134819Y179280D02*
X1134224Y179084D01*
G01X1133896Y180187D02*
X1129036Y178893D01*
G01X1134224Y179084D02*
X1129319Y177778D01*
G01X1165424Y199074D02*
X1156081Y187543D01*
G01X1166574Y198666D02*
X1156867Y186686D01*
G01X1156081Y187543D02*
X1147540Y181762D01*
G01X1156867Y186686D02*
X1148056Y180721D01*
G01X1147540Y181762D02*
X1138844Y178834D01*
G01X1148056Y180721D02*
X1139178Y177733D01*
G01X1138844Y178834D02*
X1134400Y177634D01*
G01X1139178Y177733D02*
X1134819Y176556D01*
G01X1138844Y178834D02*
X1134400Y177634D01*
G01X1134819Y176556D02*
X1134687Y176520D01*
G01X1148594Y177849D02*
X1143369Y176066D01*
G01X1143045Y177171D02*
X1148098Y178895D01*
G01X1159630Y184724D02*
X1148594Y177849D01*
G01X1148098Y178895D02*
X1158909Y185631D01*
G01X1162932Y184273D02*
X1149115Y176281D01*
G01X1163696Y183386D02*
X1149591Y175227D01*
G01X1149115Y176281D02*
X1145436Y175043D01*
G01X1149591Y175227D02*
X1145758Y173937D01*
G01X1141652Y207282D02*
Y200249D01*
G01X1142802Y207210D02*
Y199687D01*
G01X1141652Y200249D02*
X1136799Y196469D01*
G01X1142802Y199687D02*
X1137383Y195466D01*
G01X1136799Y196469D02*
X1123690Y191050D01*
G01X1137383Y195466D02*
X1124045Y189952D01*
G01X1145284Y207769D02*
Y206879D01*
G01Y204589D02*
Y203699D01*
G01Y201409D02*
Y198916D01*
G01X1146434Y207769D02*
Y198315D01*
G01X1145284Y198916D02*
X1138520Y194211D01*
G01X1146434Y198315D02*
X1139076Y193196D01*
G01X1138520Y194211D02*
X1125129Y188626D01*
G01X1139076Y193196D02*
X1125484Y187528D01*
G01X1152625Y208465D02*
Y206442D01*
G01X1151475Y208465D02*
Y206645D01*
G01X1152625Y206442D02*
X1149048Y196608D01*
G01X1151475Y206645D02*
X1151014Y205377D01*
G01X1152625Y206442D02*
X1149048Y196608D01*
G01X1150141Y202980D02*
X1149680Y201712D01*
G01X1152625Y206442D02*
X1149048Y196608D01*
G01X1148806Y199312D02*
X1148094Y197354D01*
G01X1149048Y196608D02*
X1140327Y190128D01*
G01X1148084Y197326D02*
X1139641Y191051D01*
G01X1140030Y189967D02*
X1127226Y185367D01*
G01X1139641Y191051D02*
X1126897Y186471D01*
G01X1154885Y209371D02*
Y205785D01*
G01Y203235D02*
Y201885D01*
G01X1156035Y209371D02*
Y201509D01*
G01X1154885Y201885D02*
X1154090Y200795D01*
G01X1152586Y198734D02*
X1150528Y195914D01*
G01X1156035Y201509D02*
X1151438Y195210D01*
G01X1150528Y195914D02*
X1149293Y194408D01*
G01X1151438Y195210D02*
X1150110Y193589D01*
G01X1149293Y194408D02*
X1147967Y193328D01*
G01D02*
X1147123Y193414D01*
G01X1145989Y191716D02*
X1142556Y188919D01*
G01X1150110Y193589D02*
X1143118Y187893D01*
G01X1142556Y188919D02*
X1127177Y183845D01*
G01X1143118Y187893D02*
X1127491Y182737D01*
G01X1158279Y201237D02*
X1152599Y193657D01*
G01X1159429Y200854D02*
X1153510Y192953D01*
G01X1152599Y193657D02*
X1151159Y191849D01*
G01X1153510Y192953D02*
X1151966Y191016D01*
G01X1151159Y191849D02*
X1143653Y186252D01*
G01X1151966Y191016D02*
X1144191Y185218D01*
G01X1143653Y186252D02*
X1134014Y183068D01*
G01X1144191Y185218D02*
X1134819Y182123D01*
G01X1143653Y186252D02*
X1134014Y183068D01*
G01X1134819Y182123D02*
X1134339Y181964D01*
G01X1134014Y183068D02*
X1118077Y178929D01*
G01X1134339Y181964D02*
X1118356Y177813D01*
G01X1123459Y208982D02*
X1107509D01*
G01X1123459Y210132D02*
X1107032D01*
G01X1107509Y208982D02*
X1096250Y197723D01*
G01X1107032Y210132D02*
X1095660Y198761D01*
G01X1123706Y205476D02*
X1119461D01*
G01X1123706Y206626D02*
X1118984D01*
G01X1119461Y205476D02*
X1116385Y202400D01*
G01X1118984Y206626D02*
X1115908Y203550D01*
G01X1116385Y202400D02*
X1106431D01*
G01X1115908Y203550D02*
X1106008D01*
G01X1106431Y202400D02*
X1098522Y195680D01*
G01X1106008Y203550D02*
X1097978Y196727D01*
G01X1123463Y202700D02*
X1120524D01*
G01D02*
X1119838Y202097D01*
G01X1123463Y201550D02*
X1120958D01*
G01X1120524Y202700D02*
X1119838Y202097D01*
G01D02*
X1116611Y199391D01*
G01X1120958Y201550D02*
X1120587Y201224D01*
G01X1120524Y202700D02*
X1119838Y202097D01*
G01D02*
X1116611Y199391D01*
G01D02*
X1116047Y199441D01*
G01X1120587Y201224D02*
X1115701Y197127D01*
G01X1114962Y198009D02*
X1113574Y196845D01*
G01X1115701Y197127D02*
X1115700D01*
G01X1114962Y198009D02*
X1113574Y196845D01*
G01X1115700Y197127D02*
X1114108Y195791D01*
G01X1135776Y205925D02*
Y204258D01*
G01X1136926Y205925D02*
Y203748D01*
G01X1135776Y204258D02*
X1134819Y203390D01*
G01D02*
X1134479Y203081D01*
G01D02*
X1133871Y203111D01*
G01X1136926Y203748D02*
X1134899Y201908D01*
G01X1132768Y201530D02*
X1131879Y200724D01*
G01X1134819Y201836D02*
X1132532Y199763D01*
G01X1131879Y200724D02*
X1129545Y199577D01*
G01X1127483Y198563D02*
X1122792Y196257D01*
G01D02*
X1122791D01*
G01X1132532Y199763D02*
X1123184Y195168D01*
G01X1122792Y196257D02*
X1122791D01*
G01X1139989Y203223D02*
Y201180D01*
G01X1138839Y203223D02*
Y201773D01*
G01X1139989Y201180D02*
X1134687Y197397D01*
G01X1138839Y201773D02*
X1137929Y201123D01*
G01X1139989Y201180D02*
X1134687Y197397D01*
G01X1137929Y201123D02*
X1137928D01*
G01X1139989Y201180D02*
X1134687Y197397D01*
G01X1137928Y201123D02*
X1137025Y201274D01*
G01X1139989Y201180D02*
X1134687Y197397D01*
G01X1136071Y199798D02*
X1134819Y198905D01*
G01X1139989Y201180D02*
X1134687Y197397D01*
G01X1134819Y198905D02*
X1134117Y198404D01*
G01X1134687Y197397D02*
X1124299Y192867D01*
G01X1134117Y198404D02*
X1123932Y193962D01*
G01X1142802Y207210D02*
Y199687D01*
G01X1141652Y207282D02*
Y200249D01*
G01X1142802Y199687D02*
X1137383Y195466D01*
G01X1141652Y200249D02*
X1136799Y196469D01*
G01X1137383Y195466D02*
X1124045Y189952D01*
G01X1136799Y196469D02*
X1123690Y191050D01*
G01X1123459Y210132D02*
X1107032D01*
G01X1123459Y208982D02*
X1107509D01*
G01X1107032Y210132D02*
X1095660Y198761D01*
G01X1107509Y208982D02*
X1096250Y197723D01*
G01X1123706Y206626D02*
X1118984D01*
G01X1123706Y205476D02*
X1119461D01*
G01X1118984Y206626D02*
X1115908Y203550D01*
G01X1119461Y205476D02*
X1116385Y202400D01*
G01X1115908Y203550D02*
X1106008D01*
G01X1116385Y202400D02*
X1106431D01*
G01X1106008Y203550D02*
X1097978Y196727D01*
G01X1106431Y202400D02*
X1098522Y195680D01*
G01X1123463Y201550D02*
X1120958D01*
G01X1123463Y202700D02*
X1120524D01*
G01X1123463Y201550D02*
X1120958D01*
G01D02*
X1120587Y201224D01*
G01D02*
X1115701Y197127D01*
G01X1120524Y202700D02*
X1119838Y202097D01*
G01X1120958Y201550D02*
X1120587Y201224D01*
G01D02*
X1115701Y197127D01*
G01X1119838Y202097D02*
X1116611Y199391D01*
G01X1120587Y201224D02*
X1115701Y197127D01*
G01X1116611Y199391D02*
X1116047Y199441D01*
G01X1115701Y197127D02*
X1115700D01*
G01D02*
X1114108Y195791D01*
G01X1114962Y198009D02*
X1113574Y196845D01*
G01X1136926Y205925D02*
Y203748D01*
G01X1135776Y205925D02*
Y204258D01*
G01X1136926Y203748D02*
X1134899Y201908D01*
G01X1135776Y204258D02*
X1134819Y203390D01*
G01X1136926Y203748D02*
X1134899Y201908D01*
G01X1134819Y203390D02*
X1134479Y203081D01*
G01X1136926Y203748D02*
X1134899Y201908D01*
G01X1134479Y203081D02*
X1133871Y203111D01*
G01X1134819Y201836D02*
X1132532Y199763D01*
G01X1132768Y201530D02*
X1131879Y200724D01*
G01X1132532Y199763D02*
X1123184Y195168D01*
G01X1131879Y200724D02*
X1129545Y199577D01*
G01X1132532Y199763D02*
X1123184Y195168D01*
G01X1127483Y198563D02*
X1122792Y196257D01*
G01X1132532Y199763D02*
X1123184Y195168D01*
G01X1122792Y196257D02*
X1122791D01*
G01X1138839Y203223D02*
Y201773D01*
G01X1139989Y203223D02*
Y201180D01*
G01X1138839Y201773D02*
X1137929Y201123D01*
G01D02*
X1137928D01*
G01D02*
X1137025Y201274D01*
G01X1136071Y199798D02*
X1134819Y198905D01*
G01D02*
X1134117Y198404D01*
G01X1139989Y201180D02*
X1134687Y197397D01*
G01X1134117Y198404D02*
X1123932Y193962D01*
G01X1134687Y197397D02*
X1124299Y192867D01*
G01X1107050Y419573D02*
X1140315Y405759D01*
G01D02*
X1141900Y405101D01*
G01X1107215Y420750D02*
X1142179Y406231D01*
G01X1140315Y405759D02*
X1141900Y405101D01*
G01D02*
X1142075Y405085D01*
G01X1142076Y405086D02*
X1152147Y404171D01*
G01X1142179Y406233D02*
X1142180D01*
G01X1141900Y405101D02*
X1142075Y405085D01*
G01X1142076Y405086D02*
X1152147Y404171D01*
G01X1142180Y406232D02*
X1146163Y405870D01*
G01X1142076Y405086D02*
X1152147Y404171D01*
G01X1146163Y405870D02*
X1152054Y405335D01*
G01X1152147Y404171D02*
X1192585Y414495D01*
G01X1152054Y405335D02*
X1192570Y415679D01*
G01X1150540Y452419D02*
X1146163Y451912D01*
G01X1214612Y437828D02*
X1150540Y452419D01*
G01X1150603Y453585D02*
X1215167Y438882D01*
G01X1150677Y454963D02*
X1215818Y440127D01*
G01X1216373Y441181D02*
X1150740Y456129D01*
G01X1146163Y454440D02*
X1150677Y454963D01*
G01X1150740Y456129D02*
X1146163Y455598D01*
G01Y464552D02*
X1151229Y465139D01*
G01D02*
X1220867Y449274D01*
G01X1107574Y423318D02*
X1142793Y408696D01*
G01X1107409Y422141D02*
X1142514Y407566D01*
G01X1142793Y408696D02*
X1146163Y408391D01*
G01X1142514Y407566D02*
X1146163Y407235D01*
G01Y408391D02*
X1151850Y407875D01*
G01X1146163Y407235D02*
X1151943Y406711D01*
G01X1151850Y407875D02*
X1192581Y418279D01*
G01X1151943Y406711D02*
X1192597Y417095D01*
G01X1110430Y443872D02*
X1146163Y429040D01*
G01X1110265Y442695D02*
X1146163Y427795D01*
G01Y429040D02*
X1147665Y428417D01*
G01X1146163Y427795D02*
X1147387Y427287D01*
G01X1147665Y428417D02*
X1150015Y428205D01*
G01X1147387Y427287D02*
X1150108Y427041D01*
G01X1150015Y428205D02*
X1192200Y438962D01*
G01X1150108Y427041D02*
X1192215Y437779D01*
G01X1107215Y420750D02*
X1142179Y406231D01*
G01X1107050Y419573D02*
X1140315Y405759D01*
G01X1107215Y420750D02*
X1142179Y406231D01*
G01Y406233D02*
X1142180D01*
G01X1140315Y405759D02*
X1141900Y405101D01*
G01X1142179Y406233D02*
X1142180D01*
G01Y406232D02*
X1146163Y405870D01*
G01X1141900Y405101D02*
X1142075Y405085D01*
G01X1142179Y406233D02*
X1142180D01*
G01Y406232D02*
X1146163Y405870D01*
G01D02*
X1152054Y405335D01*
G01X1142076Y405086D02*
X1152147Y404171D01*
G01X1152054Y405335D02*
X1192570Y415679D01*
G01X1152147Y404171D02*
X1192585Y414495D01*
G01X1121818Y446562D02*
X1150387Y449873D01*
G01D02*
X1213074Y435610D01*
G01X1150450Y451039D02*
X1213629Y436664D01*
G01X1150603Y453585D02*
X1215167Y438882D01*
G01X1214612Y437828D02*
X1150540Y452419D01*
G01D02*
X1146163Y451912D01*
G01X1150740Y456129D02*
X1146163Y455598D01*
G01Y454440D02*
X1150677Y454963D01*
G01X1216373Y441181D02*
X1150740Y456129D01*
G01X1150677Y454963D02*
X1215818Y440127D01*
G01X1146163Y464552D02*
X1151229Y465139D01*
G01D02*
X1220867Y449274D01*
G01X1107409Y422141D02*
X1142514Y407566D01*
G01X1107574Y423318D02*
X1142793Y408696D01*
G01X1142514Y407566D02*
X1146163Y407235D01*
G01X1142793Y408696D02*
X1146163Y408391D01*
G01Y407235D02*
X1151943Y406711D01*
G01X1146163Y408391D02*
X1151850Y407875D01*
G01X1151943Y406711D02*
X1192597Y417095D01*
G01X1151850Y407875D02*
X1192581Y418279D01*
G01X1108835Y432418D02*
X1144947Y417427D01*
G01X1109000Y433595D02*
X1145226Y418557D01*
G01X1108835Y432418D02*
X1144947Y417427D01*
G01D02*
X1151134Y416866D01*
G01X1145226Y418557D02*
X1146163Y418472D01*
G01X1144947Y417427D02*
X1151134Y416866D01*
G01X1146163Y418472D02*
X1151041Y418030D01*
G01X1151134Y416866D02*
X1192472Y427422D01*
G01X1151041Y418030D02*
X1192457Y428606D01*
G01X1110265Y442695D02*
X1146163Y427795D01*
G01X1110430Y443872D02*
X1146163Y429040D01*
G01Y427795D02*
X1147387Y427287D01*
G01X1146163Y429040D02*
X1147665Y428417D01*
G01X1147387Y427287D02*
X1150108Y427041D01*
G01X1147665Y428417D02*
X1150015Y428205D01*
G01X1150108Y427041D02*
X1192215Y437779D01*
G01X1150015Y428205D02*
X1192200Y438962D01*
G01X1146163Y456968D02*
X1150815Y457507D01*
G01X1146163Y458126D02*
X1150878Y458673D01*
G01X1150815Y457507D02*
X1217034Y442425D01*
G01X1150878Y458673D02*
X1217589Y443479D01*
G01X1121818Y446562D02*
X1150387Y449873D01*
G01X1150450Y451039D02*
X1213629Y436664D01*
G01X1150387Y449873D02*
X1213074Y435610D01*
G01X1107766Y424711D02*
X1143123Y410031D01*
G01X1107931Y425888D02*
X1143402Y411161D01*
G01X1143123Y410031D02*
X1151741Y409250D01*
G01X1143402Y411161D02*
X1151648Y410414D01*
G01X1151741Y409250D02*
X1192568Y419676D01*
G01X1151648Y410414D02*
X1192553Y420860D01*
G01X1108290Y428457D02*
X1144010Y413627D01*
G01X1108125Y427280D02*
X1143731Y412497D01*
G01X1144010Y413627D02*
X1151446Y412953D01*
G01X1143731Y412497D02*
X1151539Y411789D01*
G01X1151446Y412953D02*
X1192517Y423442D01*
G01X1151539Y411789D02*
X1192533Y422258D01*
G01X1108481Y429849D02*
X1144331Y414962D01*
G01X1108646Y431026D02*
X1128523Y422772D01*
G01X1108481Y429849D02*
X1144331Y414962D01*
G01X1128523Y422773D02*
X1144610Y416092D01*
G01X1144331Y414962D02*
X1146163Y414796D01*
G01X1144610Y416092D02*
X1146163Y415951D01*
G01Y414796D02*
X1147822Y414646D01*
G01D02*
X1151336Y414327D01*
G01X1146163Y415951D02*
X1151243Y415491D01*
G01X1151336Y414327D02*
X1192502Y424839D01*
G01X1151243Y415491D02*
X1192486Y426023D01*
G01X1109000Y433595D02*
X1145226Y418557D01*
G01D02*
X1146163Y418472D01*
G01X1108835Y432418D02*
X1144947Y417427D01*
G01X1145226Y418557D02*
X1146163Y418472D01*
G01D02*
X1151041Y418030D01*
G01X1144947Y417427D02*
X1151134Y416866D01*
G01X1151041Y418030D02*
X1192457Y428606D01*
G01X1151134Y416866D02*
X1192472Y427422D01*
G01X1109196Y434987D02*
X1145553Y419893D01*
G01X1109361Y436164D02*
X1145832Y421023D01*
G01X1109196Y434987D02*
X1145553Y419893D01*
G01D02*
X1150931Y419405D01*
G01X1145832Y421023D02*
X1146163Y420993D01*
G01X1145553Y419893D02*
X1150931Y419405D01*
G01X1146163Y420993D02*
X1150838Y420569D01*
G01X1150931Y419405D02*
X1192437Y430003D01*
G01X1150838Y420569D02*
X1192421Y431187D01*
G01X1109706Y438732D02*
X1146163Y423606D01*
G01D02*
X1146449Y423487D01*
G01X1109541Y437555D02*
X1146163Y422360D01*
G01X1146449Y423487D02*
X1150636Y423107D01*
G01X1146170Y422357D02*
X1150729Y421943D01*
G01X1150636Y423107D02*
X1192386Y433771D01*
G01X1150729Y421943D02*
X1192401Y432587D01*
G01X1109904Y440125D02*
X1146163Y425076D01*
G01X1110069Y441302D02*
X1146163Y426322D01*
G01X1109904Y440125D02*
X1146163Y425076D01*
G01D02*
X1146776Y424822D01*
G01X1146163Y426322D02*
X1147055Y425952D01*
G01X1146163Y425076D02*
X1146776Y424822D01*
G01D02*
X1150526Y424482D01*
G01X1147055Y425952D02*
X1150433Y425646D01*
G01X1150526Y424482D02*
X1192370Y435168D01*
G01X1150433Y425646D02*
X1192347Y436350D01*
G01X1146163Y458126D02*
X1150878Y458673D01*
G01X1146163Y456968D02*
X1150815Y457507D01*
G01X1150878Y458673D02*
X1217589Y443479D01*
G01X1150815Y457507D02*
X1217034Y442425D01*
G01X1107931Y425888D02*
X1143402Y411161D01*
G01X1107766Y424711D02*
X1143123Y410031D01*
G01X1143402Y411161D02*
X1151648Y410414D01*
G01X1143123Y410031D02*
X1151741Y409250D01*
G01X1151648Y410414D02*
X1192553Y420860D01*
G01X1151741Y409250D02*
X1192568Y419676D01*
G01X1108125Y427280D02*
X1143731Y412497D01*
G01X1108290Y428457D02*
X1144010Y413627D01*
G01X1143731Y412497D02*
X1151539Y411789D01*
G01X1144010Y413627D02*
X1151446Y412953D01*
G01X1151539Y411789D02*
X1192533Y422258D01*
G01X1151446Y412953D02*
X1192517Y423442D01*
G01X1108646Y431026D02*
X1128523Y422772D01*
G01Y422773D02*
X1144610Y416092D01*
G01X1108481Y429849D02*
X1144331Y414962D01*
G01X1144610Y416092D02*
X1146163Y415951D01*
G01X1144331Y414962D02*
X1146163Y414796D01*
G01Y415951D02*
X1151243Y415491D01*
G01X1146163Y414796D02*
X1147822Y414646D01*
G01X1146163Y415951D02*
X1151243Y415491D01*
G01X1147822Y414646D02*
X1151336Y414327D01*
G01X1151243Y415491D02*
X1192486Y426023D01*
G01X1151336Y414327D02*
X1192502Y424839D01*
G01X1109361Y436164D02*
X1145832Y421023D01*
G01D02*
X1146163Y420993D01*
G01X1109196Y434987D02*
X1145553Y419893D01*
G01X1145832Y421023D02*
X1146163Y420993D01*
G01D02*
X1150838Y420569D01*
G01X1145553Y419893D02*
X1150931Y419405D01*
G01X1150838Y420569D02*
X1192421Y431187D01*
G01X1150931Y419405D02*
X1192437Y430003D01*
G01X1109541Y437555D02*
X1146163Y422360D01*
G01X1109706Y438732D02*
X1146163Y423606D01*
G01X1109541Y437555D02*
X1146163Y422360D01*
G01Y423606D02*
X1146449Y423487D01*
G01X1146170Y422357D02*
X1150729Y421943D01*
G01X1146449Y423487D02*
X1150636Y423107D01*
G01X1150729Y421943D02*
X1192401Y432587D01*
G01X1150636Y423107D02*
X1192386Y433771D01*
G01X1110069Y441302D02*
X1146163Y426322D01*
G01D02*
X1147055Y425952D01*
G01X1109904Y440125D02*
X1146163Y425076D01*
G01Y426322D02*
X1147055Y425952D01*
G01D02*
X1150433Y425646D01*
G01X1146163Y425076D02*
X1146776Y424822D01*
G01X1147055Y425952D02*
X1150433Y425646D01*
G01X1146776Y424822D02*
X1150526Y424482D01*
G01X1150433Y425646D02*
X1192347Y436350D01*
G01X1150526Y424482D02*
X1192370Y435168D01*
G01X1146163Y459496D02*
X1150953Y460051D01*
G01X1146163Y460654D02*
X1151016Y461217D01*
G01X1150953Y460051D02*
X1218242Y444724D01*
G01X1151016Y461217D02*
X1218797Y445778D01*
G01X1122721Y460465D02*
X1146163Y463184D01*
G01D02*
X1151152Y463763D01*
G01D02*
X1151344Y463720D01*
G01X1146163Y462026D02*
X1151089Y462597D01*
G01X1151152Y463763D02*
X1151344Y463720D01*
G01Y463719D02*
X1220012Y448075D01*
G01X1151089Y462597D02*
X1219457Y447021D01*
G01X1146163Y460654D02*
X1151016Y461217D01*
G01X1146163Y459496D02*
X1150953Y460051D01*
G01X1151016Y461217D02*
X1218797Y445778D01*
G01X1150953Y460051D02*
X1218242Y444724D01*
G01X1122721Y460465D02*
X1146163Y463184D01*
G01Y462026D02*
X1151089Y462597D01*
G01X1146163Y463184D02*
X1151152Y463763D01*
G01X1146163Y462026D02*
X1151089Y462597D01*
G01D02*
X1219457Y447021D01*
G01X1151152Y463763D02*
X1151344Y463720D01*
G01X1151089Y462597D02*
X1219457Y447021D01*
G01X1151344Y463719D02*
X1220012Y448075D01*
G01X1103589Y404705D02*
X1098695Y409600D01*
G01X1104403Y405519D02*
X1099172Y410750D01*
G01X1104403Y405519D02*
X1099172Y410750D01*
G01X1103589Y404705D02*
X1098695Y409600D01*
G01X1117105Y410075D02*
X1116153Y411027D01*
G01D02*
X1114803D01*
G01X1117919Y410888D02*
X1116630Y412177D01*
G01X1116153Y411027D02*
X1114803D01*
G01X1112153D02*
X1103118D01*
G01X1116630Y412177D02*
X1103595D01*
G01X1103118Y411027D02*
X1101356Y412789D01*
G01X1103595Y412177D02*
X1101833Y413939D01*
G01X1117919Y410888D02*
X1116630Y412177D01*
G01X1117105Y410075D02*
X1116153Y411027D01*
G01X1117919Y410888D02*
X1116630Y412177D01*
G01D02*
X1103595D01*
G01X1116153Y411027D02*
X1114803D01*
G01X1116630Y412177D02*
X1103595D01*
G01X1112153Y411027D02*
X1103118D01*
G01X1103595Y412177D02*
X1101833Y413939D01*
G01X1103118Y411027D02*
X1101356Y412789D01*
G01X1146163Y465710D02*
X1151292Y466305D01*
G01D02*
X1221422Y450328D01*
G01X1122836Y465535D02*
X1146163Y468240D01*
G01Y467081D02*
X1151365Y467684D01*
G01X1146163Y468240D02*
X1151428Y468850D01*
G01X1151365Y467684D02*
X1222177Y451551D01*
G01X1151428Y468850D02*
X1222732Y452605D01*
G01X1146163Y465710D02*
X1151292Y466305D01*
G01D02*
X1221422Y450328D01*
G01X1151504Y470227D02*
X1223389Y453849D01*
G01X1151567Y471393D02*
X1223944Y454903D01*
G01X1122947Y470602D02*
X1146163Y473294D01*
G01D02*
X1151706Y473937D01*
G01X1146163Y472136D02*
X1151643Y472771D01*
G01X1151706Y473937D02*
X1225357Y457154D01*
G01X1151643Y472771D02*
X1224802Y456100D01*
G01X1122836Y465535D02*
X1146163Y468240D01*
G01D02*
X1151428Y468850D01*
G01X1146163Y467081D02*
X1151365Y467684D01*
G01X1151428Y468850D02*
X1222732Y452605D01*
G01X1151365Y467684D02*
X1222177Y451551D01*
G01X1151567Y471393D02*
X1223944Y454903D01*
G01X1151504Y470227D02*
X1223389Y453849D01*
G01X1122947Y470602D02*
X1146163Y473294D01*
G01Y472136D02*
X1151643Y472771D01*
G01X1146163Y473294D02*
X1151706Y473937D01*
G01X1151643Y472771D02*
X1224802Y456100D01*
G01X1151706Y473937D02*
X1225357Y457154D01*
G01X1131216Y507300D02*
X1272289D01*
G01X1131044Y508450D02*
X1272766D01*
G01X1131044D02*
X1272766D01*
G01X1131216Y507300D02*
X1272289D01*
G01X1158577Y142600D02*
X1169752Y150111D01*
G01X1158125Y143682D02*
X1168921Y150939D01*
G01X1169752Y150111D02*
X1180902Y166831D01*
G01X1168921Y150939D02*
X1179966Y167501D01*
G01X1158914Y141122D02*
X1170924Y149163D01*
G01X1159364Y140039D02*
X1171755Y148334D01*
G01X1170924Y149163D02*
X1176084Y156899D01*
G01X1171755Y148334D02*
X1176997Y156195D01*
G01D02*
X1198068Y179971D01*
G01X1158125Y143682D02*
X1168921Y150939D01*
G01X1158577Y142600D02*
X1169752Y150111D01*
G01X1168921Y150939D02*
X1179966Y167501D01*
G01X1169752Y150111D02*
X1180902Y166831D01*
G01X1159364Y140039D02*
X1171755Y148334D01*
G01X1158914Y141122D02*
X1170924Y149163D01*
G01X1171755Y148334D02*
X1176997Y156195D01*
G01X1170924Y149163D02*
X1176084Y156899D01*
G01X1176997Y156195D02*
X1198068Y179971D01*
G01X1176997Y156195D02*
X1198068Y179971D01*
G01X1176997Y156195D02*
X1198068Y179971D01*
G01X1176997Y156195D02*
X1198068Y179971D01*
G01X1176997Y156195D02*
X1198068Y179971D01*
G01X1176997Y156195D02*
X1198068Y179971D01*
G01X1176997Y156195D02*
X1198068Y179971D01*
G01X1163780Y161973D02*
X1159640Y155765D01*
G01X1166074Y162153D02*
X1161466Y155239D01*
G01X1169258Y164857D02*
X1162297Y154410D01*
G01X1173443Y165521D02*
X1165403Y153457D01*
G01X1173443Y165521D02*
X1165403Y153457D01*
G01X1170268Y162832D02*
X1164572Y154286D01*
G01X1177236Y168578D02*
X1166520Y152501D01*
G01X1180411Y171268D02*
X1167351Y151672D01*
G01D02*
X1157278Y144922D01*
G01X1163780Y161973D02*
X1159640Y155765D01*
G01X1169258Y164857D02*
X1162297Y154410D01*
G01X1169258Y164857D02*
X1162297Y154410D01*
G01X1166074Y162153D02*
X1161466Y155239D01*
G01X1170268Y162832D02*
X1164572Y154286D01*
G01X1173443Y165521D02*
X1165403Y153457D01*
G01X1180411Y171268D02*
X1167351Y151672D01*
G01X1180411Y171268D02*
X1167351Y151672D01*
G01X1177236Y168578D02*
X1166520Y152501D01*
G01X1167351Y151672D02*
X1157278Y144922D01*
G01X1180902Y166831D02*
X1194574Y184651D01*
G01X1179966Y167501D02*
X1183943Y172685D01*
G01X1180902Y166831D02*
X1194574Y184651D01*
G01X1185497Y174709D02*
X1186318Y175780D01*
G01X1180902Y166831D02*
X1194574Y184651D01*
G01X1187870Y177804D02*
X1188693Y178877D01*
G01X1180902Y166831D02*
X1194574Y184651D01*
G01X1190244Y180899D02*
X1191188Y182129D01*
G01X1180902Y166831D02*
X1194574Y184651D01*
G01X1192741Y184151D02*
X1193562Y185222D01*
G01X1194630Y184794D02*
X1198662Y195100D01*
G01X1193562Y185222D02*
X1194630Y187952D01*
G01Y184794D02*
X1198662Y195100D01*
G01X1194630Y187952D02*
X1194731Y188210D01*
G01X1194630Y184794D02*
X1198662Y195100D01*
G01X1195661Y190586D02*
X1196152Y191843D01*
G01X1194630Y184794D02*
X1198662Y195100D01*
G01X1197082Y194219D02*
X1197573Y195476D01*
G01X1198662Y195100D02*
X1204322Y211437D01*
G01X1197573Y195476D02*
X1198105Y197011D01*
G01X1198662Y195100D02*
X1204322Y211437D01*
G01X1198941Y199422D02*
X1200618Y204262D01*
G01X1198662Y195100D02*
X1204322Y211437D01*
G01X1201454Y206673D02*
X1203172Y211634D01*
G01X1204322Y211437D02*
Y213108D01*
G01X1203172Y211634D02*
Y213108D01*
G01X1176084Y156899D02*
X1181565Y163084D01*
G01X1183257Y164993D02*
X1184152Y166003D01*
G01X1185844Y167912D02*
X1186739Y168922D01*
G01X1188431Y170831D02*
X1189326Y171841D01*
G01X1191018Y173750D02*
X1191913Y174760D01*
G01X1193605Y176669D02*
X1194500Y177679D01*
G01X1196192Y179588D02*
X1197087Y180598D01*
G01D02*
X1198780Y184460D01*
G01X1199805Y186796D02*
X1200347Y188032D01*
G01X1201371Y190368D02*
X1201913Y191604D01*
G01X1202937Y193940D02*
X1203479Y195176D01*
G01X1204504Y197512D02*
X1205046Y198748D01*
G01X1206071Y201084D02*
X1206613Y202320D01*
G01X1207638Y204657D02*
X1208243Y206037D01*
G01X1198068Y179971D02*
X1209453Y205931D01*
G01X1208243Y206037D02*
X1205979Y215352D01*
G01X1209453Y205931D02*
X1207129Y215490D01*
G01X1205979Y215352D02*
Y216837D01*
G01X1207129Y215490D02*
Y216837D01*
G01X1179966Y167501D02*
X1183943Y172685D01*
G01X1185497Y174709D02*
X1186318Y175780D01*
G01X1187870Y177804D02*
X1188693Y178877D01*
G01X1190244Y180899D02*
X1191188Y182129D01*
G01X1192741Y184151D02*
X1193562Y185222D01*
G01X1180902Y166831D02*
X1194574Y184651D01*
G01X1193562Y185222D02*
X1194630Y187952D01*
G01D02*
X1194731Y188210D01*
G01X1195661Y190586D02*
X1196152Y191843D01*
G01X1197082Y194219D02*
X1197573Y195476D01*
G01X1194630Y184794D02*
X1198662Y195100D01*
G01X1197573Y195476D02*
X1198105Y197011D01*
G01X1198941Y199422D02*
X1200618Y204262D01*
G01X1201454Y206673D02*
X1203172Y211634D01*
G01X1198662Y195100D02*
X1204322Y211437D01*
G01X1203172Y211634D02*
Y213108D01*
G01X1204322Y211437D02*
Y213108D01*
G01X1176084Y156899D02*
X1181565Y163084D01*
G01X1183257Y164993D02*
X1184152Y166003D01*
G01X1185844Y167912D02*
X1186739Y168922D01*
G01X1188431Y170831D02*
X1189326Y171841D01*
G01X1191018Y173750D02*
X1191913Y174760D01*
G01X1193605Y176669D02*
X1194500Y177679D01*
G01X1196192Y179588D02*
X1197087Y180598D01*
G01X1198068Y179971D02*
X1209453Y205931D01*
G01X1197087Y180598D02*
X1198780Y184460D01*
G01X1198068Y179971D02*
X1209453Y205931D01*
G01X1199805Y186796D02*
X1200347Y188032D01*
G01X1198068Y179971D02*
X1209453Y205931D01*
G01X1201371Y190368D02*
X1201913Y191604D01*
G01X1198068Y179971D02*
X1209453Y205931D01*
G01X1202937Y193940D02*
X1203479Y195176D01*
G01X1198068Y179971D02*
X1209453Y205931D01*
G01X1204504Y197512D02*
X1205046Y198748D01*
G01X1198068Y179971D02*
X1209453Y205931D01*
G01X1206071Y201084D02*
X1206613Y202320D01*
G01X1198068Y179971D02*
X1209453Y205931D01*
G01X1207638Y204657D02*
X1208243Y206037D01*
G01X1209453Y205931D02*
X1207129Y215490D01*
G01X1208243Y206037D02*
X1205979Y215352D01*
G01X1207129Y215490D02*
Y216837D01*
G01X1205979Y215352D02*
Y216837D01*
G01X1163741Y204736D02*
Y201522D01*
G01X1162591Y204687D02*
Y201893D01*
G01X1166574Y204115D02*
Y198666D01*
G01X1165424Y204115D02*
Y199074D01*
G01X1169025Y198200D02*
Y203464D01*
G01X1170175D02*
Y197793D01*
G01X1159345Y186067D02*
X1169025Y198200D01*
G01X1170175Y197793D02*
X1160258Y185363D01*
G01X1158909Y185631D02*
X1159345Y186067D01*
G01X1160173Y185267D02*
X1159630Y184724D01*
G01X1173299Y201226D02*
Y195447D01*
G01X1172149Y201226D02*
Y195849D01*
G01X1173299Y195447D02*
X1163696Y183386D01*
G01X1172149Y195849D02*
X1162932Y184273D01*
G01X1175784Y199797D02*
Y197670D01*
G01X1176934Y199797D02*
Y197460D01*
G01X1175784Y197670D02*
X1173035Y190251D01*
G01X1172148Y187860D02*
X1171679Y186595D01*
G01X1170792Y184203D02*
X1170323Y182938D01*
G01X1169436Y180546D02*
X1168977Y179311D01*
G01X1176934Y197460D02*
X1170057Y178909D01*
G01X1168080Y176889D02*
X1167611Y175624D01*
G01X1166724Y173231D02*
X1166256Y171966D01*
G01X1165369Y169573D02*
X1164900Y168308D01*
G01X1164014Y165915D02*
X1162748Y162499D01*
G01X1170047Y178879D02*
X1163780Y161973D01*
G01X1162748Y162499D02*
X1158813Y156598D01*
G01X1179844Y196702D02*
Y193808D01*
G01X1180994Y196766D02*
Y193582D01*
G01X1179844Y193808D02*
X1177858Y188948D01*
G01X1176893Y186586D02*
X1176383Y185337D01*
G01X1175417Y182975D02*
X1174907Y181726D01*
G01X1173942Y179364D02*
X1173432Y178115D01*
G01X1172467Y175753D02*
X1171957Y174504D01*
G01X1170991Y172143D02*
X1170481Y170892D01*
G01X1169516Y168531D02*
X1168237Y165399D01*
G01X1180994Y193582D02*
X1169258Y164857D01*
G01X1168237Y165399D02*
X1167489Y164276D01*
G01X1184639Y191921D02*
Y190062D01*
G01X1183489Y191921D02*
Y190314D01*
G01X1184639Y190062D02*
X1173443Y165521D01*
G01X1183489Y190314D02*
X1182929Y189086D01*
G01X1184639Y190062D02*
X1173443Y165521D01*
G01X1181870Y186765D02*
X1181310Y185537D01*
G01X1184639Y190062D02*
X1173443Y165521D01*
G01X1180251Y183216D02*
X1179691Y181988D01*
G01X1184639Y190062D02*
X1173443Y165521D01*
G01X1178632Y179667D02*
X1178072Y178439D01*
G01X1184639Y190062D02*
X1173443Y165521D01*
G01X1177012Y176118D02*
X1176452Y174890D01*
G01X1184639Y190062D02*
X1173443Y165521D01*
G01X1175393Y172569D02*
X1174833Y171341D01*
G01X1184639Y190062D02*
X1173443Y165521D01*
G01X1173773Y169020D02*
X1172431Y166078D01*
G01D02*
X1171683Y164955D01*
G01X1192206Y197614D02*
X1191208Y195957D01*
G01X1193191Y197020D02*
X1192200Y195375D01*
G01X1191208Y195957D02*
X1186999Y188584D01*
G01X1192200Y195375D02*
X1188026Y188063D01*
G01X1186999Y188584D02*
X1186187Y186827D01*
G01X1185132Y184469D02*
X1184585Y183260D01*
G01X1183518Y180930D02*
X1182962Y179700D01*
G01X1181910Y177376D02*
X1181354Y176146D01*
G01X1180302Y173822D02*
X1179399Y171824D01*
G01X1188026Y188063D02*
X1180411Y171268D01*
G01X1179399Y171824D02*
X1178651Y170701D01*
G01X1159429Y206300D02*
Y200854D01*
G01X1158279Y206300D02*
Y201237D01*
G01X1162591Y204687D02*
Y201893D01*
G01X1163741Y204736D02*
Y201522D01*
G01X1165424Y204115D02*
Y199074D01*
G01X1166574Y204115D02*
Y198666D01*
G01X1160173Y185267D02*
X1159630Y184724D01*
G01X1158909Y185631D02*
X1159345Y186067D01*
G01X1170175Y197793D02*
X1160258Y185363D01*
G01X1159345Y186067D02*
X1169025Y198200D01*
G01X1170175Y203464D02*
Y197793D01*
G01X1169025Y198200D02*
Y203464D01*
G01X1172149Y201226D02*
Y195849D01*
G01X1173299Y201226D02*
Y195447D01*
G01X1172149Y195849D02*
X1162932Y184273D01*
G01X1173299Y195447D02*
X1163696Y183386D01*
G01X1176934Y199797D02*
Y197460D01*
G01X1175784Y199797D02*
Y197670D01*
G01X1176934Y197460D02*
X1170057Y178909D01*
G01X1175784Y197670D02*
X1173035Y190251D01*
G01X1176934Y197460D02*
X1170057Y178909D01*
G01X1172148Y187860D02*
X1171679Y186595D01*
G01X1176934Y197460D02*
X1170057Y178909D01*
G01X1170792Y184203D02*
X1170323Y182938D01*
G01X1176934Y197460D02*
X1170057Y178909D01*
G01X1169436Y180546D02*
X1168977Y179311D01*
G01X1170047Y178879D02*
X1163780Y161973D01*
G01X1168080Y176889D02*
X1167611Y175624D01*
G01X1170047Y178879D02*
X1163780Y161973D01*
G01X1166724Y173231D02*
X1166256Y171966D01*
G01X1170047Y178879D02*
X1163780Y161973D01*
G01X1165369Y169573D02*
X1164900Y168308D01*
G01X1170047Y178879D02*
X1163780Y161973D01*
G01X1164014Y165915D02*
X1162748Y162499D01*
G01D02*
X1158813Y156598D01*
G01X1180994Y196766D02*
Y193582D01*
G01X1179844Y196702D02*
Y193808D01*
G01X1180994Y193582D02*
X1169258Y164857D01*
G01X1179844Y193808D02*
X1177858Y188948D01*
G01X1180994Y193582D02*
X1169258Y164857D01*
G01X1176893Y186586D02*
X1176383Y185337D01*
G01X1180994Y193582D02*
X1169258Y164857D01*
G01X1175417Y182975D02*
X1174907Y181726D01*
G01X1180994Y193582D02*
X1169258Y164857D01*
G01X1173942Y179364D02*
X1173432Y178115D01*
G01X1180994Y193582D02*
X1169258Y164857D01*
G01X1172467Y175753D02*
X1171957Y174504D01*
G01X1180994Y193582D02*
X1169258Y164857D01*
G01X1170991Y172143D02*
X1170481Y170892D01*
G01X1180994Y193582D02*
X1169258Y164857D01*
G01X1169516Y168531D02*
X1168237Y165399D01*
G01D02*
X1167489Y164276D01*
G01X1183489Y191921D02*
Y190314D01*
G01X1184639Y191921D02*
Y190062D01*
G01X1183489Y190314D02*
X1182929Y189086D01*
G01X1181870Y186765D02*
X1181310Y185537D01*
G01X1180251Y183216D02*
X1179691Y181988D01*
G01X1178632Y179667D02*
X1178072Y178439D01*
G01X1177012Y176118D02*
X1176452Y174890D01*
G01X1175393Y172569D02*
X1174833Y171341D01*
G01X1173773Y169020D02*
X1172431Y166078D01*
G01X1184639Y190062D02*
X1173443Y165521D01*
G01X1172431Y166078D02*
X1171683Y164955D01*
G01X1193191Y197020D02*
X1192200Y195375D01*
G01X1192206Y197614D02*
X1191208Y195957D01*
G01X1192200Y195375D02*
X1188026Y188063D01*
G01X1191208Y195957D02*
X1186999Y188584D01*
G01X1188026Y188063D02*
X1180411Y171268D01*
G01X1186999Y188584D02*
X1186187Y186827D01*
G01X1188026Y188063D02*
X1180411Y171268D01*
G01X1185132Y184469D02*
X1184585Y183260D01*
G01X1188026Y188063D02*
X1180411Y171268D01*
G01X1183518Y180930D02*
X1182962Y179700D01*
G01X1188026Y188063D02*
X1180411Y171268D01*
G01X1181910Y177376D02*
X1181354Y176146D01*
G01X1188026Y188063D02*
X1180411Y171268D01*
G01X1180302Y173822D02*
X1179399Y171824D01*
G01D02*
X1178651Y170701D01*
G01X1158279Y206300D02*
Y201237D01*
G01X1159429Y206300D02*
Y200854D01*
G01X1226909Y253317D02*
X1216681D01*
G01Y252167D02*
X1227350D01*
G01X1216681D02*
X1227350D01*
G01X1226909Y253317D02*
X1216681D01*
G01X1220413Y282097D02*
X1217074Y278758D01*
G01X1221397Y281453D02*
X1217887Y277943D01*
G01X1226746Y249798D02*
X1215911D01*
G01D02*
X1215460Y249794D01*
G01X1227187Y248648D02*
X1215917D01*
G01X1226746Y249798D02*
X1215911D01*
G01D02*
X1215460Y249794D01*
G01X1215917Y248648D02*
X1215470Y248644D01*
G01X1225280Y231550D02*
X1215525D01*
G01X1225721Y230400D02*
X1216002D01*
G01X1215525Y231550D02*
X1214396Y230421D01*
G01D02*
X1213575D01*
G01X1216002Y230400D02*
X1214873Y229271D01*
G01X1214396Y230421D02*
X1213575D01*
G01X1214873Y229271D02*
X1213574D01*
G01X1225721Y230400D02*
X1216002D01*
G01X1225280Y231550D02*
X1215525D01*
G01X1216002Y230400D02*
X1214873Y229271D01*
G01X1215525Y231550D02*
X1214396Y230421D01*
G01X1216002Y230400D02*
X1214873Y229271D01*
G01D02*
X1213574D01*
G01X1214396Y230421D02*
X1213575D01*
G01X1221397Y281453D02*
X1217887Y277943D01*
G01X1220413Y282097D02*
X1217074Y278758D01*
G01X1227187Y248648D02*
X1215917D01*
G01D02*
X1215470Y248644D01*
G01X1226746Y249798D02*
X1215911D01*
G01X1227187Y248648D02*
X1215917D01*
G01D02*
X1215470Y248644D01*
G01X1215911Y249798D02*
X1215460Y249794D01*
G01X1221555Y241700D02*
X1217226D01*
G01X1221996Y240550D02*
X1216749D01*
G01X1217226Y241700D02*
X1216700Y242226D01*
G01X1216749Y240550D02*
X1215550Y241749D01*
G01X1216700Y242226D02*
Y242706D01*
G01X1215550Y241749D02*
Y242678D01*
G01X1221996Y240550D02*
X1216749D01*
G01X1221555Y241700D02*
X1217226D01*
G01X1216749Y240550D02*
X1215550Y241749D01*
G01X1217226Y241700D02*
X1216700Y242226D01*
G01X1215550Y241749D02*
Y242678D01*
G01X1216700Y242226D02*
Y242706D01*
G01X1222549Y347772D02*
X1216797Y332641D01*
G01X1216134Y330895D02*
X1215813Y330053D01*
G01X1215150Y328307D02*
X1214833Y327477D01*
G01X1214166Y325719D02*
X1213847Y324883D01*
G01X1213182Y323131D02*
X1212941Y322500D01*
G01D02*
X1212862Y322292D01*
G01X1212198Y320543D02*
X1211400Y318443D01*
G01X1223746Y347682D02*
X1211400Y315202D01*
G01Y318443D02*
X1209826Y314300D01*
G01X1211400Y315202D02*
X1211057Y314300D01*
G01X1211400Y318443D02*
X1209826Y314300D01*
G01D02*
X1209635Y313797D01*
G01X1211057Y314300D02*
X1210733Y313448D01*
G01X1209635Y313797D02*
X1208461Y309256D01*
G01X1210733Y313448D02*
X1209611Y309109D01*
G01X1208461Y309254D02*
X1207714Y306369D01*
G01Y306367D02*
X1207640Y306081D01*
G01X1209611Y309107D02*
X1208828Y306081D01*
G01X1207273Y304418D02*
Y303841D01*
G01X1208423Y304292D02*
Y303841D01*
G01X1219788Y328378D02*
X1218505Y325004D01*
G01X1218711Y328789D02*
X1218390Y327945D01*
G01X1219788Y328378D02*
X1218505Y325004D01*
G01X1217743Y326241D02*
X1217428Y325415D01*
G01X1218499Y324986D02*
X1217554Y322500D01*
G01D02*
X1217532Y322442D01*
G01X1217531Y322439D02*
X1216884Y320737D01*
G01X1216775Y323693D02*
X1216455Y322852D01*
G01X1217531Y322439D02*
X1216884Y320737D01*
G01X1216883Y320734D02*
X1213357Y311459D01*
G01X1215806Y321142D02*
X1215486Y320301D01*
G01X1216883Y320734D02*
X1213357Y311459D01*
G01X1214839Y318597D02*
X1214518Y317753D01*
G01X1216883Y320734D02*
X1213357Y311459D01*
G01X1213871Y316049D02*
X1213206Y314300D01*
G01X1216883Y320734D02*
X1213357Y311459D01*
G01X1213206Y314300D02*
X1212254Y311795D01*
G01X1213357Y311459D02*
X1212351Y307114D01*
G01X1212254Y311795D02*
X1211400Y308106D01*
G01X1213357Y311459D02*
X1212351Y307114D01*
G01X1211400Y308106D02*
X1211210Y307285D01*
G01X1212351Y307114D02*
X1212150Y304273D01*
G01X1211210Y307285D02*
X1210997Y304273D01*
G01X1212150D02*
X1211400Y293651D01*
G01D02*
X1211350Y292943D01*
G01X1210997Y304273D02*
X1210212Y293157D01*
G01X1211350Y292943D02*
X1210686Y290810D01*
G01X1210212Y293157D02*
X1209672Y291423D01*
G01X1210686Y290810D02*
X1210135Y290259D01*
G01Y290258D02*
X1207789Y287912D01*
G01X1209672Y291423D02*
X1208985Y290736D01*
G01X1210135Y290258D02*
X1207789Y287912D01*
G01X1208985Y290735D02*
X1207312Y289062D01*
G01X1210135Y290258D02*
X1207789Y287912D01*
G01D02*
X1206755D01*
G01X1207312Y289062D02*
X1206673D01*
G01X1223746Y347682D02*
X1211400Y315202D01*
G01X1222549Y347772D02*
X1216797Y332641D01*
G01X1223746Y347682D02*
X1211400Y315202D01*
G01X1216134Y330895D02*
X1215813Y330053D01*
G01X1223746Y347682D02*
X1211400Y315202D01*
G01X1215150Y328307D02*
X1214833Y327477D01*
G01X1223746Y347682D02*
X1211400Y315202D01*
G01X1214166Y325719D02*
X1213847Y324883D01*
G01X1223746Y347682D02*
X1211400Y315202D01*
G01X1213182Y323131D02*
X1212941Y322500D01*
G01X1223746Y347682D02*
X1211400Y315202D01*
G01X1212941Y322500D02*
X1212862Y322292D01*
G01X1223746Y347682D02*
X1211400Y315202D01*
G01X1212198Y320543D02*
X1211400Y318443D01*
G01Y315202D02*
X1211057Y314300D01*
G01D02*
X1210733Y313448D01*
G01X1211400Y318443D02*
X1209826Y314300D01*
G01X1211057D02*
X1210733Y313448D01*
G01X1209826Y314300D02*
X1209635Y313797D01*
G01X1210733Y313448D02*
X1209611Y309109D01*
G01X1209635Y313797D02*
X1208461Y309256D01*
G01X1209611Y309107D02*
X1208828Y306081D01*
G01X1208461Y309254D02*
X1207714Y306369D01*
G01X1209611Y309107D02*
X1208828Y306081D01*
G01X1207714Y306367D02*
X1207640Y306081D01*
G01X1208423Y304292D02*
Y303841D01*
G01X1207273Y304418D02*
Y303841D01*
G01X1218711Y328789D02*
X1218390Y327945D01*
G01X1218711Y328789D02*
X1218390Y327945D01*
G01X1217743Y326241D02*
X1217428Y325415D01*
G01X1219788Y328378D02*
X1218505Y325004D01*
G01X1216775Y323693D02*
X1216455Y322852D01*
G01X1218499Y324986D02*
X1217554Y322500D01*
G01X1216775Y323693D02*
X1216455Y322852D01*
G01X1217554Y322500D02*
X1217532Y322442D01*
G01X1216775Y323693D02*
X1216455Y322852D01*
G01X1215806Y321142D02*
X1215486Y320301D01*
G01X1217531Y322439D02*
X1216884Y320737D01*
G01X1215806Y321142D02*
X1215486Y320301D01*
G01X1214839Y318597D02*
X1214518Y317753D01*
G01X1213871Y316049D02*
X1213206Y314300D01*
G01D02*
X1212254Y311795D01*
G01X1216883Y320734D02*
X1213357Y311459D01*
G01X1212254Y311795D02*
X1211400Y308106D01*
G01D02*
X1211210Y307285D01*
G01X1213357Y311459D02*
X1212351Y307114D01*
G01X1211210Y307285D02*
X1210997Y304273D01*
G01X1212351Y307114D02*
X1212150Y304273D01*
G01X1210997D02*
X1210212Y293157D01*
G01X1212150Y304273D02*
X1211400Y293651D01*
G01X1210997Y304273D02*
X1210212Y293157D01*
G01X1211400Y293651D02*
X1211350Y292943D01*
G01X1210212Y293157D02*
X1209672Y291423D01*
G01X1211350Y292943D02*
X1210686Y290810D01*
G01X1209672Y291423D02*
X1208985Y290736D01*
G01X1210686Y290810D02*
X1210135Y290259D01*
G01X1209672Y291423D02*
X1208985Y290736D01*
G01Y290735D02*
X1207312Y289062D01*
G01D02*
X1206673D01*
G01X1210135Y290258D02*
X1207789Y287912D01*
G01X1207312Y289062D02*
X1206673D01*
G01X1207789Y287912D02*
X1206755D01*
G01X1228209Y345346D02*
X1216051Y313366D01*
G01X1229406Y345256D02*
X1217173Y313080D01*
G01X1216051Y313366D02*
X1215845Y311866D01*
G01X1215585Y309953D02*
X1215462Y309060D01*
G01X1215201Y307147D02*
X1215078Y306254D01*
G01X1214817Y304341D02*
X1214694Y303448D01*
G01X1214433Y301535D02*
X1214045Y298692D01*
G01X1217173Y313080D02*
X1215195Y298613D01*
G01X1214045Y298692D02*
Y296500D01*
G01X1215195Y298613D02*
Y296500D01*
G01X1219877Y295033D02*
X1216823Y288551D01*
G01X1218736Y295310D02*
X1218375Y294546D01*
G01X1219877Y295033D02*
X1216823Y288551D01*
G01X1217534Y292762D02*
X1215783Y289042D01*
G01X1222022Y295038D02*
X1217376Y283651D01*
G01X1223166Y294797D02*
X1218354Y283001D01*
G01X1217376Y283651D02*
X1216542Y282817D01*
G01D02*
X1216541D01*
G01X1218354Y283001D02*
X1217356Y282003D01*
G01X1229406Y345256D02*
X1217173Y313080D01*
G01X1228209Y345346D02*
X1216051Y313366D01*
G01X1217173Y313080D02*
X1215195Y298613D01*
G01X1216051Y313366D02*
X1215845Y311866D01*
G01X1217173Y313080D02*
X1215195Y298613D01*
G01X1215585Y309953D02*
X1215462Y309060D01*
G01X1217173Y313080D02*
X1215195Y298613D01*
G01X1215201Y307147D02*
X1215078Y306254D01*
G01X1217173Y313080D02*
X1215195Y298613D01*
G01X1214817Y304341D02*
X1214694Y303448D01*
G01X1217173Y313080D02*
X1215195Y298613D01*
G01X1214433Y301535D02*
X1214045Y298692D01*
G01X1215195Y298613D02*
Y296500D01*
G01X1214045Y298692D02*
Y296500D01*
G01X1218736Y295310D02*
X1218375Y294546D01*
G01X1217534Y292762D02*
X1215783Y289042D01*
G01X1219877Y295033D02*
X1216823Y288551D01*
G01X1223166Y294797D02*
X1218354Y283001D01*
G01X1222022Y295038D02*
X1217376Y283651D01*
G01X1218354Y283001D02*
X1217356Y282003D01*
G01X1217376Y283651D02*
X1216542Y282817D01*
G01X1218354Y283001D02*
X1217356Y282003D01*
G01X1216542Y282817D02*
X1216541D01*
G01X1210509Y403565D02*
X1211400Y399436D01*
G01D02*
X1220814Y355814D01*
G01X1211557Y404163D02*
X1219102Y369200D01*
G01X1213819Y405585D02*
X1226512Y346762D01*
G01X1212771Y404987D02*
X1220493Y369200D01*
G01X1213819Y405585D02*
X1226512Y346762D01*
G01X1213819Y405585D02*
X1226512Y346762D01*
G01X1211557Y404163D02*
X1219102Y369200D01*
G01X1210509Y403565D02*
X1211400Y399436D01*
G01X1211557Y404163D02*
X1219102Y369200D01*
G01X1211400Y399436D02*
X1220814Y355814D01*
G01X1212771Y404987D02*
X1220493Y369200D01*
G01X1213819Y405585D02*
X1226512Y346762D01*
G01X1215057Y406294D02*
X1228209Y345346D01*
G01X1216105Y406892D02*
X1229406Y345256D01*
G01X1217345Y407598D02*
X1230931Y344618D01*
G01X1216105Y406892D02*
X1229406Y345256D01*
G01X1215057Y406294D02*
X1228209Y345346D01*
G01X1217345Y407598D02*
X1230931Y344618D01*
G01X1192585Y414495D02*
X1200657Y412657D01*
G01D02*
X1200677Y412653D01*
G01X1192570Y415679D02*
X1201232Y413707D01*
G01X1200657Y412657D02*
X1200677Y412653D01*
G01D02*
X1200686Y412645D01*
G01D02*
X1210509Y403565D01*
G01X1201232Y413707D02*
X1201479Y413479D01*
G01X1200657Y412657D02*
X1200677Y412653D01*
G01X1200686Y412645D02*
X1210509Y403565D01*
G01X1201479Y413479D02*
X1211557Y404163D01*
G01X1259616Y396234D02*
X1214612Y437828D01*
G01X1215167Y438882D02*
X1260534Y396952D01*
G01X1215818Y440127D02*
X1261614Y397811D01*
G01X1262532Y398529D02*
X1216373Y441181D01*
G01X1192581Y418279D02*
X1202539Y416012D01*
G01X1192597Y417095D02*
X1201984Y414958D01*
G01X1202539Y416012D02*
X1203304Y415304D01*
G01X1201984Y414958D02*
X1202490Y414490D01*
G01X1203304Y415304D02*
X1213819Y405585D01*
G01X1202490Y414490D02*
X1212771Y404987D01*
G01X1192200Y438962D02*
X1211400Y434595D01*
G01D02*
X1212220Y434409D01*
G01X1192215Y437779D02*
X1211400Y433415D01*
G01Y434595D02*
X1212220Y434409D01*
G01X1211400Y433415D02*
X1211665Y433355D01*
G01X1212220Y434409D02*
X1232139Y416006D01*
G01X1211665Y433355D02*
X1231091Y415408D01*
G01X1192570Y415679D02*
X1201232Y413707D01*
G01X1192585Y414495D02*
X1200657Y412657D01*
G01X1192570Y415679D02*
X1201232Y413707D01*
G01D02*
X1201479Y413479D01*
G01D02*
X1211557Y404163D01*
G01X1200657Y412657D02*
X1200677Y412653D01*
G01X1201232Y413707D02*
X1201479Y413479D01*
G01X1200677Y412653D02*
X1200686Y412645D01*
G01X1201232Y413707D02*
X1201479Y413479D01*
G01D02*
X1211557Y404163D01*
G01X1200686Y412645D02*
X1210509Y403565D01*
G01X1213074Y435610D02*
X1233340Y416887D01*
G01X1213629Y436664D02*
X1234388Y417485D01*
G01X1215167Y438882D02*
X1260534Y396952D01*
G01X1259616Y396234D02*
X1214612Y437828D01*
G01X1262532Y398529D02*
X1216373Y441181D01*
G01X1215818Y440127D02*
X1261614Y397811D01*
G01X1192597Y417095D02*
X1201984Y414958D01*
G01X1192581Y418279D02*
X1202539Y416012D01*
G01X1201984Y414958D02*
X1202490Y414490D01*
G01X1202539Y416012D02*
X1203304Y415304D01*
G01X1202490Y414490D02*
X1212771Y404987D01*
G01X1203304Y415304D02*
X1213819Y405585D01*
G01X1192472Y427422D02*
X1206832Y424152D01*
G01X1192457Y428606D02*
X1207387Y425206D01*
G01X1206832Y424152D02*
X1221944Y410185D01*
G01X1207387Y425206D02*
X1222992Y410783D01*
G01X1192215Y437779D02*
X1211400Y433415D01*
G01X1192200Y438962D02*
X1211400Y434595D01*
G01X1192215Y437779D02*
X1211400Y433415D01*
G01D02*
X1211665Y433355D01*
G01X1211400Y434595D02*
X1212220Y434409D01*
G01X1211665Y433355D02*
X1231091Y415408D01*
G01X1212220Y434409D02*
X1232139Y416006D01*
G01X1217034Y442425D02*
X1263622Y399368D01*
G01X1217589Y443479D02*
X1264540Y400086D01*
G01X1213629Y436664D02*
X1234388Y417485D01*
G01X1213074Y435610D02*
X1233340Y416887D01*
G01X1192568Y419676D02*
X1203196Y417256D01*
G01X1192553Y420860D02*
X1203751Y418310D01*
G01X1203196Y417256D02*
X1215057Y406294D01*
G01X1203751Y418310D02*
X1216105Y406892D01*
G01X1192517Y423442D02*
X1204960Y420610D01*
G01X1192533Y422258D02*
X1204405Y419556D01*
G01X1204960Y420610D02*
X1218393Y408196D01*
G01X1204405Y419556D02*
X1217345Y407598D01*
G01X1218393Y408196D02*
X1232128Y344528D01*
G01X1192502Y424839D02*
X1199060Y423346D01*
G01Y423347D02*
X1205619Y421853D01*
G01X1192486Y426023D02*
X1206174Y422907D01*
G01X1205619Y421853D02*
X1207819Y419819D01*
G01D02*
X1219632Y408902D01*
G01X1206174Y422907D02*
X1220680Y409500D01*
G01X1192457Y428606D02*
X1207387Y425206D01*
G01X1192472Y427422D02*
X1206832Y424152D01*
G01X1207387Y425206D02*
X1222992Y410783D01*
G01X1206832Y424152D02*
X1221944Y410185D01*
G01X1192437Y430003D02*
X1208038Y426452D01*
G01X1192421Y431187D02*
X1208593Y427506D01*
G01X1208038Y426452D02*
X1224230Y411490D01*
G01X1208593Y427506D02*
X1225278Y412088D01*
G01X1192386Y433771D02*
X1209809Y429803D01*
G01X1192401Y432587D02*
X1209254Y428749D01*
G01X1209809Y429803D02*
X1227566Y413392D01*
G01X1209254Y428749D02*
X1226518Y412794D01*
G01X1192370Y435168D02*
X1210464Y431047D01*
G01X1192349Y436353D02*
X1211019Y432101D01*
G01X1210464Y431047D02*
X1228806Y414097D01*
G01X1211019Y432101D02*
X1229854Y414695D01*
G01X1217589Y443479D02*
X1264540Y400086D01*
G01X1217034Y442425D02*
X1263622Y399368D01*
G01X1192553Y420860D02*
X1203751Y418310D01*
G01X1192568Y419676D02*
X1203196Y417256D01*
G01X1203751Y418310D02*
X1216105Y406892D01*
G01X1203196Y417256D02*
X1215057Y406294D01*
G01X1192533Y422258D02*
X1204405Y419556D01*
G01X1192517Y423442D02*
X1204960Y420610D01*
G01X1204405Y419556D02*
X1217345Y407598D01*
G01X1204960Y420610D02*
X1218393Y408196D01*
G01D02*
X1232128Y344528D01*
G01X1192486Y426023D02*
X1206174Y422907D01*
G01X1192502Y424839D02*
X1199060Y423346D01*
G01X1192486Y426023D02*
X1206174Y422907D01*
G01X1199060Y423347D02*
X1205619Y421853D01*
G01X1206174Y422907D02*
X1220680Y409500D01*
G01X1205619Y421853D02*
X1207819Y419819D01*
G01X1206174Y422907D02*
X1220680Y409500D01*
G01X1207819Y419819D02*
X1219632Y408902D01*
G01X1206174Y422907D02*
X1220680Y409500D01*
G01X1192421Y431187D02*
X1208593Y427506D01*
G01X1192437Y430003D02*
X1208038Y426452D01*
G01X1208593Y427506D02*
X1225278Y412088D01*
G01X1208038Y426452D02*
X1224230Y411490D01*
G01X1192401Y432587D02*
X1209254Y428749D01*
G01X1192386Y433771D02*
X1209809Y429803D01*
G01X1209254Y428749D02*
X1226518Y412794D01*
G01X1209809Y429803D02*
X1227566Y413392D01*
G01X1192349Y436353D02*
X1211019Y432101D01*
G01X1192370Y435168D02*
X1210464Y431047D01*
G01X1211019Y432101D02*
X1229854Y414695D01*
G01X1210464Y431047D02*
X1228806Y414097D01*
G01X1218242Y444724D02*
X1265624Y400938D01*
G01X1218242Y444724D02*
X1265624Y400938D01*
G01X1232544Y261755D02*
X1235633Y269400D01*
G01D02*
X1243501Y288869D01*
G01X1244645Y288629D02*
X1233511Y261077D01*
G01X1226617Y256430D02*
X1232544Y261755D01*
G01X1233511Y261077D02*
X1227058Y255280D01*
G01X1218827Y256430D02*
X1226617D01*
G01X1227058Y255280D02*
X1218827D01*
G01X1235933Y261423D02*
X1226909Y253317D01*
G01X1227350Y252167D02*
X1236904Y260749D01*
G01X1239063Y269400D02*
X1235933Y261423D01*
G01X1236904Y260749D02*
X1240299Y269400D01*
G01X1246680Y288812D02*
X1239063Y269400D01*
G01X1240299D02*
X1247825Y288579D01*
G01X1260805Y292760D02*
X1252750Y271265D01*
G01D02*
X1252051Y269400D01*
G01X1259660Y292984D02*
X1250822Y269400D01*
G01X1252051D02*
X1247196Y256443D01*
G01X1250822Y269400D02*
X1250777Y269280D01*
G01X1252051Y269400D02*
X1247196Y256443D01*
G01X1250777Y269280D02*
X1246217Y257111D01*
G01X1247196Y256443D02*
X1246600Y255908D01*
G01D02*
X1224999Y236501D01*
G01X1246217Y257111D02*
X1224184Y237316D01*
G01X1224999Y236501D02*
X1223874Y235491D01*
G01X1224184Y237316D02*
X1223433Y236641D01*
G01X1223874Y235491D02*
X1219163D01*
G01X1223433Y236641D02*
X1219163D01*
G01X1262757Y294077D02*
X1253505Y269400D01*
G01X1263902Y293853D02*
X1254734Y269400D01*
G01X1253505D02*
X1248353Y255658D01*
G01X1254734Y269400D02*
X1250777Y258845D01*
G01X1253505Y269400D02*
X1248353Y255658D01*
G01X1250777Y258845D02*
X1249332Y254990D01*
G01X1248353Y255658D02*
X1225963Y235537D01*
G01D02*
X1224342Y234081D01*
G01X1249332Y254990D02*
X1224783Y232931D01*
G01X1224342Y234081D02*
X1219811D01*
G01X1224783Y232931D02*
X1219811D01*
G01X1238485Y288043D02*
X1231643Y272162D01*
G01X1237341Y288296D02*
X1230625Y272707D01*
G01X1231643Y272162D02*
X1229847Y269400D01*
G01X1230625Y272707D02*
X1228475Y269400D01*
G01X1229847D02*
X1227322Y265516D01*
G01X1228475Y269400D02*
X1226452Y266288D01*
G01X1227322Y265516D02*
X1226293Y264656D01*
G01X1226452Y266288D02*
X1225875Y265806D01*
G01X1227322Y265516D02*
X1226293Y264656D01*
G01D02*
X1224693D01*
G01X1225875Y265806D02*
X1224693D01*
G01X1240457Y288496D02*
X1229440Y262922D01*
G01X1241601Y288243D02*
X1230404Y262252D01*
G01X1229440Y262922D02*
X1227640Y261200D01*
G01D02*
X1226508D01*
G01X1230404Y262252D02*
X1228102Y260050D01*
G01X1227640Y261200D02*
X1226508D01*
G01X1228102Y260050D02*
X1226658D01*
G01X1227058Y255280D02*
X1218827D01*
G01Y256430D02*
X1226617D01*
G01X1233511Y261077D02*
X1227058Y255280D01*
G01X1226617Y256430D02*
X1232544Y261755D01*
G01X1244645Y288629D02*
X1233511Y261077D01*
G01X1232544Y261755D02*
X1235633Y269400D01*
G01X1244645Y288629D02*
X1233511Y261077D01*
G01X1235633Y269400D02*
X1243501Y288869D01*
G01X1240299Y269400D02*
X1247825Y288579D01*
G01X1246680Y288812D02*
X1239063Y269400D01*
G01X1236904Y260749D02*
X1240299Y269400D01*
G01X1239063D02*
X1235933Y261423D01*
G01X1227350Y252167D02*
X1236904Y260749D01*
G01X1235933Y261423D02*
X1226909Y253317D01*
G01X1259660Y292984D02*
X1250822Y269400D01*
G01X1260805Y292760D02*
X1252750Y271265D01*
G01X1259660Y292984D02*
X1250822Y269400D01*
G01X1252750Y271265D02*
X1252051Y269400D01*
G01X1250822D02*
X1250777Y269280D01*
G01D02*
X1246217Y257111D01*
G01X1252051Y269400D02*
X1247196Y256443D01*
G01X1246217Y257111D02*
X1224184Y237316D01*
G01X1247196Y256443D02*
X1246600Y255908D01*
G01X1246217Y257111D02*
X1224184Y237316D01*
G01X1246600Y255908D02*
X1224999Y236501D01*
G01X1224184Y237316D02*
X1223433Y236641D01*
G01X1224999Y236501D02*
X1223874Y235491D01*
G01X1223433Y236641D02*
X1219163D01*
G01X1223874Y235491D02*
X1219163D01*
G01X1237341Y288296D02*
X1230625Y272707D01*
G01X1238485Y288043D02*
X1231643Y272162D01*
G01X1230625Y272707D02*
X1228475Y269400D01*
G01X1231643Y272162D02*
X1229847Y269400D01*
G01X1228475D02*
X1226452Y266288D01*
G01X1229847Y269400D02*
X1227322Y265516D01*
G01X1226452Y266288D02*
X1225875Y265806D01*
G01D02*
X1224693D01*
G01X1227322Y265516D02*
X1226293Y264656D01*
G01X1225875Y265806D02*
X1224693D01*
G01X1226293Y264656D02*
X1224693D01*
G01X1249801Y288893D02*
X1242675Y269400D01*
G01X1250947Y288676D02*
X1243900Y269400D01*
G01X1242675D02*
X1239796Y261523D01*
G01X1243900Y269400D02*
X1240778Y260859D01*
G01X1239796Y261523D02*
X1226746Y249798D01*
G01X1240778Y260859D02*
X1227187Y248648D01*
G01X1265894Y295300D02*
X1250486Y254197D01*
G01X1267039Y295076D02*
X1251465Y253529D01*
G01X1250486Y254197D02*
X1225280Y231550D01*
G01X1251465Y253529D02*
X1225721Y230400D01*
G01X1269656Y294904D02*
X1260094Y269400D01*
G01X1268511Y295128D02*
X1258865Y269400D01*
G01X1260094D02*
X1253600Y252077D01*
G01X1258865Y269400D02*
X1252750Y253089D01*
G01X1260094Y269400D02*
X1253600Y252077D01*
G01X1252750Y253089D02*
X1252621Y252745D01*
G01X1253600Y252077D02*
X1226635Y227846D01*
G01X1252621Y252745D02*
X1226194Y228996D01*
G01X1226635Y227846D02*
X1218680D01*
G01X1226194Y228996D02*
X1218680D01*
G01X1263902Y293853D02*
X1254734Y269400D01*
G01X1262757Y294077D02*
X1253505Y269400D01*
G01X1254734D02*
X1250777Y258845D01*
G01D02*
X1249332Y254990D01*
G01X1253505Y269400D02*
X1248353Y255658D01*
G01X1249332Y254990D02*
X1224783Y232931D01*
G01X1248353Y255658D02*
X1225963Y235537D01*
G01X1249332Y254990D02*
X1224783Y232931D01*
G01X1225963Y235537D02*
X1224342Y234081D01*
G01X1224783Y232931D02*
X1219811D01*
G01X1224342Y234081D02*
X1219811D01*
G01X1267039Y295076D02*
X1251465Y253529D01*
G01X1265894Y295300D02*
X1250486Y254197D01*
G01X1251465Y253529D02*
X1225721Y230400D01*
G01X1250486Y254197D02*
X1225280Y231550D01*
G01X1268511Y295128D02*
X1258865Y269400D01*
G01X1269656Y294904D02*
X1260094Y269400D01*
G01X1258865D02*
X1252750Y253089D01*
G01D02*
X1252621Y252745D01*
G01X1260094Y269400D02*
X1253600Y252077D01*
G01X1252621Y252745D02*
X1226194Y228996D01*
G01X1253600Y252077D02*
X1226635Y227846D01*
G01X1226194Y228996D02*
X1218680D01*
G01X1226635Y227846D02*
X1218680D01*
G01X1241601Y288243D02*
X1230404Y262252D01*
G01X1240457Y288496D02*
X1229440Y262922D01*
G01X1230404Y262252D02*
X1228102Y260050D01*
G01X1229440Y262922D02*
X1227640Y261200D01*
G01X1230404Y262252D02*
X1228102Y260050D01*
G01D02*
X1226658D01*
G01X1227640Y261200D02*
X1226508D01*
G01X1229336Y293889D02*
X1224138Y279454D01*
G01X1223144Y280088D02*
X1221947Y278891D01*
G01X1224138Y279454D02*
X1222761Y278077D01*
G01X1232407Y294816D02*
X1226931Y277710D01*
G01X1231261Y295011D02*
X1225920Y278327D01*
G01X1226931Y277710D02*
X1221555Y272336D01*
G01X1225920Y278327D02*
X1220741Y273149D01*
G01X1234411Y295057D02*
X1229313Y277342D01*
G01X1235557Y294879D02*
X1230380Y276888D01*
G01X1229313Y277342D02*
X1229085Y276938D01*
G01X1230380Y276888D02*
X1230084Y276368D01*
G01X1229070Y276934D02*
X1223837Y270644D01*
G01X1230086Y276355D02*
X1224688Y269867D01*
G01X1223837Y270644D02*
X1222741Y269549D01*
G01X1224688Y269867D02*
X1223556Y268735D01*
G01X1250947Y288676D02*
X1243900Y269400D01*
G01X1249801Y288893D02*
X1242675Y269400D01*
G01X1243900D02*
X1240778Y260859D01*
G01X1242675Y269400D02*
X1239796Y261523D01*
G01X1240778Y260859D02*
X1227187Y248648D01*
G01X1239796Y261523D02*
X1226746Y249798D01*
G01X1229336Y293889D02*
X1224138Y279454D01*
G01D02*
X1222761Y278077D01*
G01X1223144Y280088D02*
X1221947Y278891D01*
G01X1231261Y295011D02*
X1225920Y278327D01*
G01X1232407Y294816D02*
X1226931Y277710D01*
G01X1225920Y278327D02*
X1220741Y273149D01*
G01X1226931Y277710D02*
X1221555Y272336D01*
G01X1235557Y294879D02*
X1230380Y276888D01*
G01X1234411Y295057D02*
X1229313Y277342D01*
G01X1230380Y276888D02*
X1230084Y276368D01*
G01X1229313Y277342D02*
X1229085Y276938D01*
G01X1230086Y276355D02*
X1224688Y269867D01*
G01X1229070Y276934D02*
X1223837Y270644D01*
G01X1224688Y269867D02*
X1223556Y268735D01*
G01X1223837Y270644D02*
X1222741Y269549D01*
G01X1252750Y288943D02*
X1245426Y269400D01*
G01X1254004Y289010D02*
X1246655Y269400D01*
G01X1245426D02*
X1241894Y259975D01*
G01X1246655Y269400D02*
X1242873Y259307D01*
G01X1241894Y259975D02*
X1221555Y241700D01*
G01X1242873Y259307D02*
X1221996Y240550D01*
G01X1257295Y290592D02*
X1249366Y269400D01*
G01X1256150Y290815D02*
X1248137Y269400D01*
G01X1249366D02*
X1245063Y257900D01*
G01X1248137Y269400D02*
X1244084Y258568D01*
G01X1245063Y257900D02*
X1223470Y238500D01*
G01D02*
X1223223Y238277D01*
G01X1244084Y258568D02*
X1222504Y239178D01*
G01X1222945Y238028D02*
X1220374D01*
G01X1222504Y239178D02*
X1220374D01*
G01X1254004Y289010D02*
X1246655Y269400D01*
G01X1254004Y289010D02*
X1246655Y269400D01*
G01X1252750Y288943D02*
X1245426Y269400D01*
G01X1246655D02*
X1242873Y259307D01*
G01X1245426Y269400D02*
X1241894Y259975D01*
G01X1242873Y259307D02*
X1221996Y240550D01*
G01X1241894Y259975D02*
X1221555Y241700D01*
G01X1256150Y290815D02*
X1248137Y269400D01*
G01X1257295Y290592D02*
X1249366Y269400D01*
G01X1248137D02*
X1244084Y258568D01*
G01X1249366Y269400D02*
X1245063Y257900D01*
G01X1244084Y258568D02*
X1222504Y239178D01*
G01X1245063Y257900D02*
X1223470Y238500D01*
G01X1244084Y258568D02*
X1222504Y239178D01*
G01X1223470Y238500D02*
X1223223Y238277D01*
G01X1222504Y239178D02*
X1220374D01*
G01X1222945Y238028D02*
X1220374D01*
G01X1282001Y283160D02*
X1279914Y273333D01*
G01X1280825Y283160D02*
X1278739Y273338D01*
G01X1279914Y273333D02*
X1284402Y251272D01*
G01X1278739Y273338D02*
X1283319Y250823D01*
G01X1281380Y217626D02*
X1279766Y223128D01*
G01D02*
X1279994Y224891D01*
G01D02*
X1282032Y227946D01*
G01X1281973Y250273D02*
X1277314Y273171D01*
G01X1280890Y249825D02*
X1276139Y273176D01*
G01X1277314Y273171D02*
X1279435Y283160D01*
G01X1276139Y273176D02*
X1278259Y283160D01*
G01X1280825D02*
X1278739Y273338D01*
G01X1282001Y283160D02*
X1279914Y273333D01*
G01X1278739Y273338D02*
X1283319Y250823D01*
G01X1279914Y273333D02*
X1284402Y251272D01*
G01X1281380Y217626D02*
X1279766Y223128D01*
G01D02*
X1279994Y224891D01*
G01D02*
X1282032Y227946D01*
G01X1280890Y249825D02*
X1276139Y273176D01*
G01X1281973Y250273D02*
X1277314Y273171D01*
G01X1276139Y273176D02*
X1278259Y283160D01*
G01X1277314Y273171D02*
X1279435Y283160D01*
G01X1253114Y339833D02*
X1259093Y369200D01*
G01X1263904Y387066D02*
X1254223Y339512D01*
G01X1244265Y316559D02*
X1252750Y338876D01*
G01D02*
X1253114Y339833D01*
G01X1254223Y339512D02*
X1245410Y316332D01*
G01X1243501Y288869D02*
X1243534Y290041D01*
G01X1243587Y291967D02*
X1243612Y292869D01*
G01X1243665Y294795D02*
X1243690Y295697D01*
G01X1243743Y297623D02*
X1243768Y298525D01*
G01X1243821Y300451D02*
X1243846Y301353D01*
G01X1243899Y303279D02*
X1243924Y304181D01*
G01X1243977Y306107D02*
X1244002Y307009D01*
G01X1244055Y308935D02*
X1244080Y309837D01*
G01X1244133Y311763D02*
X1244158Y312665D01*
G01X1244211Y314591D02*
X1244265Y316559D01*
G01X1245410Y316332D02*
X1244645Y288629D01*
G01X1246751Y291366D02*
X1246680Y288812D01*
G01X1247825Y288579D02*
X1248258Y304273D01*
G01X1247459Y317069D02*
X1247389Y314551D01*
G01X1248258Y304273D02*
X1248604Y316842D01*
G01X1249523Y322500D02*
X1247459Y317069D01*
G01X1248604Y316842D02*
X1250755Y322500D01*
G01X1255172Y337360D02*
X1249523Y322500D01*
G01X1250755D02*
X1256281Y337039D01*
G01X1265275Y386980D02*
X1255172Y337360D01*
G01X1256281Y337039D02*
X1266377Y386627D01*
G01X1265275Y386980D02*
X1255172Y337360D01*
G01X1276554Y386271D02*
X1264507Y327110D01*
G01X1276554Y386271D02*
X1264507Y327110D01*
G01X1271904Y369200D02*
X1263398Y327431D01*
G01X1264507Y327110D02*
X1261538Y319298D01*
G01X1263398Y327431D02*
X1261524Y322500D01*
G01X1264507Y327110D02*
X1261538Y319298D01*
G01X1261524Y322500D02*
X1260393Y319525D01*
G01X1261538Y319298D02*
X1261400Y314300D01*
G01X1260393Y319525D02*
X1260363Y318463D01*
G01X1261538Y319298D02*
X1261400Y314300D01*
G01X1260303Y316264D02*
X1260278Y315363D01*
G01X1261400Y314300D02*
X1260875Y295293D01*
G01X1260217Y313164D02*
X1260192Y312263D01*
G01X1261400Y314300D02*
X1260875Y295293D01*
G01X1260131Y310064D02*
X1260106Y309163D01*
G01X1261400Y314300D02*
X1260875Y295293D01*
G01X1260045Y306964D02*
X1260020Y306063D01*
G01X1261400Y314300D02*
X1260875Y295293D01*
G01X1259959Y303864D02*
X1259934Y302963D01*
G01X1261400Y314300D02*
X1260875Y295293D01*
G01X1259873Y300764D02*
X1259848Y299863D01*
G01X1260874Y295293D02*
X1260805Y292760D01*
G01X1259788Y297664D02*
X1259660Y292984D01*
G01X1274117Y367486D02*
X1265455Y324949D01*
G01X1275640Y369200D02*
X1266564Y324628D01*
G01X1265455Y324949D02*
X1264524Y322500D01*
G01X1266564Y324628D02*
X1265755Y322500D01*
G01X1264524D02*
X1263466Y319716D01*
G01X1265755Y322500D02*
X1264611Y319489D01*
G01X1263466Y319716D02*
X1263410Y317666D01*
G01X1264611Y319489D02*
X1264467Y314300D01*
G01X1262796Y295464D02*
X1262777Y294771D01*
G01X1264467Y314300D02*
X1263902Y293853D01*
G01X1226608Y346316D02*
X1222694Y336024D01*
G01X1225411Y346406D02*
X1222265Y338143D01*
G01X1226608Y346316D02*
X1222694Y336024D01*
G01X1222693Y336021D02*
X1222382Y335204D01*
G01X1221615Y336433D02*
X1221303Y335616D01*
G01X1222373Y335177D02*
X1219789Y328381D01*
G01X1220646Y333882D02*
X1220327Y333044D01*
G01X1222373Y335177D02*
X1219789Y328381D01*
G01X1219679Y331337D02*
X1219358Y330493D01*
G01X1222373Y335177D02*
X1219789Y328381D01*
G01X1232139Y416006D02*
X1248478Y340187D01*
G01X1232139Y416006D02*
X1248478Y340187D01*
G01X1232139Y416006D02*
X1248478Y340187D01*
G01X1232139Y416006D02*
X1248478Y340187D01*
G01X1242450Y362700D02*
X1247281Y340278D01*
G01X1248478Y340187D02*
X1239259Y315937D01*
G01X1247281Y340278D02*
X1246600Y338486D01*
G01X1248478Y340187D02*
X1239259Y315937D01*
G01X1246600Y338486D02*
X1242698Y328221D01*
G01X1248478Y340187D02*
X1239259Y315937D01*
G01X1242698Y328221D02*
X1238114Y316164D01*
G01X1239259Y315937D02*
X1239214Y314300D01*
G01X1238114Y316164D02*
X1238062Y314300D01*
G01X1239214D02*
X1238936Y304273D01*
G01X1238062Y314300D02*
X1238030Y313171D01*
G01X1233340Y416887D02*
X1250006Y339551D01*
G01X1234388Y417485D02*
X1251203Y339460D01*
G01X1250006Y339551D02*
X1241232Y316472D01*
G01X1251203Y339460D02*
X1242377Y316245D01*
G01X1241232Y316472D02*
X1241196Y315199D01*
G01X1240491Y289744D02*
X1240457Y288496D01*
G01X1242377Y316245D02*
X1241601Y288243D01*
G01X1245410Y316332D02*
X1244645Y288629D01*
G01X1243501Y288869D02*
X1243534Y290041D01*
G01X1245410Y316332D02*
X1244645Y288629D01*
G01X1243587Y291967D02*
X1243612Y292869D01*
G01X1245410Y316332D02*
X1244645Y288629D01*
G01X1243665Y294795D02*
X1243690Y295697D01*
G01X1245410Y316332D02*
X1244645Y288629D01*
G01X1243743Y297623D02*
X1243768Y298525D01*
G01X1245410Y316332D02*
X1244645Y288629D01*
G01X1243821Y300451D02*
X1243846Y301353D01*
G01X1245410Y316332D02*
X1244645Y288629D01*
G01X1243899Y303279D02*
X1243924Y304181D01*
G01X1245410Y316332D02*
X1244645Y288629D01*
G01X1243977Y306107D02*
X1244002Y307009D01*
G01X1245410Y316332D02*
X1244645Y288629D01*
G01X1244055Y308935D02*
X1244080Y309837D01*
G01X1245410Y316332D02*
X1244645Y288629D01*
G01X1244133Y311763D02*
X1244158Y312665D01*
G01X1245410Y316332D02*
X1244645Y288629D01*
G01X1244211Y314591D02*
X1244265Y316559D01*
G01X1254223Y339512D02*
X1245410Y316332D01*
G01X1244265Y316559D02*
X1252750Y338876D01*
G01X1254223Y339512D02*
X1245410Y316332D01*
G01X1252750Y338876D02*
X1253114Y339833D01*
G01X1263904Y387066D02*
X1254223Y339512D01*
G01X1253114Y339833D02*
X1259093Y369200D01*
G01X1263904Y387066D02*
X1254223Y339512D01*
G01X1263904Y387066D02*
X1254223Y339512D01*
G01X1256281Y337039D02*
X1266377Y386627D01*
G01X1265275Y386980D02*
X1255172Y337360D01*
G01X1250755Y322500D02*
X1256281Y337039D01*
G01X1255172Y337360D02*
X1249523Y322500D01*
G01X1248604Y316842D02*
X1250755Y322500D01*
G01X1249523D02*
X1247459Y317069D01*
G01X1248258Y304273D02*
X1248604Y316842D01*
G01X1247459Y317069D02*
X1247389Y314551D01*
G01X1247825Y288579D02*
X1248258Y304273D01*
G01X1246751Y291366D02*
X1246680Y288812D01*
G01X1271904Y369200D02*
X1263398Y327431D01*
G01X1276554Y386271D02*
X1264507Y327110D01*
G01X1263398Y327431D02*
X1261524Y322500D01*
G01D02*
X1260393Y319525D01*
G01X1264507Y327110D02*
X1261538Y319298D01*
G01X1260393Y319525D02*
X1260363Y318463D01*
G01X1260303Y316264D02*
X1260278Y315363D01*
G01X1261538Y319298D02*
X1261400Y314300D01*
G01X1260217Y313164D02*
X1260192Y312263D01*
G01X1260131Y310064D02*
X1260106Y309163D01*
G01X1260045Y306964D02*
X1260020Y306063D01*
G01X1259959Y303864D02*
X1259934Y302963D01*
G01X1259873Y300764D02*
X1259848Y299863D01*
G01X1261400Y314300D02*
X1260875Y295293D01*
G01X1259788Y297664D02*
X1259660Y292984D01*
G01X1260874Y295293D02*
X1260805Y292760D01*
G01X1225411Y346406D02*
X1222265Y338143D01*
G01X1221615Y336433D02*
X1221303Y335616D01*
G01X1226608Y346316D02*
X1222694Y336024D01*
G01X1221615Y336433D02*
X1221303Y335616D01*
G01X1222693Y336021D02*
X1222382Y335204D01*
G01X1220646Y333882D02*
X1220327Y333044D01*
G01X1219679Y331337D02*
X1219358Y330493D01*
G01X1222373Y335177D02*
X1219789Y328381D01*
G01X1236386Y343180D02*
X1225677Y315012D01*
G01X1237583Y343089D02*
X1226822Y314785D01*
G01X1225677Y315012D02*
X1225614Y312744D01*
G01X1226809Y314300D02*
X1226533Y304273D01*
G01X1225149Y296052D02*
X1225100Y294072D01*
G01X1226300Y296018D02*
X1226245Y293841D01*
G01X1225100Y294072D02*
X1220413Y282097D01*
G01X1226245Y293841D02*
X1221397Y281453D01*
G01X1242450Y362700D02*
X1247281Y340278D01*
G01X1232139Y416006D02*
X1248478Y340187D01*
G01X1247281Y340278D02*
X1246600Y338486D01*
G01D02*
X1242698Y328221D01*
G01D02*
X1238114Y316164D01*
G01X1248478Y340187D02*
X1239259Y315937D01*
G01X1238114Y316164D02*
X1238062Y314300D01*
G01X1239259Y315937D02*
X1239214Y314300D01*
G01X1238062D02*
X1238030Y313171D01*
G01X1239214Y314300D02*
X1238936Y304273D01*
G01X1264217Y369200D02*
X1257230Y334882D01*
G01X1265391Y369200D02*
X1258339Y334561D01*
G01X1257230Y334882D02*
X1252750Y323095D01*
G01D02*
X1252524Y322500D01*
G01D02*
X1250584Y317397D01*
G01X1258339Y334561D02*
X1251729Y317170D01*
G01X1250584Y317397D02*
X1250521Y315141D01*
G01X1251729Y317170D02*
X1251650Y314300D01*
G01X1249877Y292170D02*
X1249801Y288893D01*
G01X1251027Y292144D02*
X1250947Y288676D01*
G01X1280455Y386026D02*
X1266511Y317557D01*
G01X1281614Y385953D02*
X1267658Y317425D01*
G01X1266511Y317557D02*
X1266492Y316885D01*
G01X1267658Y317425D02*
X1267039Y295076D01*
G01X1280763Y369200D02*
X1271249Y322500D01*
G01X1279589Y369200D02*
X1270075Y322500D01*
G01X1271249D02*
X1270865Y320614D01*
G01D02*
X1270289Y317786D01*
G01X1270075Y322500D02*
X1269142Y317918D01*
G01X1270289Y317786D02*
X1270233Y315767D01*
G01X1269142Y317918D02*
X1269113Y316887D01*
G01X1270289Y317786D02*
X1270233Y315767D01*
G01D02*
X1270193Y314300D01*
G01X1269113Y316887D02*
X1269041Y314300D01*
G01X1270193D02*
X1269946Y305337D01*
G01X1269945D02*
X1269656Y294904D01*
G01X1269041Y314300D02*
X1268511Y295128D01*
G01X1275640Y369200D02*
X1266564Y324628D01*
G01X1275640Y369200D02*
X1266564Y324628D01*
G01X1274117Y367486D02*
X1265455Y324949D01*
G01X1266564Y324628D02*
X1265755Y322500D01*
G01X1265455Y324949D02*
X1264524Y322500D01*
G01X1265755D02*
X1264611Y319489D01*
G01X1264524Y322500D02*
X1263466Y319716D01*
G01X1264611Y319489D02*
X1264467Y314300D01*
G01X1263466Y319716D02*
X1263410Y317666D01*
G01X1264467Y314300D02*
X1263902Y293853D01*
G01X1262796Y295464D02*
X1262777Y294771D01*
G01X1281614Y385953D02*
X1267658Y317425D01*
G01X1280455Y386026D02*
X1266511Y317557D01*
G01X1267658Y317425D02*
X1267039Y295076D01*
G01X1266511Y317557D02*
X1266492Y316885D01*
G01X1279589Y369200D02*
X1270075Y322500D01*
G01X1280763Y369200D02*
X1271249Y322500D01*
G01X1270075D02*
X1269142Y317918D01*
G01X1271249Y322500D02*
X1270865Y320614D01*
G01X1270075Y322500D02*
X1269142Y317918D01*
G01X1270865Y320614D02*
X1270289Y317786D01*
G01X1269142Y317918D02*
X1269113Y316887D01*
G01D02*
X1269041Y314300D01*
G01X1270289Y317786D02*
X1270233Y315767D01*
G01X1269113Y316887D02*
X1269041Y314300D01*
G01X1270233Y315767D02*
X1270193Y314300D01*
G01X1269041D02*
X1268511Y295128D01*
G01X1270193Y314300D02*
X1269946Y305337D01*
G01X1269041Y314300D02*
X1268511Y295128D01*
G01X1269945Y305337D02*
X1269656Y294904D01*
G01X1234388Y417485D02*
X1251203Y339460D01*
G01X1233340Y416887D02*
X1250006Y339551D01*
G01X1251203Y339460D02*
X1242377Y316245D01*
G01X1250006Y339551D02*
X1241232Y316472D01*
G01X1242377Y316245D02*
X1241601Y288243D01*
G01X1241232Y316472D02*
X1241196Y315199D01*
G01X1242377Y316245D02*
X1241601Y288243D01*
G01X1240491Y289744D02*
X1240457Y288496D01*
G01X1232128Y344528D02*
X1220584Y314163D01*
G01X1230931Y344618D02*
X1219441Y314395D01*
G01X1220584Y314163D02*
X1219877Y295033D01*
G01X1219441Y314395D02*
X1219407Y313478D01*
G01X1220584Y314163D02*
X1219877Y295033D01*
G01X1219329Y311392D02*
X1219295Y310492D01*
G01X1220584Y314163D02*
X1219877Y295033D01*
G01X1219217Y308406D02*
X1219183Y307506D01*
G01X1220584Y314163D02*
X1219877Y295033D01*
G01X1219105Y305420D02*
X1219071Y304520D01*
G01X1220584Y314163D02*
X1219877Y295033D01*
G01X1218993Y302434D02*
X1218959Y301534D01*
G01X1220584Y314163D02*
X1219877Y295033D01*
G01X1218881Y299448D02*
X1218847Y298548D01*
G01X1233655Y343892D02*
X1222566Y314721D01*
G01X1234852Y343802D02*
X1226754Y322500D01*
G01X1233655Y343892D02*
X1222566Y314721D01*
G01X1226754Y322500D02*
X1223711Y314494D01*
G01X1222566Y314721D02*
X1222554Y314300D01*
G01X1223706D02*
X1223428Y304273D01*
G01X1237583Y343089D02*
X1226822Y314785D01*
G01X1236386Y343180D02*
X1225677Y315012D01*
G01X1226809Y314300D02*
X1226533Y304273D01*
G01X1225677Y315012D02*
X1225614Y312744D01*
G01X1226300Y296018D02*
X1226245Y293841D01*
G01X1225149Y296052D02*
X1225100Y294072D01*
G01X1226245Y293841D02*
X1221397Y281453D01*
G01X1225100Y294072D02*
X1220413Y282097D01*
G01X1239110Y342455D02*
X1228776Y315275D01*
G01X1240307Y342364D02*
X1232754Y322500D01*
G01X1239110Y342455D02*
X1228776Y315275D01*
G01X1232754Y322500D02*
X1229921Y315048D01*
G01X1228776Y315275D02*
X1228738Y313927D01*
G01X1229921Y315048D02*
X1229900Y314300D01*
G01X1228776Y315275D02*
X1228738Y313927D01*
G01X1229900Y314300D02*
X1229623Y304273D01*
G01X1228191Y294105D02*
X1223144Y280088D01*
G01X1243031Y341638D02*
X1232970Y315175D01*
G01X1241834Y341729D02*
X1234524Y322500D01*
G01X1243031Y341638D02*
X1232970Y315175D01*
G01X1234524Y322500D02*
X1231825Y315402D01*
G01X1240338Y360588D02*
X1244559Y341006D01*
G01X1241307Y361557D02*
X1245756Y340915D01*
G01X1244559Y341006D02*
X1237523Y322500D01*
G01D02*
X1234985Y315823D01*
G01X1245756Y340915D02*
X1236130Y315596D01*
G01X1265391Y369200D02*
X1258339Y334561D01*
G01X1264217Y369200D02*
X1257230Y334882D01*
G01X1258339Y334561D02*
X1251729Y317170D01*
G01X1257230Y334882D02*
X1252750Y323095D01*
G01X1258339Y334561D02*
X1251729Y317170D01*
G01X1252750Y323095D02*
X1252524Y322500D01*
G01X1258339Y334561D02*
X1251729Y317170D01*
G01X1252524Y322500D02*
X1250584Y317397D01*
G01X1251729Y317170D02*
X1251650Y314300D01*
G01X1250584Y317397D02*
X1250521Y315141D01*
G01X1251027Y292144D02*
X1250947Y288676D01*
G01X1249877Y292170D02*
X1249801Y288893D01*
G01X1230931Y344618D02*
X1219441Y314395D01*
G01X1232128Y344528D02*
X1220584Y314163D01*
G01X1219441Y314395D02*
X1219407Y313478D01*
G01X1219329Y311392D02*
X1219295Y310492D01*
G01X1219217Y308406D02*
X1219183Y307506D01*
G01X1219105Y305420D02*
X1219071Y304520D01*
G01X1218993Y302434D02*
X1218959Y301534D01*
G01X1218881Y299448D02*
X1218847Y298548D01*
G01X1220584Y314163D02*
X1219877Y295033D01*
G01X1234852Y343802D02*
X1226754Y322500D01*
G01D02*
X1223711Y314494D01*
G01X1233655Y343892D02*
X1222566Y314721D01*
G01X1223706Y314300D02*
X1223428Y304273D01*
G01X1222566Y314721D02*
X1222554Y314300D01*
G01X1240307Y342364D02*
X1232754Y322500D01*
G01D02*
X1229921Y315048D01*
G01X1239110Y342455D02*
X1228776Y315275D01*
G01X1229921Y315048D02*
X1229900Y314300D01*
G01D02*
X1229623Y304273D01*
G01X1228776Y315275D02*
X1228738Y313927D01*
G01X1228191Y294105D02*
X1223144Y280088D01*
G01X1241834Y341729D02*
X1234524Y322500D01*
G01D02*
X1231825Y315402D01*
G01X1243031Y341638D02*
X1232970Y315175D01*
G01X1241307Y361557D02*
X1245756Y340915D01*
G01X1240338Y360588D02*
X1244559Y341006D01*
G01X1245756Y340915D02*
X1236130Y315596D01*
G01X1244559Y341006D02*
X1237523Y322500D01*
G01X1245756Y340915D02*
X1236130Y315596D01*
G01X1237523Y322500D02*
X1234985Y315823D01*
G01X1266779Y369200D02*
X1259287Y332403D01*
G01X1267953Y369200D02*
X1260396Y332082D01*
G01X1259287Y332403D02*
X1255523Y322500D01*
G01D02*
X1253642Y317552D01*
G01X1260396Y332082D02*
X1254787Y317325D01*
G01X1253642Y317552D02*
X1253599Y316021D01*
G01X1254787Y317325D02*
X1254703Y314300D01*
G01X1252859Y289234D02*
X1252750Y288943D01*
G01X1270515Y369200D02*
X1262448Y329585D01*
G01X1269341Y369200D02*
X1261339Y329906D01*
G01X1262448Y329585D02*
X1259755Y322500D01*
G01X1261339Y329906D02*
X1258524Y322500D01*
G01X1259755D02*
X1258054Y318026D01*
G01X1258524Y322500D02*
X1256909Y318253D01*
G01X1258054Y318026D02*
X1257951Y314300D01*
G01X1256909Y318253D02*
X1256865Y316696D01*
G01X1258054Y318026D02*
X1257951Y314300D01*
G01D02*
X1257345Y292399D01*
G01X1256810Y314653D02*
X1256800Y314300D01*
G01X1257343Y292400D02*
X1257295Y290592D01*
G01X1256236Y294044D02*
X1256150Y290815D01*
G01X1267953Y369200D02*
X1260396Y332082D01*
G01X1266779Y369200D02*
X1259287Y332403D01*
G01X1260396Y332082D02*
X1254787Y317325D01*
G01X1259287Y332403D02*
X1255523Y322500D01*
G01X1260396Y332082D02*
X1254787Y317325D01*
G01X1255523Y322500D02*
X1253642Y317552D01*
G01X1254787Y317325D02*
X1254703Y314300D01*
G01X1253642Y317552D02*
X1253599Y316021D01*
G01X1252859Y289234D02*
X1252750Y288943D01*
G01X1269341Y369200D02*
X1261339Y329906D01*
G01X1270515Y369200D02*
X1262448Y329585D01*
G01X1261339Y329906D02*
X1258524Y322500D01*
G01X1262448Y329585D02*
X1259755Y322500D01*
G01X1258524D02*
X1256909Y318253D01*
G01X1259755Y322500D02*
X1258054Y318026D01*
G01X1256909Y318253D02*
X1256865Y316696D01*
G01X1256810Y314653D02*
X1256800Y314300D01*
G01X1258054Y318026D02*
X1257951Y314300D01*
G01X1256810Y314653D02*
X1256800Y314300D01*
G01X1257951D02*
X1257345Y292399D01*
G01X1256236Y294044D02*
X1256150Y290815D01*
G01X1257343Y292400D02*
X1257295Y290592D01*
G01X1289301Y371535D02*
X1280182Y328592D01*
G01X1288125Y371535D02*
X1279002Y328572D01*
G01X1280183Y328589D02*
X1282688Y318344D01*
G01X1279003Y328572D02*
X1281508Y318326D01*
G01X1282688Y318344D02*
X1279862Y305043D01*
G01X1281508Y318326D02*
X1278686Y305043D01*
G01X1279862D02*
X1281080Y299307D01*
G01X1278686Y305043D02*
X1279904Y299307D01*
G01X1281080D02*
X1279826Y293397D01*
G01X1279904Y299307D02*
X1278650Y293397D01*
G01X1279826D02*
X1282001Y283160D01*
G01X1278650Y293397D02*
X1280825Y283160D01*
G01X1279435D02*
X1277260Y293397D01*
G01X1278259Y283160D02*
X1276084Y293397D01*
G01X1277260D02*
X1278514Y299307D01*
G01X1276084Y293397D02*
X1277338Y299307D01*
G01X1278514D02*
X1277296Y305043D01*
G01X1277338Y299307D02*
X1276120Y305043D01*
G01X1277296D02*
X1280117Y318318D01*
G01X1276120Y305043D02*
X1278937Y318300D01*
G01X1280117Y318318D02*
X1277537Y328867D01*
G01X1278937Y318300D02*
X1276357Y328849D01*
G01X1277537Y328867D02*
X1285980Y368635D01*
G01X1276357Y328849D02*
X1285362Y371262D01*
G01X1288125Y371535D02*
X1279002Y328572D01*
G01X1289301Y371535D02*
X1280182Y328592D01*
G01X1279003Y328572D02*
X1281508Y318326D01*
G01X1280183Y328589D02*
X1282688Y318344D01*
G01X1281508Y318326D02*
X1278686Y305043D01*
G01X1282688Y318344D02*
X1279862Y305043D01*
G01X1278686D02*
X1279904Y299307D01*
G01X1279862Y305043D02*
X1281080Y299307D01*
G01X1279904D02*
X1278650Y293397D01*
G01X1281080Y299307D02*
X1279826Y293397D01*
G01X1278650D02*
X1280825Y283160D01*
G01X1279826Y293397D02*
X1282001Y283160D01*
G01X1278259D02*
X1276084Y293397D01*
G01X1279435Y283160D02*
X1277260Y293397D01*
G01X1276084D02*
X1277338Y299307D01*
G01X1277260Y293397D02*
X1278514Y299307D01*
G01X1277338D02*
X1276120Y305043D01*
G01X1278514Y299307D02*
X1277296Y305043D01*
G01X1276120D02*
X1278937Y318300D01*
G01X1277296Y305043D02*
X1280117Y318318D01*
G01X1278937Y318300D02*
X1276357Y328849D01*
G01X1280117Y318318D02*
X1277537Y328867D01*
G01X1276357Y328849D02*
X1285362Y371262D01*
G01X1277537Y328867D02*
X1285980Y368635D01*
G01X1276357Y328849D02*
X1285362Y371262D01*
G01X1220814Y355814D02*
X1222549Y347772D01*
G01X1219102Y369200D02*
X1223746Y347682D01*
G01X1262446Y391091D02*
X1260190Y395190D01*
G01D02*
X1259616Y396234D01*
G01X1260534Y396952D02*
X1263574Y391427D01*
G01X1262745Y387139D02*
X1262446Y391091D01*
G01X1263574Y391427D02*
X1263904Y387066D01*
G01X1259093Y369200D02*
X1261686Y381936D01*
G01D02*
X1262745Y387139D01*
G01X1266377Y386627D02*
X1266434Y386907D01*
G01X1264908Y391824D02*
X1265275Y386980D01*
G01X1266434Y386907D02*
X1266036Y392160D01*
G01X1261614Y397811D02*
X1262039Y397039D01*
G01D02*
X1264908Y391824D01*
G01X1266036Y392160D02*
X1262886Y397886D01*
G01X1261614Y397811D02*
X1262039Y397039D01*
G01X1262886Y397886D02*
X1262532Y398529D01*
G01X1270377Y405101D02*
X1274117Y398304D01*
G01X1270377Y405101D02*
X1274117Y398304D01*
G01D02*
X1275884Y395092D01*
G01X1269600Y404127D02*
X1274117Y395917D01*
G01Y398304D02*
X1275884Y395092D01*
G01X1274117Y395917D02*
X1274756Y394756D01*
G01X1275884Y395092D02*
X1276554Y386271D01*
G01X1274756Y394756D02*
X1275395Y386344D01*
G01D02*
X1271904Y369200D01*
G01X1271401Y406062D02*
X1277218Y395489D01*
G01X1272319Y406780D02*
X1278346Y395825D01*
G01X1277217Y395489D02*
X1277925Y386184D01*
G01X1278346Y395825D02*
X1279084Y386112D01*
G01X1277925Y386184D02*
X1274466Y369200D01*
G01X1279084Y386112D02*
X1275640Y369200D01*
G01X1274466D02*
X1274117Y367486D01*
G01X1220493Y369200D02*
X1222926Y357926D01*
G01X1226512Y346762D02*
X1226608Y346316D01*
G01X1222926Y357926D02*
X1225411Y346406D01*
G01X1231091Y415408D02*
X1239835Y374835D01*
G01D02*
X1241049Y369200D01*
G01D02*
X1242450Y362700D01*
G01X1219102Y369200D02*
X1223746Y347682D01*
G01X1220814Y355814D02*
X1222549Y347772D01*
G01X1259093Y369200D02*
X1261686Y381936D01*
G01D02*
X1262745Y387139D01*
G01X1263574Y391427D02*
X1263904Y387066D01*
G01X1262745Y387139D02*
X1262446Y391091D01*
G01X1260534Y396952D02*
X1263574Y391427D01*
G01X1262446Y391091D02*
X1260190Y395190D01*
G01X1260534Y396952D02*
X1263574Y391427D01*
G01X1260190Y395190D02*
X1259616Y396234D01*
G01X1266036Y392160D02*
X1262886Y397886D01*
G01D02*
X1262532Y398529D01*
G01X1261614Y397811D02*
X1262039Y397039D01*
G01X1266036Y392160D02*
X1262886Y397886D01*
G01X1262039Y397039D02*
X1264908Y391824D01*
G01X1266434Y386907D02*
X1266036Y392160D01*
G01X1264908Y391824D02*
X1265275Y386980D01*
G01X1266377Y386627D02*
X1266434Y386907D01*
G01X1269600Y404127D02*
X1274117Y395917D01*
G01X1270377Y405101D02*
X1274117Y398304D01*
G01X1269600Y404127D02*
X1274117Y395917D01*
G01D02*
X1274756Y394756D01*
G01X1274117Y398304D02*
X1275884Y395092D01*
G01X1274756Y394756D02*
X1275395Y386344D01*
G01X1275884Y395092D02*
X1276554Y386271D01*
G01X1275395Y386344D02*
X1271904Y369200D01*
G01X1220493D02*
X1222926Y357926D01*
G01D02*
X1225411Y346406D01*
G01X1222926Y357926D02*
X1225411Y346406D01*
G01X1226512Y346762D02*
X1226608Y346316D01*
G01X1221944Y410185D02*
X1236386Y343180D01*
G01X1222992Y410783D02*
X1232353Y367353D01*
G01X1221944Y410185D02*
X1236386Y343180D01*
G01X1232353Y367353D02*
X1234969Y355219D01*
G01X1221944Y410185D02*
X1236386Y343180D01*
G01X1234969Y355219D02*
X1237583Y343089D01*
G01X1231091Y415408D02*
X1239835Y374835D01*
G01D02*
X1241049Y369200D01*
G01D02*
X1242450Y362700D01*
G01X1263622Y399368D02*
X1263887Y398887D01*
G01X1264540Y400086D02*
X1264734Y399734D01*
G01X1263622Y399368D02*
X1263887Y398887D01*
G01D02*
X1267370Y392557D01*
G01X1264734Y399734D02*
X1268498Y392893D01*
G01X1267370Y392557D02*
X1267600Y389524D01*
G01D02*
X1267718Y387968D01*
G01X1268498Y392893D02*
X1268790Y389040D01*
G01X1267600Y389524D02*
X1267718Y387968D01*
G01D02*
X1267805Y386821D01*
G01X1268790Y389040D02*
X1268964Y386748D01*
G01X1267805Y386821D02*
X1267600Y385814D01*
G01D02*
X1264217Y369200D01*
G01X1268964Y386748D02*
X1265391Y369200D01*
G01X1273391Y407652D02*
X1279680Y396222D01*
G01X1274309Y408370D02*
X1280808Y396558D01*
G01X1279680Y396222D02*
X1280455Y386026D01*
G01X1276154Y410225D02*
X1283270Y397291D01*
G01X1275236Y409507D02*
X1282142Y396955D01*
G01X1282294Y382476D02*
X1279589Y369200D01*
G01X1272319Y406780D02*
X1278346Y395825D01*
G01X1271401Y406062D02*
X1277218Y395489D01*
G01X1278346Y395825D02*
X1279084Y386112D01*
G01X1277217Y395489D02*
X1277925Y386184D01*
G01X1279084Y386112D02*
X1275640Y369200D01*
G01X1277925Y386184D02*
X1274466Y369200D01*
G01D02*
X1274117Y367486D01*
G01X1274309Y408370D02*
X1280808Y396558D01*
G01X1273391Y407652D02*
X1279680Y396222D01*
G01D02*
X1280455Y386026D01*
G01X1275236Y409507D02*
X1282142Y396955D01*
G01X1276154Y410225D02*
X1283270Y397291D01*
G01X1282294Y382476D02*
X1279589Y369200D01*
G01X1219631Y408902D02*
X1228196Y369200D01*
G01X1220680Y409500D02*
X1229373Y369200D01*
G01X1228196D02*
X1229261Y364261D01*
G01X1229373Y369200D02*
X1230230Y365230D01*
G01X1229261Y364261D02*
X1231878Y352128D01*
G01X1230230Y365230D02*
X1232847Y353097D01*
G01X1231878Y352128D02*
X1233655Y343892D01*
G01X1232847Y353097D02*
X1234852Y343802D01*
G01X1222992Y410783D02*
X1232353Y367353D01*
G01D02*
X1234969Y355219D01*
G01D02*
X1237583Y343089D01*
G01X1221944Y410185D02*
X1236386Y343180D01*
G01X1224230Y411490D02*
X1239110Y342455D01*
G01X1225278Y412088D02*
X1234466Y369466D01*
G01X1224230Y411490D02*
X1239110Y342455D01*
G01X1234466Y369466D02*
X1234523Y369200D01*
G01X1224230Y411490D02*
X1239110Y342455D01*
G01X1234523Y369200D02*
X1237081Y357331D01*
G01X1224230Y411490D02*
X1239110Y342455D01*
G01X1237081Y357331D02*
X1240307Y342364D01*
G01X1227566Y413392D02*
X1236578Y371578D01*
G01X1226518Y412794D02*
X1235609Y370609D01*
G01X1236578Y371578D02*
X1237091Y369200D01*
G01X1235609Y370609D02*
X1235913Y369200D01*
G01X1237091D02*
X1239194Y359444D01*
G01X1235913Y369200D02*
X1238225Y358475D01*
G01X1239194Y359444D02*
X1243031Y341638D01*
G01X1238225Y358475D02*
X1241834Y341729D01*
G01X1228806Y414097D02*
X1237723Y372723D01*
G01X1229854Y414695D02*
X1238692Y373692D01*
G01X1237723Y372723D02*
X1238482Y369200D01*
G01X1238692Y373692D02*
X1239660Y369200D01*
G01X1238482D02*
X1240338Y360588D01*
G01X1239660Y369200D02*
X1241307Y361557D01*
G01X1264540Y400086D02*
X1264734Y399734D01*
G01D02*
X1268498Y392893D01*
G01X1263622Y399368D02*
X1263887Y398887D01*
G01X1264734Y399734D02*
X1268498Y392893D01*
G01X1263887Y398887D02*
X1267370Y392557D01*
G01X1268498Y392893D02*
X1268790Y389040D01*
G01X1267370Y392557D02*
X1267600Y389524D01*
G01X1268498Y392893D02*
X1268790Y389040D01*
G01D02*
X1268964Y386748D01*
G01X1267600Y389524D02*
X1267718Y387968D01*
G01X1268790Y389040D02*
X1268964Y386748D01*
G01X1267718Y387968D02*
X1267805Y386821D01*
G01X1268964Y386748D02*
X1265391Y369200D01*
G01X1267805Y386821D02*
X1267600Y385814D01*
G01X1268964Y386748D02*
X1265391Y369200D01*
G01X1267600Y385814D02*
X1264217Y369200D01*
G01X1220680Y409500D02*
X1229373Y369200D01*
G01X1219631Y408902D02*
X1228196Y369200D01*
G01X1229373D02*
X1230230Y365230D01*
G01X1228196Y369200D02*
X1229261Y364261D01*
G01X1230230Y365230D02*
X1232847Y353097D01*
G01X1229261Y364261D02*
X1231878Y352128D01*
G01X1232847Y353097D02*
X1234852Y343802D01*
G01X1231878Y352128D02*
X1233655Y343892D01*
G01X1225278Y412088D02*
X1234466Y369466D01*
G01D02*
X1234523Y369200D01*
G01D02*
X1237081Y357331D01*
G01D02*
X1240307Y342364D01*
G01X1224230Y411490D02*
X1239110Y342455D01*
G01X1226518Y412794D02*
X1235609Y370609D01*
G01X1227566Y413392D02*
X1236578Y371578D01*
G01X1235609Y370609D02*
X1235913Y369200D01*
G01X1236578Y371578D02*
X1237091Y369200D01*
G01X1235913D02*
X1238225Y358475D01*
G01X1237091Y369200D02*
X1239194Y359444D01*
G01X1238225Y358475D02*
X1241834Y341729D01*
G01X1239194Y359444D02*
X1243031Y341638D01*
G01X1229854Y414695D02*
X1238692Y373692D01*
G01X1228806Y414097D02*
X1237723Y372723D01*
G01X1238692Y373692D02*
X1239660Y369200D01*
G01X1237723Y372723D02*
X1238482Y369200D01*
G01X1239660D02*
X1241307Y361557D01*
G01X1238482Y369200D02*
X1240338Y360588D01*
G01X1218797Y445778D02*
X1266542Y401656D01*
G01X1265624Y400938D02*
X1265735Y400735D01*
G01D02*
X1269600Y393712D01*
G01D02*
X1269832Y393290D01*
G01X1266582Y401582D02*
X1270865Y393799D01*
G01X1269831Y393290D02*
X1270335Y386662D01*
G01X1270960Y393626D02*
X1271494Y386589D01*
G01X1270335Y386662D02*
X1266779Y369200D01*
G01X1271494Y386589D02*
X1267953Y369200D01*
G01X1219457Y447021D02*
X1267569Y402569D01*
G01D02*
X1267600Y402541D01*
G01D02*
X1267615Y402527D01*
G01X1268533Y403245D02*
X1269600Y401306D01*
G01D02*
X1273422Y394359D01*
G01X1267615Y402527D02*
X1272294Y394023D01*
G01X1273422Y394359D02*
X1274024Y386430D01*
G01X1272294Y394023D02*
X1272865Y386503D01*
G01X1274024Y386430D02*
X1270865Y370919D01*
G01D02*
X1270515Y369200D01*
G01X1272865Y386503D02*
X1269341Y369200D01*
G01X1218797Y445778D02*
X1266542Y401656D01*
G01X1266582Y401582D02*
X1270865Y393799D01*
G01X1265624Y400938D02*
X1265735Y400735D01*
G01X1266582Y401582D02*
X1270865Y393799D01*
G01X1265735Y400735D02*
X1269600Y393712D01*
G01X1266582Y401582D02*
X1270865Y393799D01*
G01X1269600Y393712D02*
X1269832Y393290D01*
G01X1270960Y393626D02*
X1271494Y386589D01*
G01X1269831Y393290D02*
X1270335Y386662D01*
G01X1271494Y386589D02*
X1267953Y369200D01*
G01X1270335Y386662D02*
X1266779Y369200D01*
G01X1219457Y447021D02*
X1267569Y402569D01*
G01D02*
X1267600Y402541D01*
G01D02*
X1267615Y402527D01*
G01X1267569Y402569D02*
X1267600Y402541D01*
G01D02*
X1267615Y402527D01*
G01D02*
X1272294Y394023D01*
G01X1268533Y403245D02*
X1269600Y401306D01*
G01X1267615Y402527D02*
X1272294Y394023D01*
G01X1269600Y401306D02*
X1273422Y394359D01*
G01X1272294Y394023D02*
X1272865Y386503D01*
G01X1273422Y394359D02*
X1274024Y386430D01*
G01X1272865Y386503D02*
X1269341Y369200D01*
G01X1274024Y386430D02*
X1270865Y370919D01*
G01X1272865Y386503D02*
X1269341Y369200D01*
G01X1270865Y370919D02*
X1270515Y369200D01*
G01X1221422Y450328D02*
X1270234Y405234D01*
G01X1220867Y449274D02*
X1269419Y404419D01*
G01X1221422Y450328D02*
X1270234Y405234D01*
G01D02*
X1270377Y405101D01*
G01X1269419Y404419D02*
X1269459Y404383D01*
G01D02*
X1269600Y404127D01*
G01X1222177Y451551D02*
X1270865Y406558D01*
G01D02*
X1271225Y406225D01*
G01D02*
X1271401Y406062D01*
G01X1222732Y452605D02*
X1272039Y407039D01*
G01X1271225Y406225D02*
X1271401Y406062D01*
G01X1272039Y407039D02*
X1272319Y406780D01*
G01X1220867Y449274D02*
X1269419Y404419D01*
G01D02*
X1269459Y404383D01*
G01X1221422Y450328D02*
X1270234Y405234D01*
G01X1269419Y404419D02*
X1269459Y404383D01*
G01X1270234Y405234D02*
X1270377Y405101D01*
G01X1269459Y404383D02*
X1269600Y404127D01*
G01X1223389Y453849D02*
X1273391Y407652D01*
G01X1223944Y454903D02*
X1274309Y408370D01*
G01X1225357Y457154D02*
X1275671Y410671D01*
G01D02*
X1276154Y410225D01*
G01X1224802Y456100D02*
X1275236Y409507D01*
G01X1222732Y452605D02*
X1272039Y407039D01*
G01X1222177Y451551D02*
X1270865Y406558D01*
G01X1222732Y452605D02*
X1272039Y407039D01*
G01X1270865Y406558D02*
X1271225Y406225D01*
G01X1222732Y452605D02*
X1272039Y407039D01*
G01D02*
X1272319Y406780D01*
G01X1271225Y406225D02*
X1271401Y406062D01*
G01X1223944Y454903D02*
X1274309Y408370D01*
G01X1223389Y453849D02*
X1273391Y407652D01*
G01X1224802Y456100D02*
X1275236Y409507D01*
G01X1225357Y457154D02*
X1275671Y410671D01*
G01X1224802Y456100D02*
X1275236Y409507D01*
G01X1275671Y410671D02*
X1276154Y410225D01*
G01X1219632Y408902D02*
X1219631D01*
G01X1219632D02*
X1219631D01*
G01X1220012Y448075D02*
X1268383Y403383D01*
G01X1220012Y448075D02*
X1268383Y403383D01*
G01D02*
X1268533Y403245D01*
G01X1220012Y448075D02*
X1268383Y403383D01*
G01D02*
X1268533Y403245D01*
G01X1220012Y448075D02*
X1268383Y403383D01*
G01D02*
X1268533Y403245D01*
G01X1246049Y470427D02*
X1248491Y461588D01*
G01X1244831Y470517D02*
X1247291Y461613D01*
G01X1248491Y461588D02*
X1245548Y452423D01*
G01X1247291Y461613D02*
X1244309Y452328D01*
G01X1245548Y452423D02*
X1250414Y442728D01*
G01X1244308Y452328D02*
X1249480Y442025D01*
G01X1250414Y442728D02*
X1281471Y414037D01*
G01X1249480Y442025D02*
X1280553Y413319D01*
G01X1286907Y398666D02*
X1279180Y412710D01*
G01X1286907Y398666D02*
X1279180Y412710D01*
G01X1286907Y398666D02*
X1279180Y412710D01*
G01X1285300Y399200D02*
X1278262Y411992D01*
G01X1279180Y412710D02*
X1248107Y441417D01*
G01X1278262Y411992D02*
X1247173Y440714D01*
G01X1248107Y441418D02*
X1242603Y452379D01*
G01X1247173Y440714D02*
X1241453Y452106D01*
G01X1242603Y452379D02*
Y453729D01*
G01Y456379D02*
Y457729D01*
G01Y460379D02*
Y461729D01*
G01Y464379D02*
Y465729D01*
G01X1241453Y452106D02*
Y475576D01*
G01X1244831Y470517D02*
X1247291Y461613D01*
G01X1246049Y470427D02*
X1248491Y461588D01*
G01X1247291Y461613D02*
X1244309Y452328D01*
G01X1248491Y461588D02*
X1245548Y452423D01*
G01X1244308Y452328D02*
X1249480Y442025D01*
G01X1245548Y452423D02*
X1250414Y442728D01*
G01X1249480Y442025D02*
X1280553Y413319D01*
G01X1250414Y442728D02*
X1281471Y414037D01*
G01X1285300Y399200D02*
X1278262Y411992D01*
G01X1286907Y398666D02*
X1279180Y412710D01*
G01X1278262Y411992D02*
X1247173Y440714D01*
G01X1279180Y412710D02*
X1248107Y441417D01*
G01X1247173Y440714D02*
X1241453Y452106D01*
G01X1248107Y441418D02*
X1242603Y452379D01*
G01X1241453Y452106D02*
Y475576D01*
G01X1242603Y452379D02*
Y453729D01*
G01X1241453Y452106D02*
Y475576D01*
G01X1242603Y456379D02*
Y457729D01*
G01X1241453Y452106D02*
Y475576D01*
G01X1242603Y460379D02*
Y461729D01*
G01X1241453Y452106D02*
Y475576D01*
G01X1242603Y464379D02*
Y465729D01*
G01X1241453Y452106D02*
Y475576D01*
G01X1276634Y466555D02*
X1273589Y463510D01*
G01X1281813Y473361D02*
X1272439Y463987D01*
G01X1273589Y463510D02*
Y460448D01*
G01Y457798D02*
Y456448D01*
G01Y453798D02*
Y435420D01*
G01X1272439Y463987D02*
Y434916D01*
G01X1273589Y435420D02*
X1290724Y419588D01*
G01X1272439Y434916D02*
X1289806Y418870D01*
G01X1263150Y463587D02*
X1266692D01*
G01X1267169Y464737D02*
X1269695Y462211D01*
G01X1266692Y463587D02*
X1268545Y461734D01*
G01X1269695Y462211D02*
Y459603D01*
G01X1268545Y461734D02*
Y460080D01*
G01X1269695Y459603D02*
X1268572Y458480D01*
G01X1268545Y460080D02*
X1268095Y459630D01*
G01X1268572Y458480D02*
X1266384D01*
G01X1268095Y459630D02*
X1265907D01*
G01X1266384Y458480D02*
X1265934Y458030D01*
G01X1265907Y459630D02*
X1264784Y458507D01*
G01X1265934Y458030D02*
Y456980D01*
G01X1264784Y458507D02*
Y456503D01*
G01X1265934Y456980D02*
X1266384Y456530D01*
G01X1264784Y456503D02*
X1265907Y455380D01*
G01X1266384Y456530D02*
X1268572D01*
G01X1265907Y455380D02*
X1268095D01*
G01X1268572Y456530D02*
X1269695Y455407D01*
G01X1268095Y455380D02*
X1268545Y454930D01*
G01X1269695Y455407D02*
Y453403D01*
G01X1268545Y454930D02*
Y453880D01*
G01X1269695Y453403D02*
X1268572Y452280D01*
G01X1268545Y453880D02*
X1268095Y453430D01*
G01X1268572Y452280D02*
X1266384D01*
G01X1268095Y453430D02*
X1265907D01*
G01X1266384Y452280D02*
X1265934Y451830D01*
G01X1265907Y453430D02*
X1264784Y452307D01*
G01X1265934Y451830D02*
Y450780D01*
G01X1264784Y452307D02*
Y450303D01*
G01X1265934Y450780D02*
X1266384Y450330D01*
G01X1264784Y450303D02*
X1265907Y449180D01*
G01X1266384Y450330D02*
X1268572D01*
G01X1265907Y449180D02*
X1268095D01*
G01X1268572Y450330D02*
X1269695Y449207D01*
G01X1268095Y449180D02*
X1268545Y448730D01*
G01X1269695Y449207D02*
Y447203D01*
G01X1268545Y448730D02*
Y447680D01*
G01X1269695Y447203D02*
X1268572Y446080D01*
G01X1268545Y447680D02*
X1268095Y447230D01*
G01X1268572Y446080D02*
X1266384D01*
G01X1268095Y447230D02*
X1265907D01*
G01X1266384Y446080D02*
X1265934Y445630D01*
G01X1265907Y447230D02*
X1264784Y446107D01*
G01X1265934Y445630D02*
Y444580D01*
G01X1264784Y446107D02*
Y444103D01*
G01X1265934Y444580D02*
X1266384Y444130D01*
G01X1264784Y444103D02*
X1265907Y442980D01*
G01X1266384Y444130D02*
X1268572D01*
G01X1265907Y442980D02*
X1268095D01*
G01X1268572Y444130D02*
X1269695Y443007D01*
G01X1268095Y442980D02*
X1268545Y442530D01*
G01X1269695Y443007D02*
Y437137D01*
G01X1268545Y442530D02*
Y436864D01*
G01X1269695Y437137D02*
X1271310Y433920D01*
G01X1268545Y436864D02*
X1270376Y433217D01*
G01X1271310Y433920D02*
X1288704Y417851D01*
G01X1270376Y433217D02*
X1287785Y417133D01*
G01X1271310Y433920D02*
X1288704Y417851D01*
G01X1252400Y466592D02*
X1253813Y461478D01*
G01X1251250Y466436D02*
X1252613Y461503D01*
G01X1253814Y461478D02*
X1251126Y453122D01*
G01X1252613Y461503D02*
X1249887Y453026D01*
G01X1251126Y453122D02*
X1254878Y445646D01*
G01X1249887Y453026D02*
X1253944Y444943D01*
G01X1254878Y445646D02*
X1285980Y416912D01*
G01X1253944Y444943D02*
X1285252Y416018D01*
G01X1248750Y470229D02*
X1251153Y461533D01*
G01X1247532Y470319D02*
X1249952Y461558D01*
G01X1251153Y461533D02*
X1248336Y452774D01*
G01X1249952Y461558D02*
X1247243Y453132D01*
G01X1251153Y461533D02*
X1248336Y452774D01*
G01X1247241Y453126D02*
X1247097Y452678D01*
G01X1248336Y452774D02*
X1252708Y444063D01*
G01X1247100Y452672D02*
X1251569Y443767D01*
G01X1252708Y444062D02*
X1284093Y415067D01*
G01X1251579Y443538D02*
X1283175Y414349D01*
G01X1285644Y468635D02*
X1279075Y462066D01*
G01X1285167Y469785D02*
X1277925Y462543D01*
G01X1279075Y462066D02*
Y434148D01*
G01X1277925Y462543D02*
Y433644D01*
G01X1279075Y434148D02*
X1292677Y421588D01*
G01X1277925Y433644D02*
X1291759Y420869D01*
G01X1279075Y434148D02*
X1292677Y421588D01*
G01X1281813Y473361D02*
X1272439Y463987D01*
G01X1281813Y473361D02*
X1272439Y463987D01*
G01X1281813Y473361D02*
X1272439Y463987D01*
G01X1276634Y466555D02*
X1273589Y463510D01*
G01X1272439Y463987D02*
Y434916D01*
G01X1273589Y463510D02*
Y460448D01*
G01X1272439Y463987D02*
Y434916D01*
G01X1273589Y457798D02*
Y456448D01*
G01X1272439Y463987D02*
Y434916D01*
G01X1273589Y453798D02*
Y435420D01*
G01X1272439Y434916D02*
X1289806Y418870D01*
G01X1273589Y435420D02*
X1290724Y419588D01*
G01X1263150Y463587D02*
X1266692D01*
G01D02*
X1268545Y461734D01*
G01X1267169Y464737D02*
X1269695Y462211D01*
G01X1268545Y461734D02*
Y460080D01*
G01X1269695Y462211D02*
Y459603D01*
G01X1268545Y460080D02*
X1268095Y459630D01*
G01X1269695Y459603D02*
X1268572Y458480D01*
G01X1268095Y459630D02*
X1265907D01*
G01X1268572Y458480D02*
X1266384D01*
G01X1265907Y459630D02*
X1264784Y458507D01*
G01X1266384Y458480D02*
X1265934Y458030D01*
G01X1264784Y458507D02*
Y456503D01*
G01X1265934Y458030D02*
Y456980D01*
G01X1264784Y456503D02*
X1265907Y455380D01*
G01X1265934Y456980D02*
X1266384Y456530D01*
G01X1265907Y455380D02*
X1268095D01*
G01X1266384Y456530D02*
X1268572D01*
G01X1268095Y455380D02*
X1268545Y454930D01*
G01X1268572Y456530D02*
X1269695Y455407D01*
G01X1268545Y454930D02*
Y453880D01*
G01X1269695Y455407D02*
Y453403D01*
G01X1268545Y453880D02*
X1268095Y453430D01*
G01X1269695Y453403D02*
X1268572Y452280D01*
G01X1268095Y453430D02*
X1265907D01*
G01X1268572Y452280D02*
X1266384D01*
G01X1265907Y453430D02*
X1264784Y452307D01*
G01X1266384Y452280D02*
X1265934Y451830D01*
G01X1264784Y452307D02*
Y450303D01*
G01X1265934Y451830D02*
Y450780D01*
G01X1264784Y450303D02*
X1265907Y449180D01*
G01X1265934Y450780D02*
X1266384Y450330D01*
G01X1265907Y449180D02*
X1268095D01*
G01X1266384Y450330D02*
X1268572D01*
G01X1268095Y449180D02*
X1268545Y448730D01*
G01X1268572Y450330D02*
X1269695Y449207D01*
G01X1268545Y448730D02*
Y447680D01*
G01X1269695Y449207D02*
Y447203D01*
G01X1268545Y447680D02*
X1268095Y447230D01*
G01X1269695Y447203D02*
X1268572Y446080D01*
G01X1268095Y447230D02*
X1265907D01*
G01X1268572Y446080D02*
X1266384D01*
G01X1265907Y447230D02*
X1264784Y446107D01*
G01X1266384Y446080D02*
X1265934Y445630D01*
G01X1264784Y446107D02*
Y444103D01*
G01X1265934Y445630D02*
Y444580D01*
G01X1264784Y444103D02*
X1265907Y442980D01*
G01X1265934Y444580D02*
X1266384Y444130D01*
G01X1265907Y442980D02*
X1268095D01*
G01X1266384Y444130D02*
X1268572D01*
G01X1268095Y442980D02*
X1268545Y442530D01*
G01X1268572Y444130D02*
X1269695Y443007D01*
G01X1268545Y442530D02*
Y436864D01*
G01X1269695Y443007D02*
Y437137D01*
G01X1268545Y436864D02*
X1270376Y433217D01*
G01X1269695Y437137D02*
X1271310Y433920D01*
G01X1270376Y433217D02*
X1287785Y417133D01*
G01X1271310Y433920D02*
X1288704Y417851D01*
G01X1251250Y466436D02*
X1252613Y461503D01*
G01X1252400Y466592D02*
X1253813Y461478D01*
G01X1252613Y461503D02*
X1249887Y453026D01*
G01X1253814Y461478D02*
X1251126Y453122D01*
G01X1249887Y453026D02*
X1253944Y444943D01*
G01X1251126Y453122D02*
X1254878Y445646D01*
G01X1253944Y444943D02*
X1285252Y416018D01*
G01X1254878Y445646D02*
X1285980Y416912D01*
G01X1253944Y444943D02*
X1285252Y416018D01*
G01X1247532Y470319D02*
X1249952Y461558D01*
G01X1248750Y470229D02*
X1251153Y461533D01*
G01X1249952Y461558D02*
X1247243Y453132D01*
G01X1247241Y453126D02*
X1247097Y452678D01*
G01X1251153Y461533D02*
X1248336Y452774D01*
G01X1247100Y452672D02*
X1251569Y443767D01*
G01X1248336Y452774D02*
X1252708Y444063D01*
G01X1251579Y443538D02*
X1283175Y414349D01*
G01X1252708Y444062D02*
X1284093Y415067D01*
G01X1285167Y469785D02*
X1277925Y462543D01*
G01X1285644Y468635D02*
X1279075Y462066D01*
G01X1277925Y462543D02*
Y433644D01*
G01X1279075Y462066D02*
Y434148D01*
G01X1277925Y433644D02*
X1291759Y420869D01*
G01X1279075Y434148D02*
X1292677Y421588D01*
G01X1272289Y507300D02*
X1272739Y506850D01*
G01X1272766Y508450D02*
X1273216Y508000D01*
G01X1272739Y506850D02*
X1276564D01*
G01X1273216Y508000D02*
X1276718D01*
G01X1276564Y506850D02*
X1294145Y502070D01*
G01X1276718Y508000D02*
X1294593Y503140D01*
G01X1272766Y508450D02*
X1273216Y508000D01*
G01X1272289Y507300D02*
X1272739Y506850D01*
G01X1273216Y508000D02*
X1276718D01*
G01X1272739Y506850D02*
X1276564D01*
G01X1276718Y508000D02*
X1294593Y503140D01*
G01X1276564Y506850D02*
X1294145Y502070D01*
G01X1270226Y483798D02*
X1269556Y483128D01*
G01X1269749Y484948D02*
X1269079Y484278D01*
G01X1269556Y483128D02*
X1265899D01*
G01X1269079Y484278D02*
X1265737D01*
G01X1265899Y483128D02*
X1251633Y479051D01*
G01X1265737Y484278D02*
X1251101Y480096D01*
G01X1251633Y479051D02*
X1248929Y476935D01*
G01X1251101Y480096D02*
X1247993Y477664D01*
G01X1248929Y476935D02*
X1246049Y470427D01*
G01X1247993Y477664D02*
X1244831Y470517D01*
G01X1242603Y468379D02*
Y475220D01*
G01D02*
X1243366Y476334D01*
G01X1244863Y478521D02*
X1245626Y479635D01*
G01X1247123Y481822D02*
X1249759Y485673D01*
G01X1241453Y475576D02*
X1248930Y486498D01*
G01X1249759Y485673D02*
X1252921Y487860D01*
G01X1248930Y486498D02*
X1252562Y489010D01*
G01X1252921Y487860D02*
X1255700D01*
G01X1252562Y489010D02*
X1255210D01*
G01X1269749Y484948D02*
X1269079Y484278D01*
G01X1270226Y483798D02*
X1269556Y483128D01*
G01X1269079Y484278D02*
X1265737D01*
G01X1269556Y483128D02*
X1265899D01*
G01X1265737Y484278D02*
X1251101Y480096D01*
G01X1265899Y483128D02*
X1251633Y479051D01*
G01X1251101Y480096D02*
X1247993Y477664D01*
G01X1251633Y479051D02*
X1248929Y476935D01*
G01X1247993Y477664D02*
X1244831Y470517D01*
G01X1248929Y476935D02*
X1246049Y470427D01*
G01X1242603Y468379D02*
Y475220D01*
G01X1241453Y475576D02*
X1248930Y486498D01*
G01X1242603Y475220D02*
X1243366Y476334D01*
G01X1241453Y475576D02*
X1248930Y486498D01*
G01X1244863Y478521D02*
X1245626Y479635D01*
G01X1241453Y475576D02*
X1248930Y486498D01*
G01X1247123Y481822D02*
X1249759Y485673D01*
G01X1248930Y486498D02*
X1252562Y489010D01*
G01X1249759Y485673D02*
X1252921Y487860D01*
G01X1252562Y489010D02*
X1255210D01*
G01X1252921Y487860D02*
X1255700D01*
G01X1279462Y469383D02*
X1278507Y468428D01*
G01X1263350Y464737D02*
X1267169D01*
G01X1257105Y471475D02*
X1253902D01*
G01X1257315Y472625D02*
X1253425D01*
G01X1253902Y471475D02*
X1252400Y469973D01*
G01X1253425Y472625D02*
X1251250Y470450D01*
G01X1252400Y469973D02*
Y466592D01*
G01X1251250Y470450D02*
Y466436D01*
G01X1270008Y476052D02*
X1267551D01*
G01X1269773Y477202D02*
X1267712D01*
G01X1267551Y476052D02*
X1260429Y478075D01*
G01X1267712Y477202D02*
X1260488Y479254D01*
G01X1260429Y478075D02*
X1252974Y476746D01*
G01X1260488Y479254D02*
X1252490Y477828D01*
G01X1252974Y476746D02*
X1250925Y475141D01*
G01X1252490Y477828D02*
X1249989Y475870D01*
G01X1250925Y475141D02*
X1248750Y470229D01*
G01X1249989Y475870D02*
X1247532Y470319D01*
G01X1279462Y469383D02*
X1278507Y468428D01*
G01X1263350Y464737D02*
X1267169D01*
G01X1257315Y472625D02*
X1253425D01*
G01X1257105Y471475D02*
X1253902D01*
G01X1253425Y472625D02*
X1251250Y470450D01*
G01X1253902Y471475D02*
X1252400Y469973D01*
G01X1251250Y470450D02*
Y466436D01*
G01X1252400Y469973D02*
Y466592D01*
G01X1269773Y477202D02*
X1267712D01*
G01X1270008Y476052D02*
X1267551D01*
G01X1267712Y477202D02*
X1260488Y479254D01*
G01X1267551Y476052D02*
X1260429Y478075D01*
G01X1260488Y479254D02*
X1252490Y477828D01*
G01X1260429Y478075D02*
X1252974Y476746D01*
G01X1252490Y477828D02*
X1249989Y475870D01*
G01X1252974Y476746D02*
X1250925Y475141D01*
G01X1249989Y475870D02*
X1247532Y470319D01*
G01X1250925Y475141D02*
X1248750Y470229D01*
G01X1267665Y649509D02*
X1266599Y648699D01*
G01D02*
X1265753D01*
G01X1267665Y649509D02*
X1266599Y648699D01*
G01X1266211Y649849D02*
X1266841Y650328D01*
G01X1268662Y650838D02*
X1267665Y649509D01*
G01X1269670Y644932D02*
X1271154Y653339D01*
G01X1272370Y653608D02*
X1270886Y645202D01*
G01X1270583Y643628D02*
X1269670Y644932D01*
G01X1270886Y645202D02*
X1271253Y644678D01*
G01X1273856Y644189D02*
X1272556Y643279D01*
G01D02*
X1270583Y643628D01*
G01X1271253Y644678D02*
X1272287Y644495D01*
G01X1273856Y644189D02*
X1272556Y643279D01*
G01X1272287Y644495D02*
X1272806Y644858D01*
G01X1275541Y653739D02*
X1273856Y644189D01*
G01X1272806Y644858D02*
X1274490Y654408D01*
G01X1275969Y644947D02*
X1277461Y653401D01*
G01X1278677Y653669D02*
X1277185Y645216D01*
G01X1276879Y643644D02*
X1275969Y644947D01*
G01X1277185Y645216D02*
X1277549Y644695D01*
G01X1280157Y644208D02*
X1278853Y643298D01*
G01D02*
X1276879Y643644D01*
G01X1277549Y644695D02*
X1278584Y644513D01*
G01X1280157Y644208D02*
X1278853Y643298D01*
G01X1278584Y644513D02*
X1279107Y644878D01*
G01X1281836Y653742D02*
X1280157Y644208D01*
G01X1279107Y644878D02*
X1280785Y654412D01*
G01X1279107Y644878D02*
X1280785Y654412D01*
G01X1281836Y653742D02*
X1280157Y644208D01*
G01X1277549Y644695D02*
X1278584Y644513D01*
G01D02*
X1279107Y644878D01*
G01X1280157Y644208D02*
X1278853Y643298D01*
G01X1277549Y644695D02*
X1278584Y644513D01*
G01X1278853Y643298D02*
X1276879Y643644D01*
G01X1277185Y645216D02*
X1277549Y644695D01*
G01X1276879Y643644D02*
X1275969Y644947D01*
G01X1278677Y653669D02*
X1277185Y645216D01*
G01X1275969Y644947D02*
X1277461Y653401D01*
G01X1272806Y644858D02*
X1274490Y654408D01*
G01X1275541Y653739D02*
X1273856Y644189D01*
G01X1271253Y644678D02*
X1272287Y644495D01*
G01D02*
X1272806Y644858D01*
G01X1273856Y644189D02*
X1272556Y643279D01*
G01X1271253Y644678D02*
X1272287Y644495D01*
G01X1272556Y643279D02*
X1270583Y643628D01*
G01X1270886Y645202D02*
X1271253Y644678D01*
G01X1270583Y643628D02*
X1269670Y644932D01*
G01X1272370Y653608D02*
X1270886Y645202D01*
G01X1269670Y644932D02*
X1271154Y653339D01*
G01X1268662Y650838D02*
X1267665Y649509D01*
G01X1266211Y649849D02*
X1266841Y650328D01*
G01X1267665Y649509D02*
X1266599Y648699D01*
G01D02*
X1265753D01*
G01X1265733Y649849D02*
X1266211D01*
G01X1266841Y650328D02*
X1267603Y651344D01*
G01X1268898Y651768D02*
X1268662Y650838D01*
G01X1267603Y651344D02*
X1267772Y652010D01*
G01X1269234Y653678D02*
X1268898Y651768D01*
G01X1267772Y652010D02*
X1268184Y654347D01*
G01X1270789Y653861D02*
X1269755Y654043D01*
G01D02*
X1269234Y653678D01*
G01X1268184Y654347D02*
X1269485Y655259D01*
G01X1270789Y653861D02*
X1269755Y654043D01*
G01X1269485Y655259D02*
X1271459Y654912D01*
G01X1271154Y653339D02*
X1270789Y653861D01*
G01X1271459Y654912D02*
X1272370Y653608D01*
G01X1277097Y653924D02*
X1276064Y654106D01*
G01D02*
X1275541Y653739D01*
G01X1274490Y654408D02*
X1275794Y655322D01*
G01X1277097Y653924D02*
X1276064Y654106D01*
G01X1275794Y655322D02*
X1277768Y654974D01*
G01X1277461Y653401D02*
X1277097Y653924D01*
G01X1277768Y654974D02*
X1278677Y653669D01*
G01X1277768Y654974D02*
X1278677Y653669D01*
G01X1277461Y653401D02*
X1277097Y653924D01*
G01X1274490Y654408D02*
X1275794Y655322D01*
G01D02*
X1277768Y654974D01*
G01X1277097Y653924D02*
X1276064Y654106D01*
G01X1274490Y654408D02*
X1275794Y655322D01*
G01X1276064Y654106D02*
X1275541Y653739D01*
G01X1271459Y654912D02*
X1272370Y653608D01*
G01X1271154Y653339D02*
X1270789Y653861D01*
G01X1268184Y654347D02*
X1269485Y655259D01*
G01D02*
X1271459Y654912D01*
G01X1270789Y653861D02*
X1269755Y654043D01*
G01X1268184Y654347D02*
X1269485Y655259D01*
G01X1269755Y654043D02*
X1269234Y653678D01*
G01X1267772Y652010D02*
X1268184Y654347D01*
G01X1269234Y653678D02*
X1268898Y651768D01*
G01X1267603Y651344D02*
X1267772Y652010D01*
G01X1268898Y651768D02*
X1268662Y650838D01*
G01X1266841Y650328D02*
X1267603Y651344D01*
G01X1265733Y649849D02*
X1266211D01*
G01X1265733D02*
X1266211D01*
G01X1286434Y225831D02*
X1293908Y205874D01*
G01X1285241Y225735D02*
X1292953Y205144D01*
G01X1293908Y205874D02*
X1314240Y191245D01*
G01X1292953Y205144D02*
X1313769Y190167D01*
G01X1314240Y191245D02*
X1331986Y187636D01*
G01X1313769Y190167D02*
X1331986Y186462D01*
G01Y187636D02*
X1341756Y189622D01*
G01X1331986Y186462D02*
X1341720Y188441D01*
G01X1341756Y189622D02*
X1401121Y173708D01*
G01X1341720Y188441D02*
X1400645Y172644D01*
G01X1400061Y171355D02*
X1341891Y186944D01*
G01X1399585Y170291D02*
X1341855Y185763D01*
G01X1341891Y186944D02*
X1331990Y184930D01*
G01X1341855Y185763D02*
X1331990Y183756D01*
G01Y184930D02*
X1312928Y188809D01*
G01X1331990Y183756D02*
X1312457Y187731D01*
G01X1312928Y188809D02*
X1291886Y203946D01*
G01X1312457Y187731D02*
X1291045Y203134D01*
G01X1291886Y203946D02*
X1289092Y208135D01*
G01X1287622Y210341D02*
X1286873Y211464D01*
G01X1285403Y213668D02*
X1285300Y213822D01*
G01D02*
X1284654Y214791D01*
G01X1283184Y216996D02*
X1282435Y218119D01*
G01X1291045Y203134D02*
X1281380Y217626D01*
G01X1285241Y225735D02*
X1292953Y205144D01*
G01X1286434Y225831D02*
X1293908Y205874D01*
G01X1292953Y205144D02*
X1313769Y190167D01*
G01X1293908Y205874D02*
X1314240Y191245D01*
G01X1313769Y190167D02*
X1331986Y186462D01*
G01X1314240Y191245D02*
X1331986Y187636D01*
G01Y186462D02*
X1341720Y188441D01*
G01X1331986Y187636D02*
X1341756Y189622D01*
G01X1341720Y188441D02*
X1400645Y172644D01*
G01X1341756Y189622D02*
X1401121Y173708D01*
G01X1399585Y170291D02*
X1341855Y185763D01*
G01X1400061Y171355D02*
X1341891Y186944D01*
G01X1341855Y185763D02*
X1331990Y183756D01*
G01X1341891Y186944D02*
X1331990Y184930D01*
G01Y183756D02*
X1312457Y187731D01*
G01X1331990Y184930D02*
X1312928Y188809D01*
G01X1312457Y187731D02*
X1291045Y203134D01*
G01X1312928Y188809D02*
X1291886Y203946D01*
G01X1291045Y203134D02*
X1281380Y217626D01*
G01X1291886Y203946D02*
X1289092Y208135D01*
G01X1291045Y203134D02*
X1281380Y217626D01*
G01X1287622Y210341D02*
X1286873Y211464D01*
G01X1291045Y203134D02*
X1281380Y217626D01*
G01X1285403Y213668D02*
X1285300Y213822D01*
G01X1291045Y203134D02*
X1281380Y217626D01*
G01X1285300Y213822D02*
X1284654Y214791D01*
G01X1291045Y203134D02*
X1281380Y217626D01*
G01X1283184Y216996D02*
X1282435Y218119D01*
G01X1304980Y218072D02*
X1305623Y216885D01*
G01X1306886Y214555D02*
X1307529Y213368D01*
G01X1308792Y211039D02*
X1309435Y209852D01*
G01X1310698Y207522D02*
X1311341Y206335D01*
G01X1300969Y223058D02*
X1310455Y205555D01*
G01X1311341Y206335D02*
X1318477Y201202D01*
G01X1310455Y205555D02*
X1318006Y200124D01*
G01X1318477Y201202D02*
X1331989Y198452D01*
G01X1318006Y200124D02*
X1331989Y197278D01*
G01Y198452D02*
X1341009Y200286D01*
G01X1331989Y197278D02*
X1340973Y199105D01*
G01X1341009Y200286D02*
X1405581Y182977D01*
G01X1340973Y199105D02*
X1405105Y181913D01*
G01X1301358Y219192D02*
X1300909Y217668D01*
G01D02*
X1299267Y216778D01*
G01X1299940Y218452D02*
X1298300Y217562D01*
G01X1299267Y216778D02*
X1299086Y216169D01*
G01X1298300Y217562D02*
X1297847Y216040D01*
G01X1299086Y216169D02*
X1299587Y215244D01*
G01X1297847Y216040D02*
X1298802Y214277D01*
G01X1299587Y215244D02*
X1300196Y215063D01*
G01X1298802Y214277D02*
X1300325Y213824D01*
G01X1300196Y215063D02*
X1300567Y215264D01*
G01Y215263D02*
X1301778Y215920D01*
G01X1300325Y213824D02*
X1301907Y214681D01*
G01X1301778Y215920D02*
X1303367Y215447D01*
G01X1301907Y214681D02*
X1302583Y214480D01*
G01X1303367Y215447D02*
X1304325Y213680D01*
G01X1302583Y214480D02*
X1303086Y213552D01*
G01X1304325Y213680D02*
X1303811Y211957D01*
G01X1303086Y213552D02*
X1302844Y212742D01*
G01X1303811Y211957D02*
X1302936Y211483D01*
G01X1302935Y211482D02*
X1302059Y211007D01*
G01X1302844Y212742D02*
X1301092Y211791D01*
G01X1302059Y211007D02*
X1301878Y210398D01*
G01X1301092Y211791D02*
X1300639Y210269D01*
G01X1301878Y210398D02*
X1302379Y209473D01*
G01X1300639Y210269D02*
X1301594Y208506D01*
G01X1302379Y209473D02*
X1302988Y209292D01*
G01X1301594Y208506D02*
X1303117Y208053D01*
G01X1302988Y209292D02*
X1303510Y209575D01*
G01Y209574D02*
X1304871Y210312D01*
G01X1303117Y208053D02*
X1305001Y209074D01*
G01X1304871Y210312D02*
X1306393Y209862D01*
G01X1305001Y209074D02*
X1305609Y208894D01*
G01X1306393Y209862D02*
X1309276Y204543D01*
G01X1305609Y208894D02*
X1308264Y203995D01*
G01X1306393Y209862D02*
X1309276Y204543D01*
G01X1308264Y203995D02*
X1308390Y203762D01*
G01X1309277Y204541D02*
X1313322Y201632D01*
G01D02*
X1313323D01*
G01D02*
X1317368Y198722D01*
G01X1308390Y203762D02*
X1316897Y197644D01*
G01X1317368Y198722D02*
X1331990Y195747D01*
G01X1316897Y197644D02*
X1331990Y194573D01*
G01Y195747D02*
X1341215Y197624D01*
G01X1331990Y194573D02*
X1341179Y196443D01*
G01X1341215Y197624D02*
X1404429Y180683D01*
G01X1341179Y196443D02*
X1403953Y179619D01*
G01X1292862Y225106D02*
X1299053Y208626D01*
G01X1291669Y225009D02*
X1298098Y207895D01*
G01X1299053Y208626D02*
X1299665Y208186D01*
G01D02*
X1316259Y196245D01*
G01X1298098Y207895D02*
X1315973Y195032D01*
G01X1316261Y196243D02*
X1322631Y194948D01*
G01X1315973Y195032D02*
X1316236Y195074D01*
G01X1316261Y196243D02*
X1322631Y194948D01*
G01D02*
X1331996Y193044D01*
G01X1316236Y195074D02*
X1331994Y191869D01*
G01X1331996Y193044D02*
X1341355Y194949D01*
G01X1331994Y191869D02*
X1341319Y193768D01*
G01X1341355Y194949D02*
X1403382Y178324D01*
G01X1341319Y193768D02*
X1402906Y177260D01*
G01X1292692Y216394D02*
X1293165Y215130D01*
G01X1294094Y212648D02*
X1294567Y211384D01*
G01X1288765Y223597D02*
X1294419Y208500D01*
G01X1295502Y208887D02*
X1296009Y207534D01*
G01X1294425Y208482D02*
X1295054Y206804D01*
G01X1296009Y207534D02*
X1315148Y193767D01*
G01X1295054Y206804D02*
X1314677Y192689D01*
G01X1315148Y193767D02*
X1331990Y190339D01*
G01X1314677Y192689D02*
X1331990Y189165D01*
G01Y190339D02*
X1341588Y192292D01*
G01X1331990Y189165D02*
X1341552Y191111D01*
G01X1341588Y192292D02*
X1402201Y176047D01*
G01X1341552Y191111D02*
X1401725Y174983D01*
G01X1303695Y228517D02*
X1309883Y217099D01*
G01X1311146Y214769D02*
X1311789Y213582D01*
G01X1313052Y211252D02*
X1313695Y210065D01*
G01X1314958Y207735D02*
X1315601Y206548D01*
G01X1302602Y228120D02*
X1314715Y205768D01*
G01X1315601Y206548D02*
X1319590Y203678D01*
G01X1314715Y205768D02*
X1319119Y202600D01*
G01X1319590Y203678D02*
X1331990Y201155D01*
G01X1319119Y202600D02*
X1331990Y199981D01*
G01Y201155D02*
X1340849Y202958D01*
G01X1331990Y199981D02*
X1340813Y201777D01*
G01X1340849Y202958D02*
X1406671Y185312D01*
G01X1340813Y201777D02*
X1406193Y184249D01*
G01X1340849Y202958D02*
X1406671Y185312D01*
G01X1300969Y223058D02*
X1310455Y205555D01*
G01X1300969Y223058D02*
X1310455Y205555D01*
G01X1304980Y218072D02*
X1305623Y216885D01*
G01X1300969Y223058D02*
X1310455Y205555D01*
G01X1306886Y214555D02*
X1307529Y213368D01*
G01X1300969Y223058D02*
X1310455Y205555D01*
G01X1308792Y211039D02*
X1309435Y209852D01*
G01X1300969Y223058D02*
X1310455Y205555D01*
G01X1310698Y207522D02*
X1311341Y206335D01*
G01X1310455Y205555D02*
X1318006Y200124D01*
G01X1311341Y206335D02*
X1318477Y201202D01*
G01X1318006Y200124D02*
X1331989Y197278D01*
G01X1318477Y201202D02*
X1331989Y198452D01*
G01Y197278D02*
X1340973Y199105D01*
G01X1331989Y198452D02*
X1341009Y200286D01*
G01X1340973Y199105D02*
X1405105Y181913D01*
G01X1341009Y200286D02*
X1405581Y182977D01*
G01X1301358Y219192D02*
X1300909Y217668D01*
G01X1299940Y218452D02*
X1298300Y217562D01*
G01X1300909Y217668D02*
X1299267Y216778D01*
G01X1298300Y217562D02*
X1297847Y216040D01*
G01X1299267Y216778D02*
X1299086Y216169D01*
G01X1297847Y216040D02*
X1298802Y214277D01*
G01X1299086Y216169D02*
X1299587Y215244D01*
G01X1298802Y214277D02*
X1300325Y213824D01*
G01X1299587Y215244D02*
X1300196Y215063D01*
G01X1300325Y213824D02*
X1301907Y214681D01*
G01X1300196Y215063D02*
X1300567Y215264D01*
G01X1300325Y213824D02*
X1301907Y214681D01*
G01X1300567Y215263D02*
X1301778Y215920D01*
G01X1301907Y214681D02*
X1302583Y214480D01*
G01X1301778Y215920D02*
X1303367Y215447D01*
G01X1302583Y214480D02*
X1303086Y213552D01*
G01X1303367Y215447D02*
X1304325Y213680D01*
G01X1303086Y213552D02*
X1302844Y212742D01*
G01X1304325Y213680D02*
X1303811Y211957D01*
G01X1302844Y212742D02*
X1301092Y211791D01*
G01X1303811Y211957D02*
X1302936Y211483D01*
G01X1302844Y212742D02*
X1301092Y211791D01*
G01X1302935Y211482D02*
X1302059Y211007D01*
G01X1301092Y211791D02*
X1300639Y210269D01*
G01X1302059Y211007D02*
X1301878Y210398D01*
G01X1300639Y210269D02*
X1301594Y208506D01*
G01X1301878Y210398D02*
X1302379Y209473D01*
G01X1301594Y208506D02*
X1303117Y208053D01*
G01X1302379Y209473D02*
X1302988Y209292D01*
G01X1303117Y208053D02*
X1305001Y209074D01*
G01X1302988Y209292D02*
X1303510Y209575D01*
G01X1303117Y208053D02*
X1305001Y209074D01*
G01X1303510Y209574D02*
X1304871Y210312D01*
G01X1305001Y209074D02*
X1305609Y208894D01*
G01X1304871Y210312D02*
X1306393Y209862D01*
G01X1305609Y208894D02*
X1308264Y203995D01*
G01D02*
X1308390Y203762D01*
G01X1306393Y209862D02*
X1309276Y204543D01*
G01X1308390Y203762D02*
X1316897Y197644D01*
G01X1309277Y204541D02*
X1313322Y201632D01*
G01X1308390Y203762D02*
X1316897Y197644D01*
G01X1313322Y201632D02*
X1313323D01*
G01X1308390Y203762D02*
X1316897Y197644D01*
G01X1313323Y201632D02*
X1317368Y198722D01*
G01X1316897Y197644D02*
X1331990Y194573D01*
G01X1317368Y198722D02*
X1331990Y195747D01*
G01Y194573D02*
X1341179Y196443D01*
G01X1331990Y195747D02*
X1341215Y197624D01*
G01X1341179Y196443D02*
X1403953Y179619D01*
G01X1341215Y197624D02*
X1404429Y180683D01*
G01X1291669Y225009D02*
X1298098Y207895D01*
G01X1292862Y225106D02*
X1299053Y208626D01*
G01X1298098Y207895D02*
X1315973Y195032D01*
G01X1299053Y208626D02*
X1299665Y208186D01*
G01X1298098Y207895D02*
X1315973Y195032D01*
G01X1299665Y208186D02*
X1316259Y196245D01*
G01X1315973Y195032D02*
X1316236Y195074D01*
G01D02*
X1331994Y191869D01*
G01X1316261Y196243D02*
X1322631Y194948D01*
G01X1316236Y195074D02*
X1331994Y191869D01*
G01X1322631Y194948D02*
X1331996Y193044D01*
G01X1331994Y191869D02*
X1341319Y193768D01*
G01X1331996Y193044D02*
X1341355Y194949D01*
G01X1341319Y193768D02*
X1402906Y177260D01*
G01X1341355Y194949D02*
X1403382Y178324D01*
G01X1288765Y223597D02*
X1294419Y208500D01*
G01X1288765Y223597D02*
X1294419Y208500D01*
G01X1292692Y216394D02*
X1293165Y215130D01*
G01X1288765Y223597D02*
X1294419Y208500D01*
G01X1294094Y212648D02*
X1294567Y211384D01*
G01X1294425Y208482D02*
X1295054Y206804D01*
G01X1295502Y208887D02*
X1296009Y207534D01*
G01X1295054Y206804D02*
X1314677Y192689D01*
G01X1296009Y207534D02*
X1315148Y193767D01*
G01X1314677Y192689D02*
X1331990Y189165D01*
G01X1315148Y193767D02*
X1331990Y190339D01*
G01Y189165D02*
X1341552Y191111D01*
G01X1331990Y190339D02*
X1341588Y192292D01*
G01X1341552Y191111D02*
X1401725Y174983D01*
G01X1341588Y192292D02*
X1402201Y176047D01*
G01X1302602Y228120D02*
X1314715Y205768D01*
G01X1303695Y228517D02*
X1309883Y217099D01*
G01X1302602Y228120D02*
X1314715Y205768D01*
G01X1311146Y214769D02*
X1311789Y213582D01*
G01X1302602Y228120D02*
X1314715Y205768D01*
G01X1313052Y211252D02*
X1313695Y210065D01*
G01X1302602Y228120D02*
X1314715Y205768D01*
G01X1314958Y207735D02*
X1315601Y206548D01*
G01X1314715Y205768D02*
X1319119Y202600D01*
G01X1315601Y206548D02*
X1319590Y203678D01*
G01X1319119Y202600D02*
X1331990Y199981D01*
G01X1319590Y203678D02*
X1331990Y201155D01*
G01Y199981D02*
X1340813Y201777D01*
G01X1331990Y201155D02*
X1340849Y202958D01*
G01X1340813Y201777D02*
X1406193Y184249D01*
G01X1340849Y202958D02*
X1406671Y185312D01*
G01X1318622Y207651D02*
X1309492Y224498D01*
G01X1304587Y231135D02*
X1317736Y206871D01*
G01X1320697Y206158D02*
X1318622Y207651D01*
G01X1317736Y206871D02*
X1320226Y205080D01*
G01X1331990Y203860D02*
X1320697Y206158D01*
G01X1320226Y205080D02*
X1331990Y202686D01*
G01X1341333Y205762D02*
X1331990Y203860D01*
G01Y202686D02*
X1341294Y204580D01*
G01X1407789Y187629D02*
X1341333Y205762D01*
G01X1341299Y204578D02*
X1407311Y186567D01*
G01X1341299Y204578D02*
X1407311Y186567D01*
G01X1407789Y187629D02*
X1341333Y205762D01*
G01X1331990Y202686D02*
X1341294Y204580D01*
G01X1341333Y205762D02*
X1331990Y203860D01*
G01X1320226Y205080D02*
X1331990Y202686D01*
G01Y203860D02*
X1320697Y206158D01*
G01X1317736Y206871D02*
X1320226Y205080D01*
G01X1320697Y206158D02*
X1318622Y207651D01*
G01X1304587Y231135D02*
X1317736Y206871D01*
G01X1318622Y207651D02*
X1309492Y224498D01*
G01X1304587Y231135D02*
X1317736Y206871D01*
G01X1304587Y231135D02*
X1317736Y206871D01*
G01X1284402Y251272D02*
X1285300Y249915D01*
G01D02*
X1286433Y248204D01*
G01X1283319Y250823D02*
X1285300Y247831D01*
G01Y249915D02*
X1286433Y248204D01*
G01X1285300Y247831D02*
X1285350Y247755D01*
G01X1286433Y248204D02*
X1287088Y244985D01*
G01X1285350Y247755D02*
X1285914Y244983D01*
G01X1287088Y244985D02*
X1286823Y243661D01*
G01X1286303Y241063D02*
X1285265Y235876D01*
G01X1285914Y244983D02*
X1284092Y235876D01*
G01X1285265D02*
X1285980Y232299D01*
G01D02*
X1286042Y231989D01*
G01X1286561Y229391D02*
X1286853Y227930D01*
G01X1284092Y235876D02*
X1285680Y227930D01*
G01X1286853D02*
X1286434Y225831D01*
G01X1285680Y227930D02*
X1285241Y225735D01*
G01X1282435Y218119D02*
X1280938Y223220D01*
G01D02*
X1281101Y224476D01*
G01D02*
X1283115Y227497D01*
G01D02*
X1283612Y229966D01*
G01X1282032Y227946D02*
X1282439Y229967D01*
G01X1283612Y229966D02*
X1282482Y235617D01*
G01X1282439Y229967D02*
X1281309Y235617D01*
G01X1282482D02*
X1284420Y245308D01*
G01X1281309Y235617D02*
X1283246Y245306D01*
G01X1284420Y245308D02*
X1284048Y247133D01*
G01X1283246Y245306D02*
X1282965Y246685D01*
G01X1284048Y247133D02*
X1281973Y250273D01*
G01X1282965Y246685D02*
X1280890Y249825D01*
G01X1283319Y250823D02*
X1285300Y247831D01*
G01X1284402Y251272D02*
X1285300Y249915D01*
G01X1283319Y250823D02*
X1285300Y247831D01*
G01D02*
X1285350Y247755D01*
G01X1285300Y249915D02*
X1286433Y248204D01*
G01X1285350Y247755D02*
X1285914Y244983D01*
G01X1286433Y248204D02*
X1287088Y244985D01*
G01X1285914Y244983D02*
X1284092Y235876D01*
G01X1287088Y244985D02*
X1286823Y243661D01*
G01X1285914Y244983D02*
X1284092Y235876D01*
G01X1286303Y241063D02*
X1285265Y235876D01*
G01X1284092D02*
X1285680Y227930D01*
G01X1285265Y235876D02*
X1285980Y232299D01*
G01X1284092Y235876D02*
X1285680Y227930D01*
G01X1285980Y232299D02*
X1286042Y231989D01*
G01X1284092Y235876D02*
X1285680Y227930D01*
G01X1286561Y229391D02*
X1286853Y227930D01*
G01X1285680D02*
X1285241Y225735D01*
G01X1286853Y227930D02*
X1286434Y225831D01*
G01X1282435Y218119D02*
X1280938Y223220D01*
G01D02*
X1281101Y224476D01*
G01D02*
X1283115Y227497D01*
G01X1282032Y227946D02*
X1282439Y229967D01*
G01X1283115Y227497D02*
X1283612Y229966D01*
G01X1282439Y229967D02*
X1281309Y235617D01*
G01X1283612Y229966D02*
X1282482Y235617D01*
G01X1281309D02*
X1283246Y245306D01*
G01X1282482Y235617D02*
X1284420Y245308D01*
G01X1283246Y245306D02*
X1282965Y246685D01*
G01X1284420Y245308D02*
X1284048Y247133D01*
G01X1282965Y246685D02*
X1280890Y249825D01*
G01X1284048Y247133D02*
X1281973Y250273D01*
G01X1292265Y283160D02*
X1291065Y277511D01*
G01X1291089Y283160D02*
X1289890Y277516D01*
G01X1291065Y277511D02*
X1302062Y223455D01*
G01X1289890Y277516D02*
X1300969Y223058D01*
G01X1302062Y223455D02*
X1303717Y220402D01*
G01X1289699Y283160D02*
X1288472Y277386D01*
G01X1288523Y283160D02*
X1287297Y277391D01*
G01X1288472Y277386D02*
X1293378Y253272D01*
G01Y253271D02*
X1298428Y228453D01*
G01X1287297Y277391D02*
X1297205Y228692D01*
G01X1298428Y228453D02*
X1297452Y226986D01*
G01X1297205Y228692D02*
X1296757Y228018D01*
G01X1297452Y226986D02*
X1296144Y226718D01*
G01X1296757Y228018D02*
X1295447Y227750D01*
G01X1296144Y226718D02*
X1295793Y226188D01*
G01X1295447Y227750D02*
X1294570Y226426D01*
G01X1295793Y226188D02*
X1296003Y225159D01*
G01X1294570Y226426D02*
X1294971Y224463D01*
G01X1296003Y225159D02*
X1296534Y224807D01*
G01X1294971Y224463D02*
X1296296Y223584D01*
G01X1296534Y224807D02*
X1297963Y225098D01*
G01X1296296Y223584D02*
X1297726Y223875D01*
G01X1297963Y225098D02*
X1299287Y224223D01*
G01X1297726Y223875D02*
X1298254Y223526D01*
G01X1299287Y224223D02*
X1299688Y222243D01*
G01X1298254Y223526D02*
X1298596Y221842D01*
G01X1299689Y222241D02*
X1301358Y219192D01*
G01X1298596Y221842D02*
X1300119Y219059D01*
G01D02*
X1299940Y218452D01*
G01X1287133Y283160D02*
X1285143Y273790D01*
G01X1285957Y283160D02*
X1283967Y273791D01*
G01X1285143Y273790D02*
X1287748Y260974D01*
G01X1288276Y258377D02*
X1288545Y257054D01*
G01X1289073Y254457D02*
X1289342Y253134D01*
G01X1283967Y273791D02*
X1288259Y252685D01*
G01X1289342Y253134D02*
X1291301Y250173D01*
G01X1288259Y252685D02*
X1289238Y251206D01*
G01X1289342Y253134D02*
X1291301Y250173D01*
G01X1289239Y251205D02*
X1290216Y249728D01*
G01X1291301Y250173D02*
X1294555Y233571D01*
G01X1290216Y249728D02*
X1293382Y233573D01*
G01X1294555Y233571D02*
X1292862Y225106D01*
G01X1293382Y233573D02*
X1291669Y225009D01*
G01X1284567Y283160D02*
X1282583Y273817D01*
G01X1283391Y283160D02*
X1281408Y273822D01*
G01X1282583Y273817D02*
X1286988Y252159D01*
G01X1281408Y273822D02*
X1285905Y251710D01*
G01X1286988Y252159D02*
X1288942Y249206D01*
G01X1285980Y251597D02*
X1287857Y248761D01*
G01X1288942Y249206D02*
X1291971Y233751D01*
G01X1287857Y248761D02*
X1290798Y233755D01*
G01X1291971Y233751D02*
X1289958Y223693D01*
G01X1290798Y233755D02*
X1288765Y223597D01*
G01X1289958Y223693D02*
X1291762Y218876D01*
G01X1294831Y283160D02*
X1293679Y277738D01*
G01X1293655Y283160D02*
X1292504Y277743D01*
G01X1293679Y277738D02*
X1303695Y228517D01*
G01X1292504Y277743D02*
X1302602Y228120D01*
G01X1291089Y283160D02*
X1289890Y277516D01*
G01X1292265Y283160D02*
X1291065Y277511D01*
G01X1289890Y277516D02*
X1300969Y223058D01*
G01X1291065Y277511D02*
X1302062Y223455D01*
G01D02*
X1303717Y220402D01*
G01X1288523Y283160D02*
X1287297Y277391D01*
G01X1289699Y283160D02*
X1288472Y277386D01*
G01X1287297Y277391D02*
X1297205Y228692D01*
G01X1288472Y277386D02*
X1293378Y253272D01*
G01X1287297Y277391D02*
X1297205Y228692D01*
G01X1293378Y253271D02*
X1298428Y228453D01*
G01X1297205Y228692D02*
X1296757Y228018D01*
G01X1298428Y228453D02*
X1297452Y226986D01*
G01X1296757Y228018D02*
X1295447Y227750D01*
G01X1297452Y226986D02*
X1296144Y226718D01*
G01X1295447Y227750D02*
X1294570Y226426D01*
G01X1296144Y226718D02*
X1295793Y226188D01*
G01X1294570Y226426D02*
X1294971Y224463D01*
G01X1295793Y226188D02*
X1296003Y225159D01*
G01X1294971Y224463D02*
X1296296Y223584D01*
G01X1296003Y225159D02*
X1296534Y224807D01*
G01X1296296Y223584D02*
X1297726Y223875D01*
G01X1296534Y224807D02*
X1297963Y225098D01*
G01X1297726Y223875D02*
X1298254Y223526D01*
G01X1297963Y225098D02*
X1299287Y224223D01*
G01X1298254Y223526D02*
X1298596Y221842D01*
G01X1299287Y224223D02*
X1299688Y222243D01*
G01X1298596Y221842D02*
X1300119Y219059D01*
G01X1299689Y222241D02*
X1301358Y219192D01*
G01X1300119Y219059D02*
X1299940Y218452D01*
G01X1285957Y283160D02*
X1283967Y273791D01*
G01X1287133Y283160D02*
X1285143Y273790D01*
G01X1283967Y273791D02*
X1288259Y252685D01*
G01X1285143Y273790D02*
X1287748Y260974D01*
G01X1283967Y273791D02*
X1288259Y252685D01*
G01X1288276Y258377D02*
X1288545Y257054D01*
G01X1283967Y273791D02*
X1288259Y252685D01*
G01X1289073Y254457D02*
X1289342Y253134D01*
G01X1288259Y252685D02*
X1289238Y251206D01*
G01X1289239Y251205D02*
X1290216Y249728D01*
G01X1289342Y253134D02*
X1291301Y250173D01*
G01X1290216Y249728D02*
X1293382Y233573D01*
G01X1291301Y250173D02*
X1294555Y233571D01*
G01X1293382Y233573D02*
X1291669Y225009D01*
G01X1294555Y233571D02*
X1292862Y225106D01*
G01X1283391Y283160D02*
X1281408Y273822D01*
G01X1284567Y283160D02*
X1282583Y273817D01*
G01X1281408Y273822D02*
X1285905Y251710D01*
G01X1282583Y273817D02*
X1286988Y252159D01*
G01X1285980Y251597D02*
X1287857Y248761D01*
G01X1286988Y252159D02*
X1288942Y249206D01*
G01X1287857Y248761D02*
X1290798Y233755D01*
G01X1288942Y249206D02*
X1291971Y233751D01*
G01X1290798Y233755D02*
X1288765Y223597D01*
G01X1291971Y233751D02*
X1289958Y223693D01*
G01D02*
X1291762Y218876D01*
G01X1293655Y283160D02*
X1292504Y277743D01*
G01X1294831Y283160D02*
X1293679Y277738D01*
G01X1292504Y277743D02*
X1302602Y228120D01*
G01X1293679Y277738D02*
X1303695Y228517D01*
G01X1296262Y277816D02*
X1297397Y283160D01*
G01X1296221D02*
X1295087Y277821D01*
G01X1305680Y231532D02*
X1296262Y277816D01*
G01X1295087Y277821D02*
X1304587Y231135D01*
G01X1308229Y226828D02*
X1307586Y228015D01*
G01X1306323Y230345D02*
X1305680Y231532D01*
G01X1308229Y226828D02*
X1307586Y228015D01*
G01X1306323Y230345D02*
X1305680Y231532D01*
G01X1295087Y277821D02*
X1304587Y231135D01*
G01X1305680Y231532D02*
X1296262Y277816D01*
G01X1296221Y283160D02*
X1295087Y277821D01*
G01X1296262Y277816D02*
X1297397Y283160D01*
G01X1300211Y370609D02*
X1291270Y328493D01*
G01X1299035Y370609D02*
X1290090Y328475D01*
G01X1291270Y328493D02*
X1293324Y320090D01*
G01X1290090Y328475D02*
X1292144Y320072D01*
G01X1293324Y320090D02*
X1290126Y305042D01*
G01X1292144Y320072D02*
X1288950Y305042D01*
G01X1290126D02*
X1291344Y299308D01*
G01X1288950Y305042D02*
X1290168Y299308D01*
G01X1291344D02*
X1290090Y293399D01*
G01X1290168Y299308D02*
X1288914Y293399D01*
G01X1290090D02*
X1292265Y283160D01*
G01X1288914Y293399D02*
X1291089Y283160D01*
G01X1297574Y370291D02*
X1288626Y328148D01*
G01X1296398Y370291D02*
X1287446Y328130D01*
G01X1288626Y328148D02*
X1290683Y319736D01*
G01X1287446Y328130D02*
X1289503Y319718D01*
G01X1290683Y319736D02*
X1287560Y305042D01*
G01X1289503Y319718D02*
X1286384Y305042D01*
G01X1287560D02*
X1288778Y299308D01*
G01X1286384Y305042D02*
X1287602Y299308D01*
G01X1288778D02*
X1287524Y293398D01*
G01X1287602Y299308D02*
X1286348Y293398D01*
G01X1287524D02*
X1289699Y283160D01*
G01X1286348Y293398D02*
X1288523Y283160D01*
G01X1288380Y342390D02*
X1288099Y341069D01*
G01X1287549Y338477D02*
X1285980Y331078D01*
G01D02*
X1285609Y329328D01*
G01X1293448Y371799D02*
X1284427Y329312D01*
G01X1285609Y329328D02*
X1285980Y327811D01*
G01D02*
X1286877Y324142D01*
G01X1284427Y329312D02*
X1285980Y322963D01*
G01X1286877Y324142D02*
X1288041Y319382D01*
G01X1285980Y322963D02*
X1286860Y319366D01*
G01X1288041Y319382D02*
X1285102Y305547D01*
G01X1286860Y319366D02*
X1285980Y315220D01*
G01X1288041Y319382D02*
X1285102Y305547D01*
G01X1285980Y315220D02*
X1285300Y312016D01*
G01X1288041Y319382D02*
X1285102Y305547D01*
G01X1285300Y312016D02*
X1284021Y305995D01*
G01X1288041Y319382D02*
X1285102Y305547D01*
G01X1285089Y305527D02*
X1284995Y305081D01*
G01X1284008Y305975D02*
X1283819Y305084D01*
G01X1284995Y305045D02*
X1285300Y303601D01*
G01X1283819Y305044D02*
X1284174Y303362D01*
G01X1285300Y303601D02*
X1285980Y300406D01*
G01D02*
X1286012Y300256D01*
G01X1286025Y300231D02*
X1286160Y299595D01*
G01X1284174Y303362D02*
X1284930Y299810D01*
G01X1286025Y300231D02*
X1286160Y299595D01*
G01D02*
X1286212Y299349D01*
G01X1284942Y299791D02*
X1285040Y299329D01*
G01X1286207Y299286D02*
X1285980Y298215D01*
G01D02*
X1285736Y297064D01*
G01D02*
X1285697Y296879D01*
G01X1285040Y299329D02*
X1284610Y297302D01*
G01X1285980Y298215D02*
X1285736Y297064D01*
G01D02*
X1285697Y296879D01*
G01D02*
X1285300Y295011D01*
G01X1284610Y297302D02*
X1284571Y297117D01*
G01X1285736Y297064D02*
X1285697Y296879D01*
G01D02*
X1285300Y295011D01*
G01X1284571Y297117D02*
X1284175Y295250D01*
G01X1285300Y295011D02*
X1284997Y293583D01*
G01X1284175Y295250D02*
X1283877Y293848D01*
G01X1285300Y295011D02*
X1284997Y293583D01*
G01X1283859Y293803D02*
X1283857Y293794D01*
G01X1285300Y295011D02*
X1284997Y293583D01*
G01D02*
X1284995Y293572D01*
G01X1283857Y293794D02*
X1283778Y293420D01*
G01X1284956Y293410D02*
X1285980Y288589D01*
G01D02*
X1287133Y283160D01*
G01X1283778Y293420D02*
X1285957Y283160D01*
G01X1291903Y371689D02*
X1282772Y328698D01*
G01X1290727Y371689D02*
X1281592Y328680D01*
G01X1282772Y328698D02*
X1285278Y318452D01*
G01X1281592Y328680D02*
X1284098Y318434D01*
G01X1285278Y318452D02*
X1282429Y305043D01*
G01X1284098Y318434D02*
X1281253Y305043D01*
G01X1282429D02*
X1283646Y299307D01*
G01X1281253Y305043D02*
X1282470Y299307D01*
G01X1283646D02*
X1282392Y293398D01*
G01X1282470Y299307D02*
X1281216Y293398D01*
G01X1282392D02*
X1284567Y283160D01*
G01X1281216Y293398D02*
X1283391Y283160D01*
G01X1299275Y353980D02*
X1293926Y328787D01*
G01X1301642Y370668D02*
X1292746Y328769D01*
G01X1293926Y328785D02*
X1295966Y320445D01*
G01X1292746Y328769D02*
X1294786Y320427D01*
G01X1295966Y320445D02*
X1292692Y305042D01*
G01X1294786Y320427D02*
X1291516Y305042D01*
G01X1292692D02*
X1293910Y299308D01*
G01X1291516Y305042D02*
X1292734Y299308D01*
G01X1293910D02*
X1292656Y293399D01*
G01X1292734Y299308D02*
X1291480Y293399D01*
G01X1292656D02*
X1294831Y283160D01*
G01X1291480Y293399D02*
X1293655Y283160D01*
G01X1299035Y370609D02*
X1290090Y328475D01*
G01X1300211Y370609D02*
X1291270Y328493D01*
G01X1290090Y328475D02*
X1292144Y320072D01*
G01X1291270Y328493D02*
X1293324Y320090D01*
G01X1292144Y320072D02*
X1288950Y305042D01*
G01X1293324Y320090D02*
X1290126Y305042D01*
G01X1288950D02*
X1290168Y299308D01*
G01X1290126Y305042D02*
X1291344Y299308D01*
G01X1290168D02*
X1288914Y293399D01*
G01X1291344Y299308D02*
X1290090Y293399D01*
G01X1288914D02*
X1291089Y283160D01*
G01X1290090Y293399D02*
X1292265Y283160D01*
G01X1296398Y370291D02*
X1287446Y328130D01*
G01X1297574Y370291D02*
X1288626Y328148D01*
G01X1287446Y328130D02*
X1289503Y319718D01*
G01X1288626Y328148D02*
X1290683Y319736D01*
G01X1289503Y319718D02*
X1286384Y305042D01*
G01X1290683Y319736D02*
X1287560Y305042D01*
G01X1286384D02*
X1287602Y299308D01*
G01X1287560Y305042D02*
X1288778Y299308D01*
G01X1287602D02*
X1286348Y293398D01*
G01X1288778Y299308D02*
X1287524Y293398D01*
G01X1286348D02*
X1288523Y283160D01*
G01X1287524Y293398D02*
X1289699Y283160D01*
G01X1293448Y371799D02*
X1284427Y329312D01*
G01X1293448Y371799D02*
X1284427Y329312D01*
G01X1293448Y371799D02*
X1284427Y329312D01*
G01X1293448Y371799D02*
X1284427Y329312D01*
G01X1293448Y371799D02*
X1284427Y329312D01*
G01X1293448Y371799D02*
X1284427Y329312D01*
G01X1288380Y342390D02*
X1288099Y341069D01*
G01X1293448Y371799D02*
X1284427Y329312D01*
G01X1287549Y338477D02*
X1285980Y331078D01*
G01X1293448Y371799D02*
X1284427Y329312D01*
G01X1285980Y331078D02*
X1285609Y329328D01*
G01X1284427Y329312D02*
X1285980Y322963D01*
G01X1285609Y329328D02*
X1285980Y327811D01*
G01X1284427Y329312D02*
X1285980Y322963D01*
G01Y327811D02*
X1286877Y324142D01*
G01X1285980Y322963D02*
X1286860Y319366D01*
G01X1286877Y324142D02*
X1288041Y319382D01*
G01X1286860Y319366D02*
X1285980Y315220D01*
G01D02*
X1285300Y312016D01*
G01D02*
X1284021Y305995D01*
G01X1284008Y305975D02*
X1283819Y305084D01*
G01X1288041Y319382D02*
X1285102Y305547D01*
G01X1284008Y305975D02*
X1283819Y305084D01*
G01X1285089Y305527D02*
X1284995Y305081D01*
G01X1283819Y305044D02*
X1284174Y303362D01*
G01X1284995Y305045D02*
X1285300Y303601D01*
G01X1284174Y303362D02*
X1284930Y299810D01*
G01X1285300Y303601D02*
X1285980Y300406D01*
G01X1284174Y303362D02*
X1284930Y299810D01*
G01X1285980Y300406D02*
X1286012Y300256D01*
G01X1284174Y303362D02*
X1284930Y299810D01*
G01X1284942Y299791D02*
X1285040Y299329D01*
G01X1286025Y300231D02*
X1286160Y299595D01*
G01X1284942Y299791D02*
X1285040Y299329D01*
G01X1286160Y299595D02*
X1286212Y299349D01*
G01X1285040Y299329D02*
X1284610Y297302D01*
G01X1286207Y299286D02*
X1285980Y298215D01*
G01X1285040Y299329D02*
X1284610Y297302D01*
G01D02*
X1284571Y297117D01*
G01X1285980Y298215D02*
X1285736Y297064D01*
G01X1285040Y299329D02*
X1284610Y297302D01*
G01D02*
X1284571Y297117D01*
G01D02*
X1284175Y295250D01*
G01X1285736Y297064D02*
X1285697Y296879D01*
G01X1284610Y297302D02*
X1284571Y297117D01*
G01D02*
X1284175Y295250D01*
G01X1285697Y296879D02*
X1285300Y295011D01*
G01X1284175Y295250D02*
X1283877Y293848D01*
G01X1283859Y293803D02*
X1283857Y293794D01*
G01D02*
X1283778Y293420D01*
G01X1285300Y295011D02*
X1284997Y293583D01*
G01X1283857Y293794D02*
X1283778Y293420D01*
G01X1284997Y293583D02*
X1284995Y293572D01*
G01X1283778Y293420D02*
X1285957Y283160D01*
G01X1284956Y293410D02*
X1285980Y288589D01*
G01X1283778Y293420D02*
X1285957Y283160D01*
G01X1285980Y288589D02*
X1287133Y283160D01*
G01X1290727Y371689D02*
X1281592Y328680D01*
G01X1291903Y371689D02*
X1282772Y328698D01*
G01X1281592Y328680D02*
X1284098Y318434D01*
G01X1282772Y328698D02*
X1285278Y318452D01*
G01X1284098Y318434D02*
X1281253Y305043D01*
G01X1285278Y318452D02*
X1282429Y305043D01*
G01X1281253D02*
X1282470Y299307D01*
G01X1282429Y305043D02*
X1283646Y299307D01*
G01X1282470D02*
X1281216Y293398D01*
G01X1283646Y299307D02*
X1282392Y293398D01*
G01X1281216D02*
X1283391Y283160D01*
G01X1282392Y293398D02*
X1284567Y283160D01*
G01X1301642Y370668D02*
X1292746Y328769D01*
G01X1301642Y370668D02*
X1292746Y328769D01*
G01X1301642Y370668D02*
X1292746Y328769D01*
G01X1301642Y370668D02*
X1292746Y328769D01*
G01X1301642Y370668D02*
X1292746Y328769D01*
G01X1299275Y353980D02*
X1293926Y328787D01*
G01X1292746Y328769D02*
X1294786Y320427D01*
G01X1293926Y328785D02*
X1295966Y320445D01*
G01X1294786Y320427D02*
X1291516Y305042D01*
G01X1295966Y320445D02*
X1292692Y305042D01*
G01X1291516D02*
X1292734Y299308D01*
G01X1292692Y305042D02*
X1293910Y299308D01*
G01X1292734D02*
X1291480Y293399D01*
G01X1293910Y299308D02*
X1292656Y293399D01*
G01X1291480D02*
X1293655Y283160D01*
G01X1292656Y293399D02*
X1294831Y283160D01*
G01X1296952Y327570D02*
X1303415Y358017D01*
G01X1304572Y369006D02*
X1295771Y327554D01*
G01X1298605Y320801D02*
X1296952Y327570D01*
G01X1295771Y327554D02*
X1297425Y320782D01*
G01X1295258Y305042D02*
X1295538Y306363D01*
G01X1296089Y308955D02*
X1296369Y310276D01*
G01X1296920Y312868D02*
X1297201Y314189D01*
G01X1297751Y316781D02*
X1298605Y320800D01*
G01X1297425Y320782D02*
X1294082Y305042D01*
G01X1296475Y299308D02*
X1295258Y305042D01*
G01X1294082D02*
X1295299Y299308D01*
G01X1295222Y293399D02*
X1296475Y299308D01*
G01X1295299D02*
X1294046Y293399D01*
G01X1297397Y283160D02*
X1295222Y293399D01*
G01X1294046D02*
X1296221Y283160D01*
G01X1294046Y293399D02*
X1296221Y283160D01*
G01X1297397D02*
X1295222Y293399D01*
G01X1295299Y299308D02*
X1294046Y293399D01*
G01X1295222D02*
X1296475Y299308D01*
G01X1294082Y305042D02*
X1295299Y299308D01*
G01X1296475D02*
X1295258Y305042D01*
G01X1297425Y320782D02*
X1294082Y305042D01*
G01X1295258D02*
X1295538Y306363D01*
G01X1297425Y320782D02*
X1294082Y305042D01*
G01X1296089Y308955D02*
X1296369Y310276D01*
G01X1297425Y320782D02*
X1294082Y305042D01*
G01X1296920Y312868D02*
X1297201Y314189D01*
G01X1297425Y320782D02*
X1294082Y305042D01*
G01X1297751Y316781D02*
X1298605Y320800D01*
G01X1295771Y327554D02*
X1297425Y320782D01*
G01X1298605Y320801D02*
X1296952Y327570D01*
G01X1304572Y369006D02*
X1295771Y327554D01*
G01X1296952Y327570D02*
X1303415Y358017D01*
G01X1304572Y369006D02*
X1295771Y327554D01*
G01X1304572Y369006D02*
X1295771Y327554D01*
G01X1280808Y396558D02*
X1281614Y385953D01*
G01X1283270Y397291D02*
X1284144Y385794D01*
G01X1282142Y396955D02*
X1282294Y394956D01*
G01X1283270Y397291D02*
X1284144Y385794D01*
G01X1282294Y394956D02*
X1282985Y385867D01*
G01X1284144Y385794D02*
X1280763Y369200D01*
G01X1282985Y385867D02*
X1282294Y382476D01*
G01X1284144Y385794D02*
X1280763Y369200D01*
G01X1280808Y396558D02*
X1281614Y385953D01*
G01X1282142Y396955D02*
X1282294Y394956D01*
G01D02*
X1282985Y385867D01*
G01X1283270Y397291D02*
X1284144Y385794D01*
G01X1282985Y385867D02*
X1282294Y382476D01*
G01X1284144Y385794D02*
X1280763Y369200D01*
G01X1281471Y414037D02*
X1289654Y399160D01*
G01X1280553Y413319D02*
X1288526Y398822D01*
G01X1289654Y399160D02*
X1289692Y398666D01*
G01D02*
X1290655Y386038D01*
G01X1288526Y398822D02*
X1288538Y398666D01*
G01X1289654Y399160D02*
X1289692Y398666D01*
G01D02*
X1290655Y386038D01*
G01X1288538Y398666D02*
X1289495Y386115D01*
G01X1290655Y386038D02*
X1288437Y375604D01*
G01X1289495Y386115D02*
X1287261Y375604D01*
G01X1288437D02*
X1289301Y371535D01*
G01X1287261Y375604D02*
X1288125Y371535D01*
G01X1285980Y368635D02*
X1286538Y371263D01*
G01D02*
X1285980Y373887D01*
G01X1285362Y371262D02*
X1285300Y371554D01*
G01X1286538Y371263D02*
X1285980Y373887D01*
G01D02*
X1285743Y375002D01*
G01X1285300Y371554D02*
X1284567Y375002D01*
G01X1285743D02*
X1288002Y385639D01*
G01X1284567Y375002D02*
X1285980Y381656D01*
G01X1285743Y375002D02*
X1288002Y385639D01*
G01X1285980Y381656D02*
X1286842Y385716D01*
G01X1288002Y385639D02*
X1287028Y398446D01*
G01X1286842Y385716D02*
X1285980Y397057D01*
G01X1288002Y385639D02*
X1287028Y398446D01*
G01X1285980Y397057D02*
X1285900Y398110D01*
G01X1287028Y398446D02*
X1286907Y398666D01*
G01X1285900Y398110D02*
X1285594Y398666D01*
G01D02*
X1285300Y399200D01*
G01X1280553Y413319D02*
X1288526Y398822D01*
G01X1281471Y414037D02*
X1289654Y399160D01*
G01X1288526Y398822D02*
X1288538Y398666D01*
G01D02*
X1289495Y386115D01*
G01X1289654Y399160D02*
X1289692Y398666D01*
G01X1288526Y398822D02*
X1288538Y398666D01*
G01D02*
X1289495Y386115D01*
G01X1289692Y398666D02*
X1290655Y386038D01*
G01X1289495Y386115D02*
X1287261Y375604D01*
G01X1290655Y386038D02*
X1288437Y375604D01*
G01X1287261D02*
X1288125Y371535D01*
G01X1288437Y375604D02*
X1289301Y371535D01*
G01X1285980Y368635D02*
X1286538Y371263D01*
G01X1285362Y371262D02*
X1285300Y371554D01*
G01D02*
X1284567Y375002D01*
G01X1286538Y371263D02*
X1285980Y373887D01*
G01X1285300Y371554D02*
X1284567Y375002D01*
G01X1285980Y373887D02*
X1285743Y375002D01*
G01X1284567D02*
X1285980Y381656D01*
G01D02*
X1286842Y385716D01*
G01X1285743Y375002D02*
X1288002Y385639D01*
G01X1286842Y385716D02*
X1285980Y397057D01*
G01D02*
X1285900Y398110D01*
G01X1288002Y385639D02*
X1287028Y398446D01*
G01X1285900Y398110D02*
X1285594Y398666D01*
G01X1287028Y398446D02*
X1286907Y398666D01*
G01X1285900Y398110D02*
X1285594Y398666D01*
G01D02*
X1285300Y399200D01*
G01X1290724Y419588D02*
X1300080Y402581D01*
G01X1289806Y418870D02*
X1298952Y402245D01*
G01X1300080Y402581D02*
X1301226Y387491D01*
G01X1298952Y402245D02*
X1300066Y387568D01*
G01X1301226Y387491D02*
X1298927Y376661D01*
G01X1300066Y387568D02*
X1297751Y376661D01*
G01X1298927D02*
X1300211Y370609D01*
G01X1297751Y376661D02*
X1299035Y370609D01*
G01X1288704Y417851D02*
X1297366Y402108D01*
G01X1287786Y417133D02*
X1296238Y401772D01*
G01X1297366Y402108D02*
X1298526Y386853D01*
G01X1296238Y401772D02*
X1297366Y386931D01*
G01X1298526Y386853D02*
X1296290Y376332D01*
G01X1297366Y386931D02*
X1295114Y376332D01*
G01X1296290D02*
X1297574Y370291D01*
G01X1295114Y376332D02*
X1296398Y370291D01*
G01X1286174Y416733D02*
X1294840Y400982D01*
G01X1285256Y416015D02*
X1293712Y400646D01*
G01X1294840Y400982D02*
X1295927Y386697D01*
G01X1293712Y400646D02*
X1294767Y386775D01*
G01X1295927Y386697D02*
X1293693Y376190D01*
G01X1294767Y386775D02*
X1292517Y376190D01*
G01X1293693D02*
X1294625Y371803D01*
G01X1292517Y376190D02*
X1293450Y371798D01*
G01X1294625Y371803D02*
X1294345Y370482D01*
G01X1293794Y367890D02*
X1293514Y366570D01*
G01X1292964Y363977D02*
X1292683Y362657D01*
G01X1292133Y360065D02*
X1291853Y358744D01*
G01X1291302Y356152D02*
X1288930Y344982D01*
G01X1284093Y415067D02*
X1292218Y400296D01*
G01X1283175Y414349D02*
X1291089Y399961D01*
G01X1292218Y400296D02*
X1293282Y386325D01*
G01X1291090Y399961D02*
X1292122Y386403D01*
G01X1293282Y386325D02*
X1291037Y375764D01*
G01X1292122Y386403D02*
X1289861Y375764D01*
G01X1291037D02*
X1291903Y371689D01*
G01X1289861Y375764D02*
X1290727Y371689D01*
G01X1291767Y420855D02*
X1301720Y402766D01*
G01X1302835Y403324D02*
X1303972Y388335D01*
G01X1301724Y402762D02*
X1302812Y388413D01*
G01X1303972Y388335D02*
X1301518Y376784D01*
G01X1302812Y388413D02*
X1300342Y376784D01*
G01X1301518D02*
X1302817Y370672D01*
G01X1300342Y376784D02*
X1301642Y370668D01*
G01X1302818D02*
X1302318Y368312D01*
G01X1301767Y365720D02*
X1301487Y364399D01*
G01X1300937Y361807D02*
X1300656Y360486D01*
G01X1300106Y357894D02*
X1299825Y356573D01*
G01X1289806Y418870D02*
X1298952Y402245D01*
G01X1290724Y419588D02*
X1300080Y402581D01*
G01X1298952Y402245D02*
X1300066Y387568D01*
G01X1300080Y402581D02*
X1301226Y387491D01*
G01X1300066Y387568D02*
X1297751Y376661D01*
G01X1301226Y387491D02*
X1298927Y376661D01*
G01X1297751D02*
X1299035Y370609D01*
G01X1298927Y376661D02*
X1300211Y370609D01*
G01X1287786Y417133D02*
X1296238Y401772D01*
G01X1288704Y417851D02*
X1297366Y402108D01*
G01X1296238Y401772D02*
X1297366Y386931D01*
G01Y402108D02*
X1298526Y386853D01*
G01X1297366Y386931D02*
X1295114Y376332D01*
G01X1298526Y386853D02*
X1296290Y376332D01*
G01X1295114D02*
X1296398Y370291D01*
G01X1296290Y376332D02*
X1297574Y370291D01*
G01X1285256Y416015D02*
X1293712Y400646D01*
G01X1286174Y416733D02*
X1294840Y400982D01*
G01X1293712Y400646D02*
X1294767Y386775D01*
G01X1294840Y400982D02*
X1295927Y386697D01*
G01X1294767Y386775D02*
X1292517Y376190D01*
G01X1295927Y386697D02*
X1293693Y376190D01*
G01X1292517D02*
X1293450Y371798D01*
G01X1293693Y376190D02*
X1294625Y371803D01*
G01D02*
X1294345Y370482D01*
G01X1293794Y367890D02*
X1293514Y366570D01*
G01X1292964Y363977D02*
X1292683Y362657D01*
G01X1292133Y360065D02*
X1291853Y358744D01*
G01X1291302Y356152D02*
X1288930Y344982D01*
G01X1283175Y414349D02*
X1291089Y399961D01*
G01X1284093Y415067D02*
X1292218Y400296D01*
G01X1291090Y399961D02*
X1292122Y386403D01*
G01X1292218Y400296D02*
X1293282Y386325D01*
G01X1292122Y386403D02*
X1289861Y375764D01*
G01X1293282Y386325D02*
X1291037Y375764D01*
G01X1289861D02*
X1290727Y371689D01*
G01X1291037Y375764D02*
X1291903Y371689D01*
G01X1291767Y420855D02*
X1301720Y402766D01*
G01X1301724Y402762D02*
X1302812Y388413D01*
G01X1302835Y403324D02*
X1303972Y388335D01*
G01X1302812Y388413D02*
X1300342Y376784D01*
G01X1303972Y388335D02*
X1301518Y376784D01*
G01X1300342D02*
X1301642Y370668D01*
G01X1301518Y376784D02*
X1302817Y370672D01*
G01X1302818Y370668D02*
X1302318Y368312D01*
G01X1301767Y365720D02*
X1301487Y364399D01*
G01X1300937Y361807D02*
X1300656Y360486D01*
G01X1300106Y357894D02*
X1299825Y356573D01*
G01X1305847Y398666D02*
X1305449Y403893D01*
G01X1304321Y403557D02*
X1304693Y398666D01*
G01X1306684Y387656D02*
X1305847Y398666D01*
G01X1304693D02*
X1305524Y387733D01*
G01X1304235Y376125D02*
X1306684Y387655D01*
G01X1305524Y387733D02*
X1303059Y376125D01*
G01X1305748Y369006D02*
X1304235Y376125D01*
G01X1303059D02*
X1304572Y369006D01*
G01X1303966Y360609D02*
X1304246Y361930D01*
G01X1304796Y364522D02*
X1305748Y369006D01*
G01X1303966Y360609D02*
X1304246Y361930D01*
G01X1304796Y364522D02*
X1305748Y369006D01*
G01X1303059Y376125D02*
X1304572Y369006D01*
G01X1305748D02*
X1304235Y376125D01*
G01X1305524Y387733D02*
X1303059Y376125D01*
G01X1304235D02*
X1306684Y387655D01*
G01X1304693Y398666D02*
X1305524Y387733D01*
G01X1306684Y387656D02*
X1305847Y398666D01*
G01X1304321Y403557D02*
X1304693Y398666D01*
G01X1305847D02*
X1305449Y403893D01*
G01X1287785Y417133D02*
X1287786D01*
G01X1285980Y416912D02*
X1286174Y416733D01*
G01X1285980Y416912D02*
X1286174Y416733D01*
G01X1285255Y416015D02*
X1285256D01*
G01X1291766Y420855D02*
X1291767D01*
G01X1292677Y421588D02*
X1302594Y403565D01*
G01X1287785Y417133D02*
X1287786D01*
G01X1285255Y416015D02*
X1285256D01*
G01X1285980Y416912D02*
X1286174Y416733D01*
G01X1291766Y420855D02*
X1291767D01*
G01X1292677Y421588D02*
X1302594Y403565D01*
G01X1289551Y463490D02*
X1303850D01*
G01X1303750Y464640D02*
X1289074D01*
G01X1283472Y457411D02*
X1289551Y463490D01*
G01X1289074Y464640D02*
X1282322Y457888D01*
G01X1283472Y435373D02*
Y457411D01*
G01X1282322Y457888D02*
Y434896D01*
G01X1293828Y425017D02*
X1283472Y435373D01*
G01X1282322Y434896D02*
X1292899Y424319D01*
G01X1305449Y403893D02*
X1304798Y405076D01*
G01X1303521Y407398D02*
X1302870Y408581D01*
G01X1301593Y410903D02*
X1300942Y412086D01*
G01X1299665Y414408D02*
X1299014Y415591D01*
G01X1297737Y417913D02*
X1293828Y425017D01*
G01X1292899Y424319D02*
X1304321Y403557D01*
G01X1292899Y424319D02*
X1304321Y403557D01*
G01X1305449Y403893D02*
X1304798Y405076D01*
G01X1292899Y424319D02*
X1304321Y403557D01*
G01X1303521Y407398D02*
X1302870Y408581D01*
G01X1292899Y424319D02*
X1304321Y403557D01*
G01X1301593Y410903D02*
X1300942Y412086D01*
G01X1292899Y424319D02*
X1304321Y403557D01*
G01X1299665Y414408D02*
X1299014Y415591D01*
G01X1292899Y424319D02*
X1304321Y403557D01*
G01X1297737Y417913D02*
X1293828Y425017D01*
G01X1282322Y434896D02*
X1292899Y424319D01*
G01X1293828Y425017D02*
X1283472Y435373D01*
G01X1282322Y457888D02*
Y434896D01*
G01X1283472Y435373D02*
Y457411D01*
G01X1289074Y464640D02*
X1282322Y457888D01*
G01X1283472Y457411D02*
X1289551Y463490D01*
G01X1303750Y464640D02*
X1289074D01*
G01X1289551Y463490D02*
X1303850D01*
G01X1294145Y502070D02*
X1306808Y494694D01*
G01X1294593Y503140D02*
X1307119Y495844D01*
G01X1306808Y494694D02*
X1312911D01*
G01X1307119Y495844D02*
X1313045D01*
G01X1312911Y494694D02*
X1330995Y490447D01*
G01X1313045Y495844D02*
X1331129Y491597D01*
G01X1330995Y490447D02*
X1348791D01*
G01X1331129Y491597D02*
X1348314D01*
G01X1294593Y503140D02*
X1307119Y495844D01*
G01X1294145Y502070D02*
X1306808Y494694D01*
G01X1307119Y495844D02*
X1313045D01*
G01X1306808Y494694D02*
X1312911D01*
G01X1313045Y495844D02*
X1331129Y491597D01*
G01X1312911Y494694D02*
X1330995Y490447D01*
G01X1331129Y491597D02*
X1348314D01*
G01X1330995Y490447D02*
X1348791D01*
G01X1321466Y474234D02*
X1304805D01*
G01X1320728Y475384D02*
X1304328D01*
G01X1304805Y474234D02*
X1302782Y472211D01*
G01X1304328Y475384D02*
X1302305Y473361D01*
G01X1302782Y472211D02*
X1282290D01*
G01X1302305Y473361D02*
X1281813D01*
G01X1282290Y472211D02*
X1281335Y471256D01*
G01X1328347Y466304D02*
X1311402D01*
G01X1328347Y467454D02*
X1311879D01*
G01X1311402Y466304D02*
X1309071Y468635D01*
G01X1311879Y467454D02*
X1309548Y469785D01*
G01X1309071Y468635D02*
X1285644D01*
G01X1309548Y469785D02*
X1285167D01*
G01X1320728Y475384D02*
X1304328D01*
G01X1321466Y474234D02*
X1304805D01*
G01X1304328Y475384D02*
X1302305Y473361D01*
G01X1304805Y474234D02*
X1302782Y472211D01*
G01X1302305Y473361D02*
X1281813D01*
G01X1302782Y472211D02*
X1282290D01*
G01D02*
X1281335Y471256D01*
G01X1328347Y467454D02*
X1311879D01*
G01X1328347Y466304D02*
X1311402D01*
G01X1311879Y467454D02*
X1309548Y469785D01*
G01X1311402Y466304D02*
X1309071Y468635D01*
G01X1309548Y469785D02*
X1285167D01*
G01X1309071Y468635D02*
X1285644D01*
G01X1339027Y539731D02*
X1351101D01*
G01X1350624Y540881D02*
X1338550D01*
G01X1337169Y537873D02*
X1339027Y539731D01*
G01X1338550Y540881D02*
X1336692Y539023D01*
G01X1326298Y537873D02*
X1337169D01*
G01X1336692Y539023D02*
X1326775D01*
G01X1318821Y545350D02*
X1326298Y537873D01*
G01X1326775Y539023D02*
X1319298Y546500D01*
G01X1300849Y545350D02*
X1318821D01*
G01X1319298Y546500D02*
X1301326D01*
G01X1297225Y548974D02*
X1300849Y545350D01*
G01X1301326Y546500D02*
X1298375Y549451D01*
G01X1297225Y561651D02*
Y548974D01*
G01X1298375Y549451D02*
Y561174D01*
G01X1298907Y563333D02*
X1297225Y561651D01*
G01X1298375Y561174D02*
X1300057Y562856D01*
G01X1298907Y581151D02*
Y563333D01*
G01X1300057Y562856D02*
Y580674D01*
G01X1299819Y582063D02*
X1298907Y581151D01*
G01X1300057Y580674D02*
X1300969Y581586D01*
G01X1299819Y599337D02*
Y582063D01*
G01X1300969Y581586D02*
Y599814D01*
G01Y581586D02*
Y599814D01*
G01X1299819Y599337D02*
Y582063D01*
G01X1300057Y580674D02*
X1300969Y581586D01*
G01X1299819Y582063D02*
X1298907Y581151D01*
G01X1300057Y562856D02*
Y580674D01*
G01X1298907Y581151D02*
Y563333D01*
G01X1298375Y561174D02*
X1300057Y562856D01*
G01X1298907Y563333D02*
X1297225Y561651D01*
G01X1298375Y549451D02*
Y561174D01*
G01X1297225Y561651D02*
Y548974D01*
G01X1301326Y546500D02*
X1298375Y549451D01*
G01X1297225Y548974D02*
X1300849Y545350D01*
G01X1319298Y546500D02*
X1301326D01*
G01X1300849Y545350D02*
X1318821D01*
G01X1326775Y539023D02*
X1319298Y546500D01*
G01X1318821Y545350D02*
X1326298Y537873D01*
G01X1336692Y539023D02*
X1326775D01*
G01X1326298Y537873D02*
X1337169D01*
G01X1338550Y540881D02*
X1336692Y539023D01*
G01X1337169Y537873D02*
X1339027Y539731D01*
G01X1350624Y540881D02*
X1338550D01*
G01X1339027Y539731D02*
X1351101D01*
G01X1298506Y600650D02*
X1299819Y599337D01*
G01X1300969Y599814D02*
X1298983Y601800D01*
G01X1300969Y599814D02*
X1298983Y601800D01*
G01X1298506Y600650D02*
X1299819Y599337D01*
G01X1282265Y644948D02*
X1283756Y653404D01*
G01X1284972Y653673D02*
X1283481Y645217D01*
G01X1283175Y643645D02*
X1282265Y644948D01*
G01X1283481Y645217D02*
X1283845Y644696D01*
G01X1286453Y644209D02*
X1285149Y643299D01*
G01D02*
X1283175Y643645D01*
G01X1283845Y644696D02*
X1284879Y644514D01*
G01X1286453Y644209D02*
X1285149Y643299D01*
G01X1284879Y644514D02*
X1285402Y644879D01*
G01X1288135Y653761D02*
X1286453Y644209D01*
G01X1285402Y644879D02*
X1287085Y654431D01*
G01X1288556Y644915D02*
X1290056Y653424D01*
G01X1291272Y653695D02*
X1289772Y645184D01*
G01X1289466Y643612D02*
X1288556Y644915D01*
G01X1289772Y645184D02*
X1290136Y644663D01*
G01X1292740Y644176D02*
X1291440Y643265D01*
G01D02*
X1289466Y643612D01*
G01X1290136Y644663D02*
X1291170Y644481D01*
G01X1292740Y644176D02*
X1291440Y643265D01*
G01X1291170Y644481D02*
X1291690Y644845D01*
G01X1294431Y653758D02*
X1292740Y644176D01*
G01X1291690Y644845D02*
X1293380Y654426D01*
G01X1294853Y644914D02*
X1296353Y653422D01*
G01X1297569Y653692D02*
X1296069Y645185D01*
G01X1295762Y643613D02*
X1294853Y644914D01*
G01X1296069Y645185D02*
X1296432Y644663D01*
G01X1299038Y644175D02*
X1297735Y643265D01*
G01D02*
X1295762Y643613D01*
G01X1296432Y644663D02*
X1297466Y644480D01*
G01X1299038Y644175D02*
X1297735Y643265D01*
G01X1297466Y644480D02*
X1297988Y644845D01*
G01X1300707Y653645D02*
X1299038Y644175D01*
G01X1297988Y644845D02*
X1299656Y654314D01*
G01X1301150Y644932D02*
X1302627Y653309D01*
G01X1303843Y653577D02*
X1302366Y645201D01*
G01X1302060Y643629D02*
X1301150Y644932D01*
G01X1302366Y645201D02*
X1302730Y644680D01*
G01X1305336Y644193D02*
X1304033Y643284D01*
G01D02*
X1302060Y643629D01*
G01X1302730Y644680D02*
X1303764Y644499D01*
G01X1305336Y644193D02*
X1304033Y643284D01*
G01X1303764Y644499D02*
X1304286Y644863D01*
G01X1307005Y653649D02*
X1305336Y644193D01*
G01X1304286Y644863D02*
X1305955Y654319D01*
G01X1307445Y644934D02*
X1308923Y653309D01*
G01X1310139Y653578D02*
X1308661Y645203D01*
G01X1308356Y643630D02*
X1307445Y644934D01*
G01X1308661Y645203D02*
X1309026Y644681D01*
G01X1311633Y644193D02*
X1310330Y643284D01*
G01D02*
X1308356Y643630D01*
G01X1309026Y644681D02*
X1310061Y644499D01*
G01X1311633Y644193D02*
X1310330Y643284D01*
G01X1310061Y644499D02*
X1310583Y644863D01*
G01X1313300Y653665D02*
X1311633Y644193D01*
G01X1310583Y644863D02*
X1312249Y654336D01*
G01X1313735Y644901D02*
X1315221Y653326D01*
G01X1316437Y653594D02*
X1314951Y645170D01*
G01X1314646Y643597D02*
X1313735Y644901D01*
G01X1314951Y645170D02*
X1315316Y644648D01*
G01X1317923Y644160D02*
X1316620Y643251D01*
G01D02*
X1314646Y643597D01*
G01X1315316Y644648D02*
X1316351Y644466D01*
G01X1317923Y644160D02*
X1316620Y643251D01*
G01X1316351Y644466D02*
X1316873Y644830D01*
G01X1319589Y653617D02*
X1317923Y644160D01*
G01X1316873Y644830D02*
X1318539Y654286D01*
G01X1320031Y644901D02*
X1321508Y653279D01*
G01X1322724Y653548D02*
X1321247Y645170D01*
G01X1320941Y643598D02*
X1320031Y644901D01*
G01X1321247Y645170D02*
X1321611Y644648D01*
G01X1324217Y644161D02*
X1322914Y643251D01*
G01D02*
X1320941Y643598D01*
G01X1321611Y644648D02*
X1322645Y644466D01*
G01X1324217Y644161D02*
X1322914Y643251D01*
G01X1322645Y644466D02*
X1323167Y644831D01*
G01X1325855Y653420D02*
X1324217Y644161D01*
G01X1323167Y644831D02*
X1324805Y654090D01*
G01X1326349Y644995D02*
X1327775Y653081D01*
G01X1328991Y653349D02*
X1327565Y645264D01*
G01X1327286Y643653D02*
X1326349Y644995D01*
G01X1327565Y645264D02*
X1327955Y644704D01*
G01X1330534Y644257D02*
X1329194Y643318D01*
G01D02*
X1327286Y643653D01*
G01X1327955Y644704D02*
X1328924Y644534D01*
G01X1330534Y644257D02*
X1329194Y643318D01*
G01X1328924Y644534D02*
X1329484Y644926D01*
G01X1332149Y653422D02*
X1330534Y644257D01*
G01X1329484Y644926D02*
X1331099Y654092D01*
G01X1332639Y644966D02*
X1334071Y653082D01*
G01X1335287Y653351D02*
X1333855Y645234D01*
G01X1333550Y643659D02*
X1332639Y644966D01*
G01X1333855Y645234D02*
X1334220Y644710D01*
G01X1336827Y644224D02*
X1335521Y643315D01*
G01D02*
X1333550Y643659D01*
G01X1334220Y644710D02*
X1335252Y644530D01*
G01X1336827Y644224D02*
X1335521Y643315D01*
G01X1335252Y644530D02*
X1335776Y644895D01*
G01X1338439Y653389D02*
X1336827Y644224D01*
G01X1335776Y644895D02*
X1337389Y654059D01*
G01X1338934Y644965D02*
X1340361Y653049D01*
G01X1341577Y653318D02*
X1340150Y645234D01*
G01X1339845Y643661D02*
X1338934Y644965D01*
G01X1340150Y645234D02*
X1340515Y644712D01*
G01X1343118Y644224D02*
X1341816Y643314D01*
G01D02*
X1339845Y643661D01*
G01X1340515Y644712D02*
X1341547Y644530D01*
G01X1343118Y644224D02*
X1341816Y643314D01*
G01X1341547Y644530D02*
X1342068Y644894D01*
G01X1340515Y644712D02*
X1341547Y644530D01*
G01D02*
X1342068Y644894D01*
G01X1343118Y644224D02*
X1341816Y643314D01*
G01X1340515Y644712D02*
X1341547Y644530D01*
G01X1341816Y643314D02*
X1339845Y643661D01*
G01X1340150Y645234D02*
X1340515Y644712D01*
G01X1339845Y643661D02*
X1338934Y644965D01*
G01X1341577Y653318D02*
X1340150Y645234D01*
G01X1338934Y644965D02*
X1340361Y653049D01*
G01X1335776Y644895D02*
X1337389Y654059D01*
G01X1338439Y653389D02*
X1336827Y644224D01*
G01X1334220Y644710D02*
X1335252Y644530D01*
G01D02*
X1335776Y644895D01*
G01X1336827Y644224D02*
X1335521Y643315D01*
G01X1334220Y644710D02*
X1335252Y644530D01*
G01X1335521Y643315D02*
X1333550Y643659D01*
G01X1333855Y645234D02*
X1334220Y644710D01*
G01X1333550Y643659D02*
X1332639Y644966D01*
G01X1335287Y653351D02*
X1333855Y645234D01*
G01X1332639Y644966D02*
X1334071Y653082D01*
G01X1329484Y644926D02*
X1331099Y654092D01*
G01X1332149Y653422D02*
X1330534Y644257D01*
G01X1327955Y644704D02*
X1328924Y644534D01*
G01D02*
X1329484Y644926D01*
G01X1330534Y644257D02*
X1329194Y643318D01*
G01X1327955Y644704D02*
X1328924Y644534D01*
G01X1329194Y643318D02*
X1327286Y643653D01*
G01X1327565Y645264D02*
X1327955Y644704D01*
G01X1327286Y643653D02*
X1326349Y644995D01*
G01X1328991Y653349D02*
X1327565Y645264D01*
G01X1326349Y644995D02*
X1327775Y653081D01*
G01X1323167Y644831D02*
X1324805Y654090D01*
G01X1325855Y653420D02*
X1324217Y644161D01*
G01X1321611Y644648D02*
X1322645Y644466D01*
G01D02*
X1323167Y644831D01*
G01X1324217Y644161D02*
X1322914Y643251D01*
G01X1321611Y644648D02*
X1322645Y644466D01*
G01X1322914Y643251D02*
X1320941Y643598D01*
G01X1321247Y645170D02*
X1321611Y644648D01*
G01X1320941Y643598D02*
X1320031Y644901D01*
G01X1322724Y653548D02*
X1321247Y645170D01*
G01X1320031Y644901D02*
X1321508Y653279D01*
G01X1316873Y644830D02*
X1318539Y654286D01*
G01X1319589Y653617D02*
X1317923Y644160D01*
G01X1315316Y644648D02*
X1316351Y644466D01*
G01D02*
X1316873Y644830D01*
G01X1317923Y644160D02*
X1316620Y643251D01*
G01X1315316Y644648D02*
X1316351Y644466D01*
G01X1316620Y643251D02*
X1314646Y643597D01*
G01X1314951Y645170D02*
X1315316Y644648D01*
G01X1314646Y643597D02*
X1313735Y644901D01*
G01X1316437Y653594D02*
X1314951Y645170D01*
G01X1313735Y644901D02*
X1315221Y653326D01*
G01X1310583Y644863D02*
X1312249Y654336D01*
G01X1313300Y653665D02*
X1311633Y644193D01*
G01X1309026Y644681D02*
X1310061Y644499D01*
G01D02*
X1310583Y644863D01*
G01X1311633Y644193D02*
X1310330Y643284D01*
G01X1309026Y644681D02*
X1310061Y644499D01*
G01X1310330Y643284D02*
X1308356Y643630D01*
G01X1308661Y645203D02*
X1309026Y644681D01*
G01X1308356Y643630D02*
X1307445Y644934D01*
G01X1310139Y653578D02*
X1308661Y645203D01*
G01X1307445Y644934D02*
X1308923Y653309D01*
G01X1304286Y644863D02*
X1305955Y654319D01*
G01X1307005Y653649D02*
X1305336Y644193D01*
G01X1302730Y644680D02*
X1303764Y644499D01*
G01D02*
X1304286Y644863D01*
G01X1305336Y644193D02*
X1304033Y643284D01*
G01X1302730Y644680D02*
X1303764Y644499D01*
G01X1304033Y643284D02*
X1302060Y643629D01*
G01X1302366Y645201D02*
X1302730Y644680D01*
G01X1302060Y643629D02*
X1301150Y644932D01*
G01X1303843Y653577D02*
X1302366Y645201D01*
G01X1301150Y644932D02*
X1302627Y653309D01*
G01X1297988Y644845D02*
X1299656Y654314D01*
G01X1300707Y653645D02*
X1299038Y644175D01*
G01X1296432Y644663D02*
X1297466Y644480D01*
G01D02*
X1297988Y644845D01*
G01X1299038Y644175D02*
X1297735Y643265D01*
G01X1296432Y644663D02*
X1297466Y644480D01*
G01X1297735Y643265D02*
X1295762Y643613D01*
G01X1296069Y645185D02*
X1296432Y644663D01*
G01X1295762Y643613D02*
X1294853Y644914D01*
G01X1297569Y653692D02*
X1296069Y645185D01*
G01X1294853Y644914D02*
X1296353Y653422D01*
G01X1291690Y644845D02*
X1293380Y654426D01*
G01X1294431Y653758D02*
X1292740Y644176D01*
G01X1290136Y644663D02*
X1291170Y644481D01*
G01D02*
X1291690Y644845D01*
G01X1292740Y644176D02*
X1291440Y643265D01*
G01X1290136Y644663D02*
X1291170Y644481D01*
G01X1291440Y643265D02*
X1289466Y643612D01*
G01X1289772Y645184D02*
X1290136Y644663D01*
G01X1289466Y643612D02*
X1288556Y644915D01*
G01X1291272Y653695D02*
X1289772Y645184D01*
G01X1288556Y644915D02*
X1290056Y653424D01*
G01X1285402Y644879D02*
X1287085Y654431D01*
G01X1288135Y653761D02*
X1286453Y644209D01*
G01X1283845Y644696D02*
X1284879Y644514D01*
G01D02*
X1285402Y644879D01*
G01X1286453Y644209D02*
X1285149Y643299D01*
G01X1283845Y644696D02*
X1284879Y644514D01*
G01X1285149Y643299D02*
X1283175Y643645D01*
G01X1283481Y645217D02*
X1283845Y644696D01*
G01X1283175Y643645D02*
X1282265Y644948D01*
G01X1284972Y653673D02*
X1283481Y645217D01*
G01X1282265Y644948D02*
X1283756Y653404D01*
G01X1283391Y653926D02*
X1282358Y654107D01*
G01D02*
X1281836Y653742D01*
G01X1280785Y654412D02*
X1282088Y655322D01*
G01X1283391Y653926D02*
X1282358Y654107D01*
G01X1282088Y655322D02*
X1284060Y654977D01*
G01X1283756Y653404D02*
X1283391Y653926D01*
G01X1284060Y654977D02*
X1284972Y653673D01*
G01X1289690Y653944D02*
X1288657Y654125D01*
G01D02*
X1288135Y653761D01*
G01X1287085Y654431D02*
X1288388Y655340D01*
G01X1289690Y653944D02*
X1288657Y654125D01*
G01X1288388Y655340D02*
X1290357Y654995D01*
G01X1290056Y653424D02*
X1289690Y653944D01*
G01X1290357Y654995D02*
X1291272Y653695D01*
G01X1295988Y653943D02*
X1294954Y654126D01*
G01D02*
X1294431Y653758D01*
G01X1293380Y654426D02*
X1294683Y655342D01*
G01X1295988Y653943D02*
X1294954Y654126D01*
G01X1294683Y655342D02*
X1296657Y654993D01*
G01X1296353Y653422D02*
X1295988Y653943D01*
G01X1296657Y654993D02*
X1297569Y653692D01*
G01X1302263Y653831D02*
X1301230Y654012D01*
G01D02*
X1300707Y653645D01*
G01X1299656Y654314D02*
X1300959Y655228D01*
G01X1302263Y653831D02*
X1301230Y654012D01*
G01X1300959Y655228D02*
X1302933Y654882D01*
G01X1302627Y653309D02*
X1302263Y653831D01*
G01X1302933Y654882D02*
X1303843Y653577D01*
G01X1308558Y653831D02*
X1307526Y654013D01*
G01D02*
X1307005Y653649D01*
G01X1305955Y654319D02*
X1307257Y655229D01*
G01X1308558Y653831D02*
X1307526Y654013D01*
G01X1307257Y655229D02*
X1309228Y654882D01*
G01X1308923Y653309D02*
X1308558Y653831D01*
G01X1309228Y654882D02*
X1310139Y653578D01*
G01X1314856Y653850D02*
X1313824Y654030D01*
G01D02*
X1313300Y653665D01*
G01X1312249Y654336D02*
X1313555Y655245D01*
G01X1314856Y653850D02*
X1313824Y654030D01*
G01X1313555Y655245D02*
X1315526Y654901D01*
G01X1315221Y653326D02*
X1314856Y653850D01*
G01X1315526Y654901D02*
X1316437Y653594D01*
G01X1321117Y653839D02*
X1320149Y654009D01*
G01D02*
X1319589Y653617D01*
G01X1318539Y654286D02*
X1319879Y655225D01*
G01X1321117Y653839D02*
X1320149Y654009D01*
G01X1319879Y655225D02*
X1321787Y654890D01*
G01X1321508Y653279D02*
X1321117Y653839D01*
G01X1321787Y654890D02*
X1322724Y653548D01*
G01X1327411Y653603D02*
X1326377Y653785D01*
G01D02*
X1325855Y653420D01*
G01X1324805Y654090D02*
X1326108Y655001D01*
G01X1327411Y653603D02*
X1326377Y653785D01*
G01X1326108Y655001D02*
X1328081Y654653D01*
G01X1327775Y653081D02*
X1327411Y653603D01*
G01X1328081Y654653D02*
X1328991Y653349D01*
G01X1333706Y653604D02*
X1332671Y653786D01*
G01D02*
X1332149Y653422D01*
G01X1331099Y654092D02*
X1332402Y655001D01*
G01X1333706Y653604D02*
X1332671Y653786D01*
G01X1332402Y655001D02*
X1334376Y654655D01*
G01X1334071Y653082D02*
X1333706Y653604D01*
G01X1334376Y654655D02*
X1335287Y653351D01*
G01X1339996Y653571D02*
X1338961Y653753D01*
G01D02*
X1338439Y653389D01*
G01X1337389Y654059D02*
X1338692Y654968D01*
G01X1339996Y653571D02*
X1338961Y653753D01*
G01X1338692Y654968D02*
X1340666Y654622D01*
G01X1340361Y653049D02*
X1339996Y653571D01*
G01X1340666Y654622D02*
X1341577Y653318D01*
G01X1340666Y654622D02*
X1341577Y653318D01*
G01X1340361Y653049D02*
X1339996Y653571D01*
G01X1337389Y654059D02*
X1338692Y654968D01*
G01D02*
X1340666Y654622D01*
G01X1339996Y653571D02*
X1338961Y653753D01*
G01X1337389Y654059D02*
X1338692Y654968D01*
G01X1338961Y653753D02*
X1338439Y653389D01*
G01X1334376Y654655D02*
X1335287Y653351D01*
G01X1334071Y653082D02*
X1333706Y653604D01*
G01X1331099Y654092D02*
X1332402Y655001D01*
G01D02*
X1334376Y654655D01*
G01X1333706Y653604D02*
X1332671Y653786D01*
G01X1331099Y654092D02*
X1332402Y655001D01*
G01X1332671Y653786D02*
X1332149Y653422D01*
G01X1328081Y654653D02*
X1328991Y653349D01*
G01X1327775Y653081D02*
X1327411Y653603D01*
G01X1324805Y654090D02*
X1326108Y655001D01*
G01D02*
X1328081Y654653D01*
G01X1327411Y653603D02*
X1326377Y653785D01*
G01X1324805Y654090D02*
X1326108Y655001D01*
G01X1326377Y653785D02*
X1325855Y653420D01*
G01X1321787Y654890D02*
X1322724Y653548D01*
G01X1321508Y653279D02*
X1321117Y653839D01*
G01X1318539Y654286D02*
X1319879Y655225D01*
G01D02*
X1321787Y654890D01*
G01X1321117Y653839D02*
X1320149Y654009D01*
G01X1318539Y654286D02*
X1319879Y655225D01*
G01X1320149Y654009D02*
X1319589Y653617D01*
G01X1315526Y654901D02*
X1316437Y653594D01*
G01X1315221Y653326D02*
X1314856Y653850D01*
G01X1312249Y654336D02*
X1313555Y655245D01*
G01D02*
X1315526Y654901D01*
G01X1314856Y653850D02*
X1313824Y654030D01*
G01X1312249Y654336D02*
X1313555Y655245D01*
G01X1313824Y654030D02*
X1313300Y653665D01*
G01X1309228Y654882D02*
X1310139Y653578D01*
G01X1308923Y653309D02*
X1308558Y653831D01*
G01X1305955Y654319D02*
X1307257Y655229D01*
G01D02*
X1309228Y654882D01*
G01X1308558Y653831D02*
X1307526Y654013D01*
G01X1305955Y654319D02*
X1307257Y655229D01*
G01X1307526Y654013D02*
X1307005Y653649D01*
G01X1302933Y654882D02*
X1303843Y653577D01*
G01X1302627Y653309D02*
X1302263Y653831D01*
G01X1299656Y654314D02*
X1300959Y655228D01*
G01D02*
X1302933Y654882D01*
G01X1302263Y653831D02*
X1301230Y654012D01*
G01X1299656Y654314D02*
X1300959Y655228D01*
G01X1301230Y654012D02*
X1300707Y653645D01*
G01X1296657Y654993D02*
X1297569Y653692D01*
G01X1296353Y653422D02*
X1295988Y653943D01*
G01X1293380Y654426D02*
X1294683Y655342D01*
G01D02*
X1296657Y654993D01*
G01X1295988Y653943D02*
X1294954Y654126D01*
G01X1293380Y654426D02*
X1294683Y655342D01*
G01X1294954Y654126D02*
X1294431Y653758D01*
G01X1290357Y654995D02*
X1291272Y653695D01*
G01X1290056Y653424D02*
X1289690Y653944D01*
G01X1287085Y654431D02*
X1288388Y655340D01*
G01D02*
X1290357Y654995D01*
G01X1289690Y653944D02*
X1288657Y654125D01*
G01X1287085Y654431D02*
X1288388Y655340D01*
G01X1288657Y654125D02*
X1288135Y653761D01*
G01X1284060Y654977D02*
X1284972Y653673D01*
G01X1283756Y653404D02*
X1283391Y653926D01*
G01X1280785Y654412D02*
X1282088Y655322D01*
G01D02*
X1284060Y654977D01*
G01X1283391Y653926D02*
X1282358Y654107D01*
G01X1280785Y654412D02*
X1282088Y655322D01*
G01X1282358Y654107D02*
X1281836Y653742D01*
G01X1401121Y173708D02*
X1406223Y170366D01*
G01X1400645Y172644D02*
X1405345Y169565D01*
G01X1405458Y163830D02*
X1403334Y167834D01*
G01X1404212Y168635D02*
X1400061Y171355D01*
G01X1403334Y167834D02*
X1399585Y170291D01*
G01X1400645Y172644D02*
X1405345Y169565D01*
G01X1401121Y173708D02*
X1406223Y170366D01*
G01X1405458Y163830D02*
X1403334Y167834D01*
G01D02*
X1399585Y170291D01*
G01X1404212Y168635D02*
X1400061Y171355D01*
G01X1403382Y178324D02*
X1410316Y173780D01*
G01X1402906Y177260D02*
X1409438Y172980D01*
G01X1402201Y176047D02*
X1408321Y172040D01*
G01X1401725Y174983D02*
X1407443Y171239D01*
G01X1402906Y177260D02*
X1409438Y172980D01*
G01X1403382Y178324D02*
X1410316Y173780D01*
G01X1401725Y174983D02*
X1407443Y171239D01*
G01X1402201Y176047D02*
X1408321Y172040D01*
G01X1410626Y290872D02*
X1403625Y275708D01*
G01X1403657Y269832D02*
X1404728Y275352D01*
G01X1403625Y275708D02*
X1402471Y269761D01*
G01X1404999Y265663D02*
X1403657Y269832D01*
G01X1402471Y269761D02*
X1403958Y265143D01*
G01X1402471Y269761D02*
X1403958Y265143D01*
G01X1404999Y265663D02*
X1403657Y269832D01*
G01X1403625Y275708D02*
X1402471Y269761D01*
G01X1403657Y269832D02*
X1404728Y275352D01*
G01X1410626Y290872D02*
X1403625Y275708D01*
G01X1361171Y472871D02*
X1410889Y462299D01*
G01X1361171Y472871D02*
X1410889Y462299D01*
G01X1348791Y490447D02*
X1355548Y497204D01*
G01X1348314Y491597D02*
X1354398Y497681D01*
G01X1355548Y497204D02*
Y500735D01*
G01X1354398Y497681D02*
Y501212D01*
G01X1355548Y500735D02*
X1359698Y504885D01*
G01X1354398Y501212D02*
X1359221Y506035D01*
G01X1359698Y504885D02*
X1378713D01*
G01X1359221Y506035D02*
X1378236D01*
G01X1378713Y504885D02*
X1380128Y506300D01*
G01X1378236Y506035D02*
X1379651Y507450D01*
G01X1380128Y506300D02*
X1392057D01*
G01X1379651Y507450D02*
X1392208D01*
G01X1392057Y506300D02*
X1411809Y501023D01*
G01X1392208Y507450D02*
X1411960Y502173D01*
G01X1348314Y491597D02*
X1354398Y497681D01*
G01X1348791Y490447D02*
X1355548Y497204D01*
G01X1354398Y497681D02*
Y501212D01*
G01X1355548Y497204D02*
Y500735D01*
G01X1354398Y501212D02*
X1359221Y506035D01*
G01X1355548Y500735D02*
X1359698Y504885D01*
G01X1359221Y506035D02*
X1378236D01*
G01X1359698Y504885D02*
X1378713D01*
G01X1378236Y506035D02*
X1379651Y507450D01*
G01X1378713Y504885D02*
X1380128Y506300D01*
G01X1379651Y507450D02*
X1392208D01*
G01X1380128Y506300D02*
X1392057D01*
G01X1392208Y507450D02*
X1411960Y502173D01*
G01X1392057Y506300D02*
X1411809Y501023D01*
G01X1390470Y496940D02*
X1389240Y496938D01*
G01D02*
X1389170D01*
G01X1389242Y495788D02*
X1390843Y495790D01*
G01X1391330Y497562D02*
X1390470Y496940D01*
G01D02*
X1389240Y496938D01*
G01X1390843Y495790D02*
X1392480Y496974D01*
G01X1391330Y499710D02*
Y497562D01*
G01X1392480Y496974D02*
Y500187D01*
G01X1390340Y500700D02*
X1391330Y499710D01*
G01X1392480Y500187D02*
X1390817Y501850D01*
G01X1382314Y500700D02*
X1390340D01*
G01X1390817Y501850D02*
X1381837D01*
G01X1380995Y499381D02*
X1382314Y500700D01*
G01X1381837Y501850D02*
X1380518Y500531D01*
G01X1362123Y499381D02*
X1372995D01*
G01X1375645D02*
X1376995D01*
G01X1379645D02*
X1380995D01*
G01X1380518Y500531D02*
X1361646D01*
G01X1361052Y498310D02*
X1362123Y499381D01*
G01X1361646Y500531D02*
X1359902Y498787D01*
G01X1361052Y495102D02*
Y498310D01*
G01X1359902Y498787D02*
Y495579D01*
G01X1355613Y489663D02*
X1358224Y492274D01*
G01D02*
X1359143D01*
G01X1360097Y494147D02*
X1361052Y495102D01*
G01X1359902Y495579D02*
X1354463Y490140D01*
G01X1355613Y478660D02*
Y489663D01*
G01X1354463Y490140D02*
Y478328D01*
G01X1356883Y476640D02*
X1355613Y478660D01*
G01X1354463Y478328D02*
X1356062Y475783D01*
G01X1361585Y473959D02*
X1356883Y476640D01*
G01X1356062Y475783D02*
X1361171Y472871D01*
G01X1411382Y463371D02*
X1361585Y473959D01*
G01X1411382Y463371D02*
X1361585Y473959D01*
G01X1356062Y475783D02*
X1361171Y472871D01*
G01X1361585Y473959D02*
X1356883Y476640D01*
G01X1354463Y478328D02*
X1356062Y475783D01*
G01X1356883Y476640D02*
X1355613Y478660D01*
G01X1354463Y490140D02*
Y478328D01*
G01X1355613Y478660D02*
Y489663D01*
G01X1359902Y495579D02*
X1354463Y490140D01*
G01X1355613Y489663D02*
X1358224Y492274D01*
G01X1359902Y495579D02*
X1354463Y490140D01*
G01X1358224Y492274D02*
X1359143D01*
G01X1359902Y495579D02*
X1354463Y490140D01*
G01X1360097Y494147D02*
X1361052Y495102D01*
G01X1359902Y498787D02*
Y495579D01*
G01X1361052Y495102D02*
Y498310D01*
G01X1361646Y500531D02*
X1359902Y498787D01*
G01X1361052Y498310D02*
X1362123Y499381D01*
G01X1380518Y500531D02*
X1361646D01*
G01X1362123Y499381D02*
X1372995D01*
G01X1380518Y500531D02*
X1361646D01*
G01X1375645Y499381D02*
X1376995D01*
G01X1380518Y500531D02*
X1361646D01*
G01X1379645Y499381D02*
X1380995D01*
G01X1381837Y501850D02*
X1380518Y500531D01*
G01X1380995Y499381D02*
X1382314Y500700D01*
G01X1390817Y501850D02*
X1381837D01*
G01X1382314Y500700D02*
X1390340D01*
G01X1392480Y500187D02*
X1390817Y501850D01*
G01X1390340Y500700D02*
X1391330Y499710D01*
G01X1392480Y496974D02*
Y500187D01*
G01X1391330Y499710D02*
Y497562D01*
G01X1390843Y495790D02*
X1392480Y496974D01*
G01X1391330Y497562D02*
X1390470Y496940D01*
G01X1389242Y495788D02*
X1390843Y495790D01*
G01D02*
X1392480Y496974D01*
G01X1390470Y496940D02*
X1389240Y496938D01*
G01X1389242Y495788D02*
X1390843Y495790D01*
G01X1389240Y496938D02*
X1389170D01*
G01X1382055Y477946D02*
X1414399Y471071D01*
G01X1413906Y469999D02*
X1381482Y476891D01*
G01X1378401Y481599D02*
X1382055Y477946D01*
G01X1381482Y476891D02*
X1377251Y481122D01*
G01X1378401Y483500D02*
Y481599D01*
G01X1377251Y481122D02*
Y483977D01*
G01X1379301Y484400D02*
X1378401Y483500D01*
G01X1377251Y483977D02*
X1378824Y485550D01*
G01X1384464Y484400D02*
X1379301D01*
G01X1378824Y485550D02*
X1384468D01*
G01X1367882Y484682D02*
X1371780D01*
G01X1368050Y483532D02*
X1371303D01*
G01X1371780Y484682D02*
X1380600Y475862D01*
G01X1371303Y483532D02*
X1372258Y482577D01*
G01X1371780Y484682D02*
X1380600Y475862D01*
G01X1373212Y480704D02*
X1374131D01*
G01X1371780Y484682D02*
X1380600Y475862D01*
G01X1374131Y480704D02*
X1375086Y479749D01*
G01X1371780Y484682D02*
X1380600Y475862D01*
G01X1376040Y477876D02*
X1376959D01*
G01X1371780Y484682D02*
X1380600Y475862D01*
G01X1376959Y477876D02*
X1377914Y476921D01*
G01X1371780Y484682D02*
X1380600Y475862D01*
G01D02*
X1380601D01*
G01X1378868Y475048D02*
X1379787D01*
G01X1380601Y475862D02*
X1381322Y475141D01*
G01X1379787Y475048D02*
X1380749Y474086D01*
G01X1381322Y475141D02*
X1413716Y468256D01*
G01X1380749Y474086D02*
X1413223Y467184D01*
G01X1368891Y495698D02*
X1370336D01*
G01X1368891Y494548D02*
X1369859D01*
G01X1370336Y495698D02*
X1371971Y494063D01*
G01X1369859Y494548D02*
X1370821Y493586D01*
G01X1371971Y494063D02*
Y491548D01*
G01X1370821Y493586D02*
Y492025D01*
G01X1371971Y491548D02*
X1369471Y489048D01*
G01X1370821Y492025D02*
X1368994Y490198D01*
G01X1369471Y489048D02*
X1359691D01*
G01X1368994Y490198D02*
X1359214D01*
G01X1359691Y489048D02*
X1358216Y487573D01*
G01X1359214Y490198D02*
X1357066Y488050D01*
G01X1358216Y487573D02*
Y479677D01*
G01X1357066Y488050D02*
Y479346D01*
G01X1358216Y479677D02*
X1358945Y478516D01*
G01X1357066Y479346D02*
X1358124Y477660D01*
G01X1358945Y478516D02*
X1362855Y476286D01*
G01X1358124Y477660D02*
X1362441Y475198D01*
G01X1362855Y476286D02*
X1412717Y465686D01*
G01X1362441Y475198D02*
X1412224Y464614D01*
G01X1378824Y485550D02*
X1384468D01*
G01X1384464Y484400D02*
X1379301D01*
G01X1377251Y483977D02*
X1378824Y485550D01*
G01X1379301Y484400D02*
X1378401Y483500D01*
G01X1377251Y481122D02*
Y483977D01*
G01X1378401Y483500D02*
Y481599D01*
G01X1381482Y476891D02*
X1377251Y481122D01*
G01X1378401Y481599D02*
X1382055Y477946D01*
G01X1413906Y469999D02*
X1381482Y476891D01*
G01X1382055Y477946D02*
X1414399Y471071D01*
G01X1368050Y483532D02*
X1371303D01*
G01X1367882Y484682D02*
X1371780D01*
G01X1371303Y483532D02*
X1372258Y482577D01*
G01X1373212Y480704D02*
X1374131D01*
G01D02*
X1375086Y479749D01*
G01X1376040Y477876D02*
X1376959D01*
G01D02*
X1377914Y476921D01*
G01X1378868Y475048D02*
X1379787D01*
G01X1371780Y484682D02*
X1380600Y475862D01*
G01X1378868Y475048D02*
X1379787D01*
G01X1380600Y475862D02*
X1380601D01*
G01X1379787Y475048D02*
X1380749Y474086D01*
G01X1380601Y475862D02*
X1381322Y475141D01*
G01X1380749Y474086D02*
X1413223Y467184D01*
G01X1381322Y475141D02*
X1413716Y468256D01*
G01X1368891Y494548D02*
X1369859D01*
G01X1368891Y495698D02*
X1370336D01*
G01X1369859Y494548D02*
X1370821Y493586D01*
G01X1370336Y495698D02*
X1371971Y494063D01*
G01X1370821Y493586D02*
Y492025D01*
G01X1371971Y494063D02*
Y491548D01*
G01X1370821Y492025D02*
X1368994Y490198D01*
G01X1371971Y491548D02*
X1369471Y489048D01*
G01X1368994Y490198D02*
X1359214D01*
G01X1369471Y489048D02*
X1359691D01*
G01X1359214Y490198D02*
X1357066Y488050D01*
G01X1359691Y489048D02*
X1358216Y487573D01*
G01X1357066Y488050D02*
Y479346D01*
G01X1358216Y487573D02*
Y479677D01*
G01X1357066Y479346D02*
X1358124Y477660D01*
G01X1358216Y479677D02*
X1358945Y478516D01*
G01X1358124Y477660D02*
X1362441Y475198D01*
G01X1358945Y478516D02*
X1362855Y476286D01*
G01X1362441Y475198D02*
X1412224Y464614D01*
G01X1362855Y476286D02*
X1412717Y465686D01*
G01X1398023Y540250D02*
X1413360D01*
G01X1413837Y541400D02*
X1398500D01*
G01X1391734Y546539D02*
X1398023Y540250D01*
G01X1398500Y541400D02*
X1392211Y547689D01*
G01X1383466Y546539D02*
X1391734D01*
G01X1392211Y547689D02*
X1382989D01*
G01X1382453Y545526D02*
X1383466Y546539D01*
G01X1382989Y547689D02*
X1381976Y546676D01*
G01X1370557Y545526D02*
X1382453D01*
G01X1381976Y546676D02*
X1370080D01*
G01X1368888Y543857D02*
X1370557Y545526D01*
G01X1370080Y546676D02*
X1368411Y545007D01*
G01X1355227Y543857D02*
X1368888D01*
G01X1368411Y545007D02*
X1354750D01*
G01X1351101Y539731D02*
X1355227Y543857D01*
G01X1354750Y545007D02*
X1350624Y540881D01*
G01X1354750Y545007D02*
X1350624Y540881D01*
G01X1351101Y539731D02*
X1355227Y543857D01*
G01X1368411Y545007D02*
X1354750D01*
G01X1355227Y543857D02*
X1368888D01*
G01X1370080Y546676D02*
X1368411Y545007D01*
G01X1368888Y543857D02*
X1370557Y545526D01*
G01X1381976Y546676D02*
X1370080D01*
G01X1370557Y545526D02*
X1382453D01*
G01X1382989Y547689D02*
X1381976Y546676D01*
G01X1382453Y545526D02*
X1383466Y546539D01*
G01X1392211Y547689D02*
X1382989D01*
G01X1383466Y546539D02*
X1391734D01*
G01X1398500Y541400D02*
X1392211Y547689D01*
G01X1391734Y546539D02*
X1398023Y540250D01*
G01X1413837Y541400D02*
X1398500D01*
G01X1398023Y540250D02*
X1413360D01*
G01X1344736Y653389D02*
X1343118Y644224D01*
G01X1342068Y644894D02*
X1343686Y654059D01*
G01X1345230Y644966D02*
X1346656Y653051D01*
G01X1347872Y653320D02*
X1346446Y645234D01*
G01X1346140Y643661D02*
X1345230Y644966D01*
G01X1346446Y645234D02*
X1346810Y644712D01*
G01X1349417Y644229D02*
X1348114Y643315D01*
G01D02*
X1346140Y643661D01*
G01X1346810Y644712D02*
X1347843Y644531D01*
G01X1349417Y644229D02*
X1348114Y643315D01*
G01X1347843Y644531D02*
X1348366Y644898D01*
G01X1351034Y653407D02*
X1349417Y644229D01*
G01X1348366Y644898D02*
X1349984Y654077D01*
G01X1351507Y644868D02*
X1352953Y653067D01*
G01X1354169Y653338D02*
X1352723Y645138D01*
G01X1352419Y643567D02*
X1351507Y644868D01*
G01X1352723Y645138D02*
X1353088Y644617D01*
G01X1355696Y644134D02*
X1354393Y643218D01*
G01D02*
X1352419Y643567D01*
G01X1353088Y644617D02*
X1354122Y644434D01*
G01X1355696Y644134D02*
X1354393Y643218D01*
G01X1354122Y644434D02*
X1354645Y644802D01*
G01X1357332Y653407D02*
X1355696Y644134D01*
G01X1354645Y644802D02*
X1356282Y654076D01*
G01X1357818Y644945D02*
X1359250Y653068D01*
G01X1360466Y653337D02*
X1359034Y645216D01*
G01X1358733Y643645D02*
X1357818Y644945D01*
G01X1359034Y645216D02*
X1359400Y644696D01*
G01X1362005Y644209D02*
X1360702Y643300D01*
G01D02*
X1358733Y643645D01*
G01X1359400Y644696D02*
X1360433Y644515D01*
G01X1362005Y644209D02*
X1360702Y643300D01*
G01X1360433Y644515D02*
X1360955Y644879D01*
G01X1363620Y653373D02*
X1362005Y644209D01*
G01X1360955Y644879D02*
X1362569Y654043D01*
G01X1364118Y644967D02*
X1365541Y653035D01*
G01X1366757Y653304D02*
X1365334Y645236D01*
G01X1365030Y643663D02*
X1364118Y644967D01*
G01X1365334Y645236D02*
X1365699Y644714D01*
G01X1368305Y644228D02*
X1367002Y643318D01*
G01D02*
X1365030Y643663D01*
G01X1365699Y644714D02*
X1366732Y644533D01*
G01X1368305Y644228D02*
X1367002Y643318D01*
G01X1366732Y644533D02*
X1367254Y644898D01*
G01X1369915Y653374D02*
X1368305Y644228D01*
G01X1367254Y644898D02*
X1368865Y654044D01*
G01X1370413Y644970D02*
X1371837Y653036D01*
G01X1373053Y653305D02*
X1371629Y645238D01*
G01X1371322Y643666D02*
X1370413Y644970D01*
G01X1371629Y645238D02*
X1371994Y644715D01*
G01X1374600Y644232D02*
X1373296Y643318D01*
G01D02*
X1371322Y643666D01*
G01X1371994Y644715D02*
X1373026Y644534D01*
G01X1374600Y644232D02*
X1373296Y643318D01*
G01X1373026Y644534D02*
X1373550Y644901D01*
G01X1376216Y653394D02*
X1374600Y644232D01*
G01X1373550Y644901D02*
X1375166Y654063D01*
G01X1376703Y644935D02*
X1378136Y653050D01*
G01X1379352Y653320D02*
X1377919Y645204D01*
G01X1377614Y643631D02*
X1376703Y644935D01*
G01X1377919Y645204D02*
X1378284Y644682D01*
G01X1380889Y644196D02*
X1379588Y643284D01*
G01D02*
X1377614Y643631D01*
G01X1378284Y644682D02*
X1379318Y644500D01*
G01X1380889Y644196D02*
X1379588Y643284D01*
G01X1379318Y644500D02*
X1379839Y644865D01*
G01X1382504Y653361D02*
X1380889Y644196D01*
G01X1379839Y644865D02*
X1381454Y654031D01*
G01X1382994Y644905D02*
X1384426Y653021D01*
G01X1385642Y653290D02*
X1384210Y645173D01*
G01X1383905Y643598D02*
X1382994Y644905D01*
G01X1384210Y645173D02*
X1384575Y644649D01*
G01X1387182Y644163D02*
X1385876Y643254D01*
G01D02*
X1383905Y643598D01*
G01X1384575Y644649D02*
X1385607Y644469D01*
G01X1387182Y644163D02*
X1385876Y643254D01*
G01X1385607Y644469D02*
X1386131Y644834D01*
G01X1388794Y653328D02*
X1387182Y644163D01*
G01X1386131Y644834D02*
X1387744Y653998D01*
G01X1389289Y644904D02*
X1390716Y652988D01*
G01X1391932Y653257D02*
X1390505Y645173D01*
G01X1390200Y643600D02*
X1389289Y644904D01*
G01X1390505Y645173D02*
X1390870Y644651D01*
G01X1393473Y644163D02*
X1392171Y643253D01*
G01D02*
X1390200Y643600D01*
G01X1390870Y644651D02*
X1391902Y644469D01*
G01X1393473Y644163D02*
X1392171Y643253D01*
G01X1391902Y644469D02*
X1392423Y644833D01*
G01X1395091Y653328D02*
X1393473Y644163D01*
G01X1392423Y644833D02*
X1394041Y653998D01*
G01X1395585Y644905D02*
X1397011Y652990D01*
G01X1398227Y653259D02*
X1396801Y645173D01*
G01X1396495Y643600D02*
X1395585Y644905D01*
G01X1396801Y645173D02*
X1397165Y644651D01*
G01X1399772Y644168D02*
X1398469Y643254D01*
G01D02*
X1396495Y643600D01*
G01X1397165Y644651D02*
X1398198Y644470D01*
G01X1399772Y644168D02*
X1398469Y643254D01*
G01X1398198Y644470D02*
X1398721Y644837D01*
G01X1401389Y653346D02*
X1399772Y644168D01*
G01X1398721Y644837D02*
X1400339Y654016D01*
G01X1401876Y644887D02*
X1403308Y653006D01*
G01X1404524Y653277D02*
X1403092Y645157D01*
G01X1402788Y643586D02*
X1401876Y644887D01*
G01X1403092Y645157D02*
X1403457Y644636D01*
G01X1404762Y643237D02*
X1402788Y643586D01*
G01X1403457Y644636D02*
X1404491Y644453D01*
G01X1403457Y644636D02*
X1404491Y644453D01*
G01X1403457Y644636D02*
X1404491Y644453D01*
G01X1404762Y643237D02*
X1402788Y643586D01*
G01X1403092Y645157D02*
X1403457Y644636D01*
G01X1402788Y643586D02*
X1401876Y644887D01*
G01X1404524Y653277D02*
X1403092Y645157D01*
G01X1401876Y644887D02*
X1403308Y653006D01*
G01X1398721Y644837D02*
X1400339Y654016D01*
G01X1401389Y653346D02*
X1399772Y644168D01*
G01X1397165Y644651D02*
X1398198Y644470D01*
G01D02*
X1398721Y644837D01*
G01X1399772Y644168D02*
X1398469Y643254D01*
G01X1397165Y644651D02*
X1398198Y644470D01*
G01X1398469Y643254D02*
X1396495Y643600D01*
G01X1396801Y645173D02*
X1397165Y644651D01*
G01X1396495Y643600D02*
X1395585Y644905D01*
G01X1398227Y653259D02*
X1396801Y645173D01*
G01X1395585Y644905D02*
X1397011Y652990D01*
G01X1392423Y644833D02*
X1394041Y653998D01*
G01X1395091Y653328D02*
X1393473Y644163D01*
G01X1390870Y644651D02*
X1391902Y644469D01*
G01D02*
X1392423Y644833D01*
G01X1393473Y644163D02*
X1392171Y643253D01*
G01X1390870Y644651D02*
X1391902Y644469D01*
G01X1392171Y643253D02*
X1390200Y643600D01*
G01X1390505Y645173D02*
X1390870Y644651D01*
G01X1390200Y643600D02*
X1389289Y644904D01*
G01X1391932Y653257D02*
X1390505Y645173D01*
G01X1389289Y644904D02*
X1390716Y652988D01*
G01X1386131Y644834D02*
X1387744Y653998D01*
G01X1388794Y653328D02*
X1387182Y644163D01*
G01X1384575Y644649D02*
X1385607Y644469D01*
G01D02*
X1386131Y644834D01*
G01X1387182Y644163D02*
X1385876Y643254D01*
G01X1384575Y644649D02*
X1385607Y644469D01*
G01X1385876Y643254D02*
X1383905Y643598D01*
G01X1384210Y645173D02*
X1384575Y644649D01*
G01X1383905Y643598D02*
X1382994Y644905D01*
G01X1385642Y653290D02*
X1384210Y645173D01*
G01X1382994Y644905D02*
X1384426Y653021D01*
G01X1379839Y644865D02*
X1381454Y654031D01*
G01X1382504Y653361D02*
X1380889Y644196D01*
G01X1378284Y644682D02*
X1379318Y644500D01*
G01D02*
X1379839Y644865D01*
G01X1380889Y644196D02*
X1379588Y643284D01*
G01X1378284Y644682D02*
X1379318Y644500D01*
G01X1379588Y643284D02*
X1377614Y643631D01*
G01X1377919Y645204D02*
X1378284Y644682D01*
G01X1377614Y643631D02*
X1376703Y644935D01*
G01X1379352Y653320D02*
X1377919Y645204D01*
G01X1376703Y644935D02*
X1378136Y653050D01*
G01X1373550Y644901D02*
X1375166Y654063D01*
G01X1376216Y653394D02*
X1374600Y644232D01*
G01X1371994Y644715D02*
X1373026Y644534D01*
G01D02*
X1373550Y644901D01*
G01X1374600Y644232D02*
X1373296Y643318D01*
G01X1371994Y644715D02*
X1373026Y644534D01*
G01X1373296Y643318D02*
X1371322Y643666D01*
G01X1371629Y645238D02*
X1371994Y644715D01*
G01X1371322Y643666D02*
X1370413Y644970D01*
G01X1373053Y653305D02*
X1371629Y645238D01*
G01X1370413Y644970D02*
X1371837Y653036D01*
G01X1367254Y644898D02*
X1368865Y654044D01*
G01X1369915Y653374D02*
X1368305Y644228D01*
G01X1365699Y644714D02*
X1366732Y644533D01*
G01D02*
X1367254Y644898D01*
G01X1368305Y644228D02*
X1367002Y643318D01*
G01X1365699Y644714D02*
X1366732Y644533D01*
G01X1367002Y643318D02*
X1365030Y643663D01*
G01X1365334Y645236D02*
X1365699Y644714D01*
G01X1365030Y643663D02*
X1364118Y644967D01*
G01X1366757Y653304D02*
X1365334Y645236D01*
G01X1364118Y644967D02*
X1365541Y653035D01*
G01X1360955Y644879D02*
X1362569Y654043D01*
G01X1363620Y653373D02*
X1362005Y644209D01*
G01X1359400Y644696D02*
X1360433Y644515D01*
G01D02*
X1360955Y644879D01*
G01X1362005Y644209D02*
X1360702Y643300D01*
G01X1359400Y644696D02*
X1360433Y644515D01*
G01X1360702Y643300D02*
X1358733Y643645D01*
G01X1359034Y645216D02*
X1359400Y644696D01*
G01X1358733Y643645D02*
X1357818Y644945D01*
G01X1360466Y653337D02*
X1359034Y645216D01*
G01X1357818Y644945D02*
X1359250Y653068D01*
G01X1354645Y644802D02*
X1356282Y654076D01*
G01X1357332Y653407D02*
X1355696Y644134D01*
G01X1353088Y644617D02*
X1354122Y644434D01*
G01D02*
X1354645Y644802D01*
G01X1355696Y644134D02*
X1354393Y643218D01*
G01X1353088Y644617D02*
X1354122Y644434D01*
G01X1354393Y643218D02*
X1352419Y643567D01*
G01X1352723Y645138D02*
X1353088Y644617D01*
G01X1352419Y643567D02*
X1351507Y644868D01*
G01X1354169Y653338D02*
X1352723Y645138D01*
G01X1351507Y644868D02*
X1352953Y653067D01*
G01X1348366Y644898D02*
X1349984Y654077D01*
G01X1351034Y653407D02*
X1349417Y644229D01*
G01X1346810Y644712D02*
X1347843Y644531D01*
G01D02*
X1348366Y644898D01*
G01X1349417Y644229D02*
X1348114Y643315D01*
G01X1346810Y644712D02*
X1347843Y644531D01*
G01X1348114Y643315D02*
X1346140Y643661D01*
G01X1346446Y645234D02*
X1346810Y644712D01*
G01X1346140Y643661D02*
X1345230Y644966D01*
G01X1347872Y653320D02*
X1346446Y645234D01*
G01X1345230Y644966D02*
X1346656Y653051D01*
G01X1342068Y644894D02*
X1343686Y654059D01*
G01X1344736Y653389D02*
X1343118Y644224D01*
G01X1346292Y653572D02*
X1345258Y653753D01*
G01D02*
X1344736Y653389D01*
G01X1343686Y654059D02*
X1344989Y654968D01*
G01X1346292Y653572D02*
X1345258Y653753D01*
G01X1344989Y654968D02*
X1346962Y654623D01*
G01X1346656Y653051D02*
X1346292Y653572D01*
G01X1346962Y654623D02*
X1347872Y653320D01*
G01X1352590Y653589D02*
X1351556Y653772D01*
G01D02*
X1351034Y653407D01*
G01X1349984Y654077D02*
X1351287Y654987D01*
G01X1352590Y653589D02*
X1351556Y653772D01*
G01X1351287Y654987D02*
X1353260Y654639D01*
G01X1352953Y653067D02*
X1352590Y653589D01*
G01X1353260Y654639D02*
X1354169Y653338D01*
G01X1358886Y653589D02*
X1357852Y653771D01*
G01D02*
X1357332Y653407D01*
G01X1356282Y654076D02*
X1357582Y654987D01*
G01X1358886Y653589D02*
X1357852Y653771D01*
G01X1357582Y654987D02*
X1359556Y654640D01*
G01X1359250Y653068D02*
X1358886Y653589D01*
G01X1359556Y654640D02*
X1360466Y653337D01*
G01X1365177Y653556D02*
X1364143Y653738D01*
G01D02*
X1363620Y653373D01*
G01X1362569Y654043D02*
X1363873Y654953D01*
G01X1365177Y653556D02*
X1364143Y653738D01*
G01X1363873Y654953D02*
X1365847Y654607D01*
G01X1365541Y653035D02*
X1365177Y653556D01*
G01X1365847Y654607D02*
X1366757Y653304D01*
G01X1371473Y653557D02*
X1370438Y653739D01*
G01D02*
X1369915Y653374D01*
G01X1368865Y654044D02*
X1370169Y654954D01*
G01X1371473Y653557D02*
X1370438Y653739D01*
G01X1370169Y654954D02*
X1372143Y654608D01*
G01X1371837Y653036D02*
X1371473Y653557D01*
G01X1372143Y654608D02*
X1373053Y653305D01*
G01X1377769Y653574D02*
X1376735Y653757D01*
G01D02*
X1376216Y653394D01*
G01X1375166Y654063D02*
X1376466Y654973D01*
G01X1377769Y653574D02*
X1376735Y653757D01*
G01X1376466Y654973D02*
X1378439Y654624D01*
G01X1378136Y653050D02*
X1377769Y653574D01*
G01X1378439Y654624D02*
X1379352Y653320D01*
G01X1384061Y653543D02*
X1383026Y653725D01*
G01D02*
X1382504Y653361D01*
G01X1381454Y654031D02*
X1382757Y654940D01*
G01X1384061Y653543D02*
X1383026Y653725D01*
G01X1382757Y654940D02*
X1384731Y654594D01*
G01X1384426Y653021D02*
X1384061Y653543D01*
G01X1384731Y654594D02*
X1385642Y653290D01*
G01X1390351Y653510D02*
X1389316Y653692D01*
G01D02*
X1388794Y653328D01*
G01X1387744Y653998D02*
X1389047Y654907D01*
G01X1390351Y653510D02*
X1389316Y653692D01*
G01X1389047Y654907D02*
X1391021Y654561D01*
G01X1390716Y652988D02*
X1390351Y653510D01*
G01X1391021Y654561D02*
X1391932Y653257D01*
G01X1396647Y653511D02*
X1395613Y653692D01*
G01D02*
X1395091Y653328D01*
G01X1394041Y653998D02*
X1395344Y654907D01*
G01X1396647Y653511D02*
X1395613Y653692D01*
G01X1395344Y654907D02*
X1397317Y654562D01*
G01X1397011Y652990D02*
X1396647Y653511D01*
G01X1397317Y654562D02*
X1398227Y653259D01*
G01X1402945Y653528D02*
X1401911Y653711D01*
G01D02*
X1401389Y653346D01*
G01X1400339Y654016D02*
X1401642Y654926D01*
G01X1402945Y653528D02*
X1401911Y653711D01*
G01X1401642Y654926D02*
X1403615Y654578D01*
G01X1403308Y653006D02*
X1402945Y653528D01*
G01X1403615Y654578D02*
X1404524Y653277D01*
G01X1403615Y654578D02*
X1404524Y653277D01*
G01X1403308Y653006D02*
X1402945Y653528D01*
G01X1400339Y654016D02*
X1401642Y654926D01*
G01D02*
X1403615Y654578D01*
G01X1402945Y653528D02*
X1401911Y653711D01*
G01X1400339Y654016D02*
X1401642Y654926D01*
G01X1401911Y653711D02*
X1401389Y653346D01*
G01X1397317Y654562D02*
X1398227Y653259D01*
G01X1397011Y652990D02*
X1396647Y653511D01*
G01X1394041Y653998D02*
X1395344Y654907D01*
G01D02*
X1397317Y654562D01*
G01X1396647Y653511D02*
X1395613Y653692D01*
G01X1394041Y653998D02*
X1395344Y654907D01*
G01X1395613Y653692D02*
X1395091Y653328D01*
G01X1391021Y654561D02*
X1391932Y653257D01*
G01X1390716Y652988D02*
X1390351Y653510D01*
G01X1387744Y653998D02*
X1389047Y654907D01*
G01D02*
X1391021Y654561D01*
G01X1390351Y653510D02*
X1389316Y653692D01*
G01X1387744Y653998D02*
X1389047Y654907D01*
G01X1389316Y653692D02*
X1388794Y653328D01*
G01X1384731Y654594D02*
X1385642Y653290D01*
G01X1384426Y653021D02*
X1384061Y653543D01*
G01X1381454Y654031D02*
X1382757Y654940D01*
G01D02*
X1384731Y654594D01*
G01X1384061Y653543D02*
X1383026Y653725D01*
G01X1381454Y654031D02*
X1382757Y654940D01*
G01X1383026Y653725D02*
X1382504Y653361D01*
G01X1378439Y654624D02*
X1379352Y653320D01*
G01X1378136Y653050D02*
X1377769Y653574D01*
G01X1375166Y654063D02*
X1376466Y654973D01*
G01D02*
X1378439Y654624D01*
G01X1377769Y653574D02*
X1376735Y653757D01*
G01X1375166Y654063D02*
X1376466Y654973D01*
G01X1376735Y653757D02*
X1376216Y653394D01*
G01X1372143Y654608D02*
X1373053Y653305D01*
G01X1371837Y653036D02*
X1371473Y653557D01*
G01X1368865Y654044D02*
X1370169Y654954D01*
G01D02*
X1372143Y654608D01*
G01X1371473Y653557D02*
X1370438Y653739D01*
G01X1368865Y654044D02*
X1370169Y654954D01*
G01X1370438Y653739D02*
X1369915Y653374D01*
G01X1365847Y654607D02*
X1366757Y653304D01*
G01X1365541Y653035D02*
X1365177Y653556D01*
G01X1362569Y654043D02*
X1363873Y654953D01*
G01D02*
X1365847Y654607D01*
G01X1365177Y653556D02*
X1364143Y653738D01*
G01X1362569Y654043D02*
X1363873Y654953D01*
G01X1364143Y653738D02*
X1363620Y653373D01*
G01X1359556Y654640D02*
X1360466Y653337D01*
G01X1359250Y653068D02*
X1358886Y653589D01*
G01X1356282Y654076D02*
X1357582Y654987D01*
G01D02*
X1359556Y654640D01*
G01X1358886Y653589D02*
X1357852Y653771D01*
G01X1356282Y654076D02*
X1357582Y654987D01*
G01X1357852Y653771D02*
X1357332Y653407D01*
G01X1353260Y654639D02*
X1354169Y653338D01*
G01X1352953Y653067D02*
X1352590Y653589D01*
G01X1349984Y654077D02*
X1351287Y654987D01*
G01D02*
X1353260Y654639D01*
G01X1352590Y653589D02*
X1351556Y653772D01*
G01X1349984Y654077D02*
X1351287Y654987D01*
G01X1351556Y653772D02*
X1351034Y653407D01*
G01X1346962Y654623D02*
X1347872Y653320D01*
G01X1346656Y653051D02*
X1346292Y653572D01*
G01X1343686Y654059D02*
X1344989Y654968D01*
G01D02*
X1346962Y654623D01*
G01X1346292Y653572D02*
X1345258Y653753D01*
G01X1343686Y654059D02*
X1344989Y654968D01*
G01X1345258Y653753D02*
X1344736Y653389D01*
G01X1465949Y32722D02*
X1461918Y31916D01*
G01X1465949Y31549D02*
X1461918Y30743D01*
G01Y31916D02*
X1455872Y33126D01*
G01X1461918Y30743D02*
X1455114Y32104D01*
G01D02*
X1438551Y63011D01*
G01X1465949Y31549D02*
X1461918Y30743D01*
G01X1465949Y32722D02*
X1461918Y31916D01*
G01Y30743D02*
X1455114Y32104D01*
G01X1461918Y31916D02*
X1455872Y33126D01*
G01X1455114Y32104D02*
X1438551Y63011D01*
G01X1435415Y95950D02*
X1441744Y65710D01*
G01X1434385Y95254D02*
X1440652Y65313D01*
G01X1441744Y65710D02*
X1449056Y52062D01*
G01X1440652Y65313D02*
X1448155Y51308D01*
G01X1449056Y52062D02*
X1451347Y50267D01*
G01D02*
X1452260Y50377D01*
G01X1453433Y48632D02*
X1454496Y47799D01*
G01D02*
X1455408Y47910D01*
G01X1456581Y46165D02*
X1457644Y45332D01*
G01X1448156Y51306D02*
X1457144Y44262D01*
G01X1457644Y45332D02*
X1462285Y44343D01*
G01X1457144Y44262D02*
X1461580Y43317D01*
G01X1462285Y44343D02*
X1463150Y43012D01*
G01X1461580Y43317D02*
X1461925Y42785D01*
G01X1463150Y43012D02*
X1462797Y41353D01*
G01X1461925Y42785D02*
X1461572Y41125D01*
G01X1462797Y41353D02*
X1463144Y40820D01*
G01X1461572Y41125D02*
X1462439Y39794D01*
G01X1463144Y40820D02*
X1464026Y40631D01*
G01X1462439Y39794D02*
X1464252Y39406D01*
G01X1464026Y40631D02*
X1464558Y40977D01*
G01X1464252Y39406D02*
X1465584Y40272D01*
G01X1464558Y40977D02*
X1464911Y42637D01*
G01D02*
X1466242Y43502D01*
G01X1455872Y33126D02*
X1439643Y63408D01*
G01D02*
X1433174Y94400D01*
G01X1438551Y63011D02*
X1432144Y93704D01*
G01X1433174Y94400D02*
X1425951Y99216D01*
G01X1432144Y93704D02*
X1424916Y98523D01*
G01X1434385Y95254D02*
X1440652Y65313D01*
G01X1435415Y95950D02*
X1441744Y65710D01*
G01X1440652Y65313D02*
X1448155Y51308D01*
G01X1441744Y65710D02*
X1449056Y52062D01*
G01X1448156Y51306D02*
X1457144Y44262D01*
G01X1449056Y52062D02*
X1451347Y50267D01*
G01X1448156Y51306D02*
X1457144Y44262D01*
G01X1451347Y50267D02*
X1452260Y50377D01*
G01X1448156Y51306D02*
X1457144Y44262D01*
G01X1453433Y48632D02*
X1454496Y47799D01*
G01X1448156Y51306D02*
X1457144Y44262D01*
G01X1454496Y47799D02*
X1455408Y47910D01*
G01X1448156Y51306D02*
X1457144Y44262D01*
G01X1456581Y46165D02*
X1457644Y45332D01*
G01X1457144Y44262D02*
X1461580Y43317D01*
G01X1457644Y45332D02*
X1462285Y44343D01*
G01X1461580Y43317D02*
X1461925Y42785D01*
G01X1462285Y44343D02*
X1463150Y43012D01*
G01X1461925Y42785D02*
X1461572Y41125D01*
G01X1463150Y43012D02*
X1462797Y41353D01*
G01X1461572Y41125D02*
X1462439Y39794D01*
G01X1462797Y41353D02*
X1463144Y40820D01*
G01X1462439Y39794D02*
X1464252Y39406D01*
G01X1463144Y40820D02*
X1464026Y40631D01*
G01X1464252Y39406D02*
X1465584Y40272D01*
G01X1464026Y40631D02*
X1464558Y40977D01*
G01D02*
X1464911Y42637D01*
G01D02*
X1466242Y43502D01*
G01X1455872Y33126D02*
X1439643Y63408D01*
G01X1438551Y63011D02*
X1432144Y93704D01*
G01X1439643Y63408D02*
X1433174Y94400D01*
G01X1432144Y93704D02*
X1424916Y98523D01*
G01X1433174Y94400D02*
X1425951Y99216D01*
G01X1444566Y102261D02*
X1450939Y72932D01*
G01X1443540Y101561D02*
X1449849Y72527D01*
G01X1450939Y72932D02*
X1452770Y69559D01*
G01X1454034Y67230D02*
X1454678Y66043D01*
G01X1455942Y63714D02*
X1456586Y62528D01*
G01X1457850Y60199D02*
X1458494Y59012D01*
G01X1449849Y72527D02*
X1457596Y58254D01*
G01X1458494Y59012D02*
X1464476Y54315D01*
G01X1457596Y58254D02*
X1463975Y53245D01*
G01X1464476Y54315D02*
X1493914Y48059D01*
G01X1463975Y53245D02*
X1493914Y46883D01*
G01X1442251Y100735D02*
X1448341Y72314D01*
G01X1441224Y100037D02*
X1447250Y71914D01*
G01X1448341Y72314D02*
X1456239Y57578D01*
G01X1447250Y71914D02*
X1455339Y56822D01*
G01X1456239Y57578D02*
X1463445Y51929D01*
G01X1455339Y56822D02*
X1462945Y50859D01*
G01X1463445Y51929D02*
X1493826Y45470D01*
G01X1462945Y50859D02*
X1493824Y44294D01*
G01X1439916Y99252D02*
X1445976Y71028D01*
G01X1438889Y98554D02*
X1444885Y70628D01*
G01X1445976Y71028D02*
X1453956Y56139D01*
G01X1444885Y70628D02*
X1453056Y55382D01*
G01X1453956Y56139D02*
X1462369Y49546D01*
G01X1453056Y55382D02*
X1461869Y48476D01*
G01X1462369Y49546D02*
X1493980Y42832D01*
G01X1461869Y48476D02*
X1493980Y41656D01*
G01X1437648Y97668D02*
X1440833Y82586D01*
G01D02*
X1444017Y67504D01*
G01X1436619Y96971D02*
X1442925Y67105D01*
G01X1444017Y67504D02*
X1445041Y65592D01*
G01X1446292Y63256D02*
X1446930Y62066D01*
G01X1448181Y59730D02*
X1450413Y55563D01*
G01X1442925Y67105D02*
X1449513Y54807D01*
G01X1450413Y55563D02*
X1461014Y47253D01*
G01X1449513Y54807D02*
X1460304Y46348D01*
G01X1450413Y55563D02*
X1461014Y47253D01*
G01X1460304Y46348D02*
X1460303D01*
G01X1450413Y55563D02*
X1461014Y47253D01*
G01X1460303Y46348D02*
X1460514Y46183D01*
G01X1461014Y47253D02*
X1494025Y40242D01*
G01X1460514Y46183D02*
X1494025Y39066D01*
G01X1446847Y103969D02*
X1451698Y82186D01*
G01X1445824Y103268D02*
X1450678Y81472D01*
G01X1451698Y82186D02*
X1458726Y77692D01*
G01X1450678Y81472D02*
X1457903Y76853D01*
G01X1458726Y77692D02*
X1459475Y76569D01*
G01X1460945Y74364D02*
X1461694Y73241D01*
G01X1463164Y71036D02*
X1463913Y69912D01*
G01X1465383Y67708D02*
X1466132Y66585D01*
G01X1457903Y76853D02*
X1468198Y61410D01*
G01X1443540Y101561D02*
X1449849Y72527D01*
G01X1444566Y102261D02*
X1450939Y72932D01*
G01X1449849Y72527D02*
X1457596Y58254D01*
G01X1450939Y72932D02*
X1452770Y69559D01*
G01X1449849Y72527D02*
X1457596Y58254D01*
G01X1454034Y67230D02*
X1454678Y66043D01*
G01X1449849Y72527D02*
X1457596Y58254D01*
G01X1455942Y63714D02*
X1456586Y62528D01*
G01X1449849Y72527D02*
X1457596Y58254D01*
G01X1457850Y60199D02*
X1458494Y59012D01*
G01X1457596Y58254D02*
X1463975Y53245D01*
G01X1458494Y59012D02*
X1464476Y54315D01*
G01X1463975Y53245D02*
X1493914Y46883D01*
G01X1464476Y54315D02*
X1493914Y48059D01*
G01X1441224Y100037D02*
X1447250Y71914D01*
G01X1442251Y100735D02*
X1448341Y72314D01*
G01X1447250Y71914D02*
X1455339Y56822D01*
G01X1448341Y72314D02*
X1456239Y57578D01*
G01X1455339Y56822D02*
X1462945Y50859D01*
G01X1456239Y57578D02*
X1463445Y51929D01*
G01X1462945Y50859D02*
X1493824Y44294D01*
G01X1463445Y51929D02*
X1493826Y45470D01*
G01X1438889Y98554D02*
X1444885Y70628D01*
G01X1439916Y99252D02*
X1445976Y71028D01*
G01X1444885Y70628D02*
X1453056Y55382D01*
G01X1445976Y71028D02*
X1453956Y56139D01*
G01X1453056Y55382D02*
X1461869Y48476D01*
G01X1453956Y56139D02*
X1462369Y49546D01*
G01X1461869Y48476D02*
X1493980Y41656D01*
G01X1462369Y49546D02*
X1493980Y42832D01*
G01X1436619Y96971D02*
X1442925Y67105D01*
G01X1437648Y97668D02*
X1440833Y82586D01*
G01X1436619Y96971D02*
X1442925Y67105D01*
G01X1440833Y82586D02*
X1444017Y67504D01*
G01X1442925Y67105D02*
X1449513Y54807D01*
G01X1444017Y67504D02*
X1445041Y65592D01*
G01X1442925Y67105D02*
X1449513Y54807D01*
G01X1446292Y63256D02*
X1446930Y62066D01*
G01X1442925Y67105D02*
X1449513Y54807D01*
G01X1448181Y59730D02*
X1450413Y55563D01*
G01X1449513Y54807D02*
X1460304Y46348D01*
G01D02*
X1460303D01*
G01D02*
X1460514Y46183D01*
G01X1450413Y55563D02*
X1461014Y47253D01*
G01X1460514Y46183D02*
X1494025Y39066D01*
G01X1461014Y47253D02*
X1494025Y40242D01*
G01X1445824Y103268D02*
X1450678Y81472D01*
G01X1446847Y103969D02*
X1451698Y82186D01*
G01X1450678Y81472D02*
X1457903Y76853D01*
G01X1451698Y82186D02*
X1458726Y77692D01*
G01X1457903Y76853D02*
X1468198Y61410D01*
G01X1458726Y77692D02*
X1459475Y76569D01*
G01X1457903Y76853D02*
X1468198Y61410D01*
G01X1460945Y74364D02*
X1461694Y73241D01*
G01X1457903Y76853D02*
X1468198Y61410D01*
G01X1463164Y71036D02*
X1463913Y69912D01*
G01X1457903Y76853D02*
X1468198Y61410D01*
G01X1465383Y67708D02*
X1466132Y66585D01*
G01X1457903Y76853D02*
X1468198Y61410D01*
G01X1452637Y89500D02*
X1449056Y105567D01*
G01X1448034Y104865D02*
X1451615Y88799D01*
G01X1459645Y84831D02*
X1452637Y89500D01*
G01X1451615Y88799D02*
X1458815Y84001D01*
G01X1475641Y60840D02*
X1459645Y84831D01*
G01X1458815Y84001D02*
X1474811Y60010D01*
G01X1458815Y84001D02*
X1474811Y60010D01*
G01X1475641Y60840D02*
X1459645Y84831D01*
G01X1451615Y88799D02*
X1458815Y84001D01*
G01X1459645Y84831D02*
X1452637Y89500D01*
G01X1448034Y104865D02*
X1451615Y88799D01*
G01X1452637Y89500D02*
X1449056Y105567D01*
G01X1458347Y93731D02*
X1455761Y105358D01*
G01X1454691Y104866D02*
X1457270Y93271D01*
G01X1478936Y62842D02*
X1458347Y93731D01*
G01X1457270Y93271D02*
X1478106Y62012D01*
G01X1457270Y93271D02*
X1478106Y62012D01*
G01X1478936Y62842D02*
X1458347Y93731D01*
G01X1454691Y104866D02*
X1457270Y93271D01*
G01X1458347Y93731D02*
X1455761Y105358D01*
G01X1463096Y96459D02*
X1483035Y66543D01*
G01X1462013Y96009D02*
X1482205Y65713D01*
G01X1460606Y95196D02*
X1480798Y64902D01*
G01X1459523Y94747D02*
X1479968Y64072D01*
G01X1462013Y96009D02*
X1482205Y65713D01*
G01X1463096Y96459D02*
X1483035Y66543D01*
G01X1459523Y94747D02*
X1479968Y64072D01*
G01X1460606Y95196D02*
X1480798Y64902D01*
G01X1408872Y165371D02*
X1414634Y137377D01*
G01X1407778Y164977D02*
X1413564Y136870D01*
G01X1414634Y137377D02*
X1425070Y124521D01*
G01X1413564Y136870D02*
X1423997Y124016D01*
G01X1425070Y124521D02*
X1426293Y118399D01*
G01X1423997Y124016D02*
X1425120Y118399D01*
G01X1426293D02*
X1425514Y114504D01*
G01X1425120Y118399D02*
X1424341Y114504D01*
G01X1425514D02*
X1428270Y100725D01*
G01X1424341Y114504D02*
X1427235Y100033D01*
G01X1428270Y100726D02*
X1435415Y95950D01*
G01X1427235Y100033D02*
X1434385Y95254D01*
G01X1425951Y99216D02*
X1422864Y114655D01*
G01X1424916Y98523D02*
X1421736Y114430D01*
G01X1425951Y99216D02*
X1422864Y114655D01*
G01X1421735Y114430D02*
X1421691Y114655D01*
G01X1422864D02*
X1423468Y117674D01*
G01X1421691Y114655D02*
X1422295Y117674D01*
G01X1423468D02*
X1422291Y123556D01*
G01X1422295Y117674D02*
X1421219Y123050D01*
G01X1422291Y123556D02*
X1412417Y135725D01*
G01X1421219Y123050D02*
X1411347Y135218D01*
G01X1412417Y135725D02*
X1406552Y164224D01*
G01X1411347Y135218D02*
X1405458Y163830D01*
G01X1407778Y164977D02*
X1413564Y136870D01*
G01X1408872Y165371D02*
X1414634Y137377D01*
G01X1413564Y136870D02*
X1423997Y124016D01*
G01X1414634Y137377D02*
X1425070Y124521D01*
G01X1423997Y124016D02*
X1425120Y118399D01*
G01X1425070Y124521D02*
X1426293Y118399D01*
G01X1425120D02*
X1424341Y114504D01*
G01X1426293Y118399D02*
X1425514Y114504D01*
G01X1424341D02*
X1427235Y100033D01*
G01X1425514Y114504D02*
X1428270Y100725D01*
G01X1427235Y100033D02*
X1434385Y95254D01*
G01X1428270Y100726D02*
X1435415Y95950D01*
G01X1424916Y98523D02*
X1421736Y114430D01*
G01X1421735D02*
X1421691Y114655D01*
G01X1425951Y99216D02*
X1422864Y114655D01*
G01X1421691D02*
X1422295Y117674D01*
G01X1422864Y114655D02*
X1423468Y117674D01*
G01X1422295D02*
X1421219Y123050D01*
G01X1423468Y117674D02*
X1422291Y123556D01*
G01X1421219Y123050D02*
X1411347Y135218D01*
G01X1422291Y123556D02*
X1412417Y135725D01*
G01X1411347Y135218D02*
X1405458Y163830D01*
G01X1412417Y135725D02*
X1406552Y164224D01*
G01X1418559Y169374D02*
X1424118Y142359D01*
G01X1417465Y168980D02*
X1423048Y141852D01*
G01X1424118Y142359D02*
X1435056Y128876D01*
G01X1423048Y141852D02*
X1433984Y128372D01*
G01X1435056Y128876D02*
X1436974Y119301D01*
G01X1433984Y128372D02*
X1435801Y119301D01*
G01X1436974D02*
X1436072Y114787D01*
G01X1435801Y119301D02*
X1434899Y114787D01*
G01X1436072D02*
X1437656Y106861D01*
G01X1434899Y114787D02*
X1436621Y106168D01*
G01X1437656Y106861D02*
X1444566Y102261D01*
G01X1436621Y106168D02*
X1443540Y101561D01*
G01X1416072Y168554D02*
X1421681Y141294D01*
G01X1414978Y168160D02*
X1420611Y140787D01*
G01X1421681Y141294D02*
X1432750Y127654D01*
G01X1420611Y140787D02*
X1431677Y127149D01*
G01X1432750Y127654D02*
X1434388Y119478D01*
G01X1431677Y127149D02*
X1433215Y119478D01*
G01X1434388D02*
X1433484Y114954D01*
G01X1433215Y119478D02*
X1432311Y114954D01*
G01X1433484D02*
X1435418Y105285D01*
G01X1432311Y114954D02*
X1434383Y104591D01*
G01X1435418Y105285D02*
X1442251Y100735D01*
G01X1434383Y104591D02*
X1441224Y100037D01*
G01X1413675Y167446D02*
X1419389Y139690D01*
G01X1412581Y167052D02*
X1418319Y139183D01*
G01X1419389Y139690D02*
X1430279Y126273D01*
G01X1418319Y139183D02*
X1429206Y125768D01*
G01X1430279Y126273D02*
X1431683Y119250D01*
G01X1429206Y125768D02*
X1430510Y119250D01*
G01X1431683D02*
X1430804Y114854D01*
G01X1430510Y119250D02*
X1429631Y114854D01*
G01X1430804D02*
X1433002Y103868D01*
G01X1429631Y114854D02*
X1431967Y103175D01*
G01X1433002Y103868D02*
X1439916Y99252D01*
G01X1431967Y103175D02*
X1438889Y98554D01*
G01X1411198Y166615D02*
X1416994Y138462D01*
G01X1410104Y166221D02*
X1415924Y137955D01*
G01X1416994Y138462D02*
X1427779Y125171D01*
G01X1415924Y137955D02*
X1426706Y124667D01*
G01X1427779Y125171D02*
X1429043Y118847D01*
G01X1426706Y124667D02*
X1427870Y118847D01*
G01X1429043D02*
X1428214Y114705D01*
G01X1427870Y118847D02*
X1427041Y114705D01*
G01X1428214D02*
X1430695Y102304D01*
G01X1427041Y114705D02*
X1429660Y101611D01*
G01X1430695Y102304D02*
X1437648Y97668D01*
G01X1429660Y101611D02*
X1436619Y96971D01*
G01X1421045Y170027D02*
X1426466Y143684D01*
G01X1419951Y169633D02*
X1425396Y143177D01*
G01X1426466Y143684D02*
X1437944Y129537D01*
G01X1425396Y143177D02*
X1436872Y129033D01*
G01X1437944Y129537D02*
X1439814Y120199D01*
G01X1436872Y129033D02*
X1438641Y120199D01*
G01X1439814D02*
X1439016Y116210D01*
G01X1438641Y120199D02*
X1437843Y116210D01*
G01X1439016D02*
X1440636Y108109D01*
G01X1437843Y116210D02*
X1439601Y107416D01*
G01X1440636Y108109D02*
X1446847Y103969D01*
G01X1439601Y107416D02*
X1445824Y103268D01*
G01X1417465Y168980D02*
X1423048Y141852D01*
G01X1418559Y169374D02*
X1424118Y142359D01*
G01X1423048Y141852D02*
X1433984Y128372D01*
G01X1424118Y142359D02*
X1435056Y128876D01*
G01X1433984Y128372D02*
X1435801Y119301D01*
G01X1435056Y128876D02*
X1436974Y119301D01*
G01X1435801D02*
X1434899Y114787D01*
G01X1436974Y119301D02*
X1436072Y114787D01*
G01X1434899D02*
X1436621Y106168D01*
G01X1436072Y114787D02*
X1437656Y106861D01*
G01X1436621Y106168D02*
X1443540Y101561D01*
G01X1437656Y106861D02*
X1444566Y102261D01*
G01X1414978Y168160D02*
X1420611Y140787D01*
G01X1416072Y168554D02*
X1421681Y141294D01*
G01X1420611Y140787D02*
X1431677Y127149D01*
G01X1421681Y141294D02*
X1432750Y127654D01*
G01X1431677Y127149D02*
X1433215Y119478D01*
G01X1432750Y127654D02*
X1434388Y119478D01*
G01X1433215D02*
X1432311Y114954D01*
G01X1434388Y119478D02*
X1433484Y114954D01*
G01X1432311D02*
X1434383Y104591D01*
G01X1433484Y114954D02*
X1435418Y105285D01*
G01X1434383Y104591D02*
X1441224Y100037D01*
G01X1435418Y105285D02*
X1442251Y100735D01*
G01X1412581Y167052D02*
X1418319Y139183D01*
G01X1413675Y167446D02*
X1419389Y139690D01*
G01X1418319Y139183D02*
X1429206Y125768D01*
G01X1419389Y139690D02*
X1430279Y126273D01*
G01X1429206Y125768D02*
X1430510Y119250D01*
G01X1430279Y126273D02*
X1431683Y119250D01*
G01X1430510D02*
X1429631Y114854D01*
G01X1431683Y119250D02*
X1430804Y114854D01*
G01X1429631D02*
X1431967Y103175D01*
G01X1430804Y114854D02*
X1433002Y103868D01*
G01X1431967Y103175D02*
X1438889Y98554D01*
G01X1433002Y103868D02*
X1439916Y99252D01*
G01X1410104Y166221D02*
X1415924Y137955D01*
G01X1411198Y166615D02*
X1416994Y138462D01*
G01X1415924Y137955D02*
X1426706Y124667D01*
G01X1416994Y138462D02*
X1427779Y125171D01*
G01X1426706Y124667D02*
X1427870Y118847D01*
G01X1427779Y125171D02*
X1429043Y118847D01*
G01X1427870D02*
X1427041Y114705D01*
G01X1429043Y118847D02*
X1428214Y114705D01*
G01X1427041D02*
X1429660Y101611D01*
G01X1428214Y114705D02*
X1430695Y102304D01*
G01X1429660Y101611D02*
X1436619Y96971D01*
G01X1430695Y102304D02*
X1437648Y97668D01*
G01X1419951Y169633D02*
X1425396Y143177D01*
G01X1421045Y170027D02*
X1426466Y143684D01*
G01X1425396Y143177D02*
X1436872Y129033D01*
G01X1426466Y143684D02*
X1437944Y129537D01*
G01X1436872Y129033D02*
X1438641Y120199D01*
G01X1437944Y129537D02*
X1439814Y120199D01*
G01X1438641D02*
X1437843Y116210D01*
G01X1439814Y120199D02*
X1439016Y116210D01*
G01X1437843D02*
X1439601Y107416D01*
G01X1439016Y116210D02*
X1440636Y108109D01*
G01X1439601Y107416D02*
X1445824Y103268D01*
G01X1440636Y108109D02*
X1446847Y103969D01*
G01X1428888Y144917D02*
X1423574Y170732D01*
G01X1422480Y170338D02*
X1427818Y144410D01*
G01X1441020Y129967D02*
X1428888Y144917D01*
G01X1427818Y144410D02*
X1439947Y129462D01*
G01X1442702Y121556D02*
X1441020Y129967D01*
G01X1439947Y129462D02*
X1441529Y121556D01*
G01X1441685Y116464D02*
X1442702Y121556D01*
G01X1441529D02*
X1440512Y116464D01*
G01X1443070Y109540D02*
X1441685Y116464D01*
G01X1440512D02*
X1442036Y108846D01*
G01X1449056Y105567D02*
X1443070Y109540D01*
G01X1442036Y108846D02*
X1448034Y104865D01*
G01X1442036Y108846D02*
X1448034Y104865D01*
G01X1449056Y105567D02*
X1443070Y109540D01*
G01X1440512Y116464D02*
X1442036Y108846D01*
G01X1443070Y109540D02*
X1441685Y116464D01*
G01X1441529Y121556D02*
X1440512Y116464D01*
G01X1441685D02*
X1442702Y121556D01*
G01X1439947Y129462D02*
X1441529Y121556D01*
G01X1442702D02*
X1441020Y129967D01*
G01X1427818Y144410D02*
X1439947Y129462D01*
G01X1441020Y129967D02*
X1428888Y144917D01*
G01X1422480Y170338D02*
X1427818Y144410D01*
G01X1428888Y144917D02*
X1423574Y170732D01*
G01X1432662Y145378D02*
X1427354Y171934D01*
G01X1426263Y171520D02*
X1431589Y144873D01*
G01X1443987Y131427D02*
X1432662Y145378D01*
G01X1431589Y144873D02*
X1442914Y130922D01*
G01X1445948Y121639D02*
X1443987Y131427D01*
G01X1442914Y130922D02*
X1444775Y121639D01*
G01X1444986Y116820D02*
X1445948Y121639D01*
G01X1444775D02*
X1443813Y116820D01*
G01X1446099Y111252D02*
X1444986Y116820D01*
G01X1443813D02*
X1445064Y110558D01*
G01X1451456Y107695D02*
X1446099Y111252D01*
G01X1445064Y110558D02*
X1450999Y106618D01*
G01X1454515Y107020D02*
X1451456Y107695D01*
G01X1450999Y106618D02*
X1453850Y105989D01*
G01X1455761Y105358D02*
X1454515Y107020D01*
G01X1453850Y105989D02*
X1454691Y104866D01*
G01X1453850Y105989D02*
X1454691Y104866D01*
G01X1455761Y105358D02*
X1454515Y107020D01*
G01X1450999Y106618D02*
X1453850Y105989D01*
G01X1454515Y107020D02*
X1451456Y107695D01*
G01X1445064Y110558D02*
X1450999Y106618D01*
G01X1451456Y107695D02*
X1446099Y111252D01*
G01X1443813Y116820D02*
X1445064Y110558D01*
G01X1446099Y111252D02*
X1444986Y116820D01*
G01X1444775Y121639D02*
X1443813Y116820D01*
G01X1444986D02*
X1445948Y121639D01*
G01X1442914Y130922D02*
X1444775Y121639D01*
G01X1445948D02*
X1443987Y131427D01*
G01X1431589Y144873D02*
X1442914Y130922D01*
G01X1443987Y131427D02*
X1432662Y145378D01*
G01X1426263Y171520D02*
X1431589Y144873D01*
G01X1432662Y145378D02*
X1427354Y171934D01*
G01X1484248Y67451D02*
X1464693Y96791D01*
G01X1460749Y120868D02*
X1465772Y97246D01*
G01X1464693Y96791D02*
X1459670Y120413D01*
G01X1451694Y134450D02*
X1460749Y120868D01*
G01X1459670Y120413D02*
X1450767Y133767D01*
G01X1444891Y142826D02*
X1451694Y134450D01*
G01X1450767Y133767D02*
X1443827Y142310D01*
G01X1441834Y156442D02*
X1444891Y142826D01*
G01X1443827Y142310D02*
X1440737Y156075D01*
G01D02*
X1439818Y158109D01*
G01X1432112Y175742D02*
X1437743Y147584D01*
G01X1431029Y175293D02*
X1436670Y147079D01*
G01X1437743Y147584D02*
X1449798Y132739D01*
G01X1436670Y147079D02*
X1448871Y132056D01*
G01X1449798Y132739D02*
X1458367Y119886D01*
G01X1448871Y132056D02*
X1457284Y119436D01*
G01X1458367Y119886D02*
X1463096Y96459D01*
G01X1457284Y119436D02*
X1462013Y96009D01*
G01X1430004Y172487D02*
X1435163Y146310D01*
G01X1428912Y172076D02*
X1434090Y145807D01*
G01X1435163Y146310D02*
X1449040Y129217D01*
G01X1434090Y145807D02*
X1448113Y128534D01*
G01X1449040Y129217D02*
X1455845Y119006D01*
G01X1448113Y128534D02*
X1452543Y121886D01*
G01X1449040Y129217D02*
X1455845Y119006D01*
G01X1454012Y119680D02*
X1454761Y118557D01*
G01X1455845Y119006D02*
X1456672Y114869D01*
G01X1454761Y118557D02*
X1455450Y115111D01*
G01X1456672Y114869D02*
X1455791Y113548D01*
G01X1455450Y115111D02*
X1455098Y114583D01*
G01X1455791Y113548D02*
X1454951Y113380D01*
G01X1455098Y114583D02*
X1454259Y114415D01*
G01X1454951Y113380D02*
X1454598Y112852D01*
G01X1454259Y114415D02*
X1453376Y113095D01*
G01X1454598Y112852D02*
X1454775Y111968D01*
G01X1453376Y113095D02*
X1453740Y111275D01*
G01X1454775Y111968D02*
X1455304Y111615D01*
G01D02*
X1456144Y111783D01*
G01X1453740Y111275D02*
X1455062Y110393D01*
G01X1455304Y111615D02*
X1456144Y111783D01*
G01D02*
X1457465Y110901D01*
G01X1455062Y110393D02*
X1455902Y110561D01*
G01X1456144Y111783D02*
X1457465Y110901D01*
G01X1455902Y110561D02*
X1456430Y110208D01*
G01X1457465Y110901D02*
X1460606Y95196D01*
G01X1456430Y110208D02*
X1459523Y94747D01*
G01X1440737Y156075D02*
X1439818Y158109D01*
G01X1443827Y142310D02*
X1440737Y156075D01*
G01X1441834Y156442D02*
X1444891Y142826D01*
G01X1450767Y133767D02*
X1443827Y142310D01*
G01X1444891Y142826D02*
X1451694Y134450D01*
G01X1459670Y120413D02*
X1450767Y133767D01*
G01X1451694Y134450D02*
X1460749Y120868D01*
G01X1464693Y96791D02*
X1459670Y120413D01*
G01X1460749Y120868D02*
X1465772Y97246D01*
G01X1484248Y67451D02*
X1464693Y96791D01*
G01X1431029Y175293D02*
X1436670Y147079D01*
G01X1432112Y175742D02*
X1437743Y147584D01*
G01X1436670Y147079D02*
X1448871Y132056D01*
G01X1437743Y147584D02*
X1449798Y132739D01*
G01X1448871Y132056D02*
X1457284Y119436D01*
G01X1449798Y132739D02*
X1458367Y119886D01*
G01X1457284Y119436D02*
X1462013Y96009D01*
G01X1458367Y119886D02*
X1463096Y96459D01*
G01X1428912Y172076D02*
X1434090Y145807D01*
G01X1430004Y172487D02*
X1435163Y146310D01*
G01X1434090Y145807D02*
X1448113Y128534D01*
G01X1435163Y146310D02*
X1449040Y129217D01*
G01X1448113Y128534D02*
X1452543Y121886D01*
G01X1454012Y119680D02*
X1454761Y118557D01*
G01X1449040Y129217D02*
X1455845Y119006D01*
G01X1454761Y118557D02*
X1455450Y115111D01*
G01X1455845Y119006D02*
X1456672Y114869D01*
G01X1455450Y115111D02*
X1455098Y114583D01*
G01X1456672Y114869D02*
X1455791Y113548D01*
G01X1455098Y114583D02*
X1454259Y114415D01*
G01X1455791Y113548D02*
X1454951Y113380D01*
G01X1454259Y114415D02*
X1453376Y113095D01*
G01X1454951Y113380D02*
X1454598Y112852D01*
G01X1453376Y113095D02*
X1453740Y111275D01*
G01X1454598Y112852D02*
X1454775Y111968D01*
G01X1453740Y111275D02*
X1455062Y110393D01*
G01X1454775Y111968D02*
X1455304Y111615D01*
G01X1453740Y111275D02*
X1455062Y110393D01*
G01D02*
X1455902Y110561D01*
G01X1455304Y111615D02*
X1456144Y111783D01*
G01X1455062Y110393D02*
X1455902Y110561D01*
G01D02*
X1456430Y110208D01*
G01X1456144Y111783D02*
X1457465Y110901D01*
G01X1456430Y110208D02*
X1459523Y94747D01*
G01X1457465Y110901D02*
X1460606Y95196D01*
G01X1456675Y159067D02*
X1458196Y151479D01*
G01X1455641Y158374D02*
X1457023Y151479D01*
G01X1458196D02*
X1457767Y149335D01*
G01X1457023Y151479D02*
X1456594Y149335D01*
G01X1457767D02*
X1461686Y129732D01*
G01X1456594Y149335D02*
X1460603Y129283D01*
G01X1461686Y129732D02*
X1465316Y124294D01*
G01X1460603Y129283D02*
X1464237Y123839D01*
G01X1465316Y124294D02*
X1470580Y99534D01*
G01X1464237Y123839D02*
X1469501Y99079D01*
G01X1455364Y151546D02*
X1454141Y157275D01*
G01X1453113Y156577D02*
X1454189Y151538D01*
G01X1454954Y149496D02*
X1455364Y151546D01*
G01X1454189Y151538D02*
X1453781Y149496D01*
G01X1459042Y129054D02*
X1454954Y149496D01*
G01X1453781D02*
X1457959Y128605D01*
G01X1462838Y123365D02*
X1459042Y129054D01*
G01X1457959Y128605D02*
X1461759Y122910D01*
G01X1468121Y98520D02*
X1462838Y123365D01*
G01X1461759Y122910D02*
X1467042Y98065D01*
G01X1474624Y133948D02*
X1464543Y140667D01*
G01X1465578Y141360D02*
X1457839Y180092D01*
G01X1464543Y140667D02*
X1456790Y179466D01*
G01X1455441Y178717D02*
X1460894Y151471D01*
G01X1454393Y178091D02*
X1459721Y151471D01*
G01X1460894D02*
X1460486Y149432D01*
G01X1459721Y151471D02*
X1459313Y149432D01*
G01X1460486D02*
X1464112Y131306D01*
G01X1459313Y149432D02*
X1463029Y130857D01*
G01X1464112Y131306D02*
X1465526Y129186D01*
G01X1463029Y130857D02*
X1464568Y128547D01*
G01D02*
X1466858Y125114D01*
G01X1455641Y158374D02*
X1457023Y151479D01*
G01X1456675Y159067D02*
X1458196Y151479D01*
G01X1457023D02*
X1456594Y149335D01*
G01X1458196Y151479D02*
X1457767Y149335D01*
G01X1456594D02*
X1460603Y129283D01*
G01X1457767Y149335D02*
X1461686Y129732D01*
G01X1460603Y129283D02*
X1464237Y123839D01*
G01X1461686Y129732D02*
X1465316Y124294D01*
G01X1464237Y123839D02*
X1469501Y99079D01*
G01X1465316Y124294D02*
X1470580Y99534D01*
G01X1461759Y122910D02*
X1467042Y98065D01*
G01X1468121Y98520D02*
X1462838Y123365D01*
G01X1457959Y128605D02*
X1461759Y122910D01*
G01X1462838Y123365D02*
X1459042Y129054D01*
G01X1453781Y149496D02*
X1457959Y128605D01*
G01X1459042Y129054D02*
X1454954Y149496D01*
G01X1454189Y151538D02*
X1453781Y149496D01*
G01X1454954D02*
X1455364Y151546D01*
G01X1453113Y156577D02*
X1454189Y151538D01*
G01X1455364Y151546D02*
X1454141Y157275D01*
G01X1474624Y133948D02*
X1464543Y140667D01*
G01D02*
X1456790Y179466D01*
G01X1465578Y141360D02*
X1457839Y180092D01*
G01X1454393Y178091D02*
X1459721Y151471D01*
G01X1455441Y178717D02*
X1460894Y151471D01*
G01X1459721D02*
X1459313Y149432D01*
G01X1460894Y151471D02*
X1460486Y149432D01*
G01X1459313D02*
X1463029Y130857D01*
G01X1460486Y149432D02*
X1464112Y131306D01*
G01X1463029Y130857D02*
X1464568Y128547D01*
G01X1464112Y131306D02*
X1465526Y129186D01*
G01X1464568Y128547D02*
X1466858Y125114D01*
G01X1464568Y128547D02*
X1466858Y125114D01*
G01X1406223Y170366D02*
X1408872Y165371D01*
G01X1405345Y169565D02*
X1407778Y164977D01*
G01X1406552Y164224D02*
X1404212Y168635D01*
G01X1405345Y169565D02*
X1407778Y164977D01*
G01X1406223Y170366D02*
X1408872Y165371D01*
G01X1406552Y164224D02*
X1404212Y168635D01*
G01X1405581Y182977D02*
X1414410Y177197D01*
G01X1405105Y181913D02*
X1413532Y176396D01*
G01X1414410Y177197D02*
X1418559Y169374D01*
G01X1413532Y176396D02*
X1417465Y168980D01*
G01X1404429Y180683D02*
X1412409Y175459D01*
G01X1403953Y179619D02*
X1411531Y174658D01*
G01X1412409Y175459D02*
X1416072Y168554D01*
G01X1411531Y174658D02*
X1414978Y168160D01*
G01X1410316Y173780D02*
X1413675Y167446D01*
G01X1409438Y172980D02*
X1412581Y167052D01*
G01X1408321Y172040D02*
X1411198Y166615D01*
G01X1407443Y171239D02*
X1410104Y166221D01*
G01X1406671Y185312D02*
X1416270Y179027D01*
G01X1406193Y184249D02*
X1406195D01*
G01X1406671Y185312D02*
X1416270Y179027D01*
G01X1406195Y184249D02*
X1415394Y178225D01*
G01X1416272Y179026D02*
X1421045Y170027D01*
G01X1415394Y178225D02*
X1419951Y169633D01*
G01X1405105Y181913D02*
X1413532Y176396D01*
G01X1405581Y182977D02*
X1414410Y177197D01*
G01X1413532Y176396D02*
X1417465Y168980D01*
G01X1414410Y177197D02*
X1418559Y169374D01*
G01X1403953Y179619D02*
X1411531Y174658D01*
G01X1404429Y180683D02*
X1412409Y175459D01*
G01X1411531Y174658D02*
X1414978Y168160D01*
G01X1412409Y175459D02*
X1416072Y168554D01*
G01X1409438Y172980D02*
X1412581Y167052D01*
G01X1410316Y173780D02*
X1413675Y167446D01*
G01X1407443Y171239D02*
X1410104Y166221D01*
G01X1408321Y172040D02*
X1411198Y166615D01*
G01X1406193Y184249D02*
X1406195D01*
G01X1406193D02*
X1406195D01*
G01D02*
X1415394Y178225D01*
G01X1406671Y185312D02*
X1416270Y179027D01*
G01X1415394Y178225D02*
X1419951Y169633D01*
G01X1416272Y179026D02*
X1421045Y170027D01*
G01X1418243Y180782D02*
X1417983Y180952D01*
G01D02*
X1407789Y187629D01*
G01X1407311Y186567D02*
X1417352Y179990D01*
G01X1418243Y180782D02*
X1417983Y180952D01*
G01D02*
X1407789Y187629D01*
G01X1417352Y179990D02*
X1417365Y179981D01*
G01X1423574Y170732D02*
X1418243Y180782D01*
G01X1417365Y179981D02*
X1422480Y170338D01*
G01X1417365Y179981D02*
X1422480Y170338D01*
G01X1423574Y170732D02*
X1418243Y180782D01*
G01X1407311Y186567D02*
X1417352Y179990D01*
G01D02*
X1417365Y179981D01*
G01X1418243Y180782D02*
X1417983Y180952D01*
G01X1407311Y186567D02*
X1417352Y179990D01*
G01D02*
X1417365Y179981D01*
G01X1417983Y180952D02*
X1407789Y187629D01*
G01X1410870Y213431D02*
X1411636Y217033D01*
G01X1413785Y232686D02*
X1409679Y213360D01*
G01X1413148Y206752D02*
X1410870Y213431D01*
G01X1409679Y213360D02*
X1411304Y208596D01*
G01X1413148Y206752D02*
X1410870Y213431D01*
G01X1411304Y208596D02*
X1411963Y206663D01*
G01X1411799Y199974D02*
X1413152Y206741D01*
G01X1411963Y206663D02*
X1410625Y199973D01*
G01X1412178Y198071D02*
X1411799Y199974D01*
G01X1410625Y199973D02*
X1411087Y197658D01*
G01X1427354Y171934D02*
X1412178Y198071D01*
G01X1411087Y197658D02*
X1426263Y171520D01*
G01X1411087Y197658D02*
X1426263Y171520D01*
G01X1427354Y171934D02*
X1412178Y198071D01*
G01X1410625Y199973D02*
X1411087Y197658D01*
G01X1412178Y198071D02*
X1411799Y199974D01*
G01X1411963Y206663D02*
X1410625Y199973D01*
G01X1411799Y199974D02*
X1413152Y206741D01*
G01X1409679Y213360D02*
X1411304Y208596D01*
G01D02*
X1411963Y206663D01*
G01X1413148Y206752D02*
X1410870Y213431D01*
G01X1413785Y232686D02*
X1409679Y213360D01*
G01X1410870Y213431D02*
X1411636Y217033D01*
G01X1413785Y232686D02*
X1409679Y213360D01*
G01X1413785Y232686D02*
X1409679Y213360D01*
G01X1413785Y232686D02*
X1409679Y213360D01*
G01X1413785Y232686D02*
X1409679Y213360D01*
G01X1440809Y158711D02*
X1441834Y156442D01*
G01X1437198Y163295D02*
X1440809Y158711D01*
G01X1439818Y158109D02*
X1436123Y162799D01*
G01X1434475Y176901D02*
X1437198Y163295D01*
G01X1436123Y162799D02*
X1433392Y176451D01*
G01X1427432Y187401D02*
X1434475Y176901D01*
G01X1433392Y176451D02*
X1426349Y186951D01*
G01X1424931Y199902D02*
X1427432Y187401D01*
G01X1426349Y186951D02*
X1423818Y199602D01*
G01X1422990Y205595D02*
X1424931Y199902D01*
G01X1423818Y199602D02*
X1421776Y205589D01*
G01X1428359Y221855D02*
X1422990Y205595D01*
G01X1421776Y205589D02*
X1427120Y221771D01*
G01X1420970Y229480D02*
X1417570Y213463D01*
G01X1419794Y229480D02*
X1416379Y213392D01*
G01X1417570Y213463D02*
X1422174Y199965D01*
G01X1416379Y213392D02*
X1421061Y199665D01*
G01X1422174Y199965D02*
X1424836Y186659D01*
G01X1421061Y199665D02*
X1423753Y186210D01*
G01X1424836Y186659D02*
X1432112Y175742D01*
G01X1423753Y186210D02*
X1431029Y175293D01*
G01X1418030Y230776D02*
X1414112Y212335D01*
G01X1416854Y230776D02*
X1412921Y212264D01*
G01X1414112Y212335D02*
X1416122Y206441D01*
G01X1412921Y212264D02*
X1414933Y206363D01*
G01X1416122Y206441D02*
X1415678Y204222D01*
G01X1414933Y206363D02*
X1414700Y205200D01*
G01X1415678Y204222D02*
X1414733Y199494D01*
G01X1414700Y205200D02*
X1413560Y199494D01*
G01X1414733D02*
X1414949Y198415D01*
G01X1413560Y199494D02*
X1413858Y198002D01*
G01X1414949Y198415D02*
X1416683Y195430D01*
G01X1413858Y198002D02*
X1415927Y194440D01*
G01X1416683Y195430D02*
X1417295Y195267D01*
G01X1415927Y194440D02*
X1417461Y194032D01*
G01X1417295Y195267D02*
X1417908Y195624D01*
G01X1417461Y194032D02*
X1418074Y194389D01*
G01X1417908Y195624D02*
X1419445Y195215D01*
G01X1418074Y194389D02*
X1418689Y194225D01*
G01X1419445Y195215D02*
X1420377Y193611D01*
G01X1418689Y194225D02*
X1419142Y193446D01*
G01X1420377Y193611D02*
X1419967Y192075D01*
G01X1419142Y193446D02*
X1418978Y192831D01*
G01X1419967Y192075D02*
X1419355Y191719D01*
G01X1418978Y192831D02*
X1418365Y192475D01*
G01X1419355Y191719D02*
X1419192Y191106D01*
G01X1418365Y192475D02*
X1417957Y190941D01*
G01X1419192Y191106D02*
X1430004Y172487D01*
G01X1417957Y190941D02*
X1428912Y172076D01*
G01X1421776Y205589D02*
X1427120Y221771D01*
G01X1428359Y221855D02*
X1422990Y205595D01*
G01X1423818Y199602D02*
X1421776Y205589D01*
G01X1422990Y205595D02*
X1424931Y199902D01*
G01X1426349Y186951D02*
X1423818Y199602D01*
G01X1424931Y199902D02*
X1427432Y187401D01*
G01X1433392Y176451D02*
X1426349Y186951D01*
G01X1427432Y187401D02*
X1434475Y176901D01*
G01X1436123Y162799D02*
X1433392Y176451D01*
G01X1434475Y176901D02*
X1437198Y163295D01*
G01X1439818Y158109D02*
X1436123Y162799D01*
G01X1437198Y163295D02*
X1440809Y158711D01*
G01D02*
X1441834Y156442D01*
G01X1419794Y229480D02*
X1416379Y213392D01*
G01X1420970Y229480D02*
X1417570Y213463D01*
G01X1416379Y213392D02*
X1421061Y199665D01*
G01X1417570Y213463D02*
X1422174Y199965D01*
G01X1421061Y199665D02*
X1423753Y186210D01*
G01X1422174Y199965D02*
X1424836Y186659D01*
G01X1423753Y186210D02*
X1431029Y175293D01*
G01X1424836Y186659D02*
X1432112Y175742D01*
G01X1416854Y230776D02*
X1412921Y212264D01*
G01X1418030Y230776D02*
X1414112Y212335D01*
G01X1412921Y212264D02*
X1414933Y206363D01*
G01X1414112Y212335D02*
X1416122Y206441D01*
G01X1414933Y206363D02*
X1414700Y205200D01*
G01X1416122Y206441D02*
X1415678Y204222D01*
G01X1414700Y205200D02*
X1413560Y199494D01*
G01X1415678Y204222D02*
X1414733Y199494D01*
G01X1413560D02*
X1413858Y198002D01*
G01X1414733Y199494D02*
X1414949Y198415D01*
G01X1413858Y198002D02*
X1415927Y194440D01*
G01X1414949Y198415D02*
X1416683Y195430D01*
G01X1415927Y194440D02*
X1417461Y194032D01*
G01X1416683Y195430D02*
X1417295Y195267D01*
G01X1417461Y194032D02*
X1418074Y194389D01*
G01X1417295Y195267D02*
X1417908Y195624D01*
G01X1418074Y194389D02*
X1418689Y194225D01*
G01X1417908Y195624D02*
X1419445Y195215D01*
G01X1418689Y194225D02*
X1419142Y193446D01*
G01X1419445Y195215D02*
X1420377Y193611D01*
G01X1419142Y193446D02*
X1418978Y192831D01*
G01X1420377Y193611D02*
X1419967Y192075D01*
G01X1418978Y192831D02*
X1418365Y192475D01*
G01X1419967Y192075D02*
X1419355Y191719D01*
G01X1418365Y192475D02*
X1417957Y190941D01*
G01X1419355Y191719D02*
X1419192Y191106D01*
G01X1417957Y190941D02*
X1428912Y172076D01*
G01X1419192Y191106D02*
X1430004Y172487D01*
G01X1433940Y222335D02*
X1430404Y205674D01*
G01X1432732Y222186D02*
X1429213Y205603D01*
G01X1430404Y205674D02*
X1435176Y191677D01*
G01X1429213Y205603D02*
X1434191Y190998D01*
G01X1435176Y191677D02*
X1445558Y183075D01*
G01X1434191Y190998D02*
X1444510Y182449D01*
G01X1445558Y183075D02*
X1446034Y180700D01*
G01X1444510Y182449D02*
X1444861Y180700D01*
G01X1445558Y183075D02*
X1446034Y180700D01*
G01D02*
X1446151Y180114D01*
G01X1444861Y180700D02*
X1444978Y180114D01*
G01X1446151D02*
X1445256Y175637D01*
G01X1444978Y180114D02*
X1444083Y175637D01*
G01X1445256D02*
X1446740Y168220D01*
G01X1444083Y175637D02*
X1445655Y167774D01*
G01X1446740Y168220D02*
X1449777Y163667D01*
G01X1445655Y167774D02*
X1448947Y162837D01*
G01X1449777Y163667D02*
X1456675Y159067D01*
G01X1448947Y162837D02*
X1455641Y158374D01*
G01X1427050Y202137D02*
X1431270Y221997D01*
G01X1430062Y221849D02*
X1425875Y202144D01*
G01X1429700Y188894D02*
X1427050Y202137D01*
G01X1425875Y202144D02*
X1428617Y188444D01*
G01X1437136Y177815D02*
X1429700Y188894D01*
G01X1428617Y188444D02*
X1436053Y177364D01*
G01X1437879Y174109D02*
X1437136Y177815D01*
G01X1436053Y177364D02*
X1436796Y173660D01*
G01X1439532Y171632D02*
X1437879Y174109D01*
G01X1436796Y173660D02*
X1438702Y170802D01*
G01X1442849Y169421D02*
X1439532Y171632D01*
G01X1438702Y170802D02*
X1442020Y168591D01*
G01X1448394Y161107D02*
X1442977Y169229D01*
G01Y169230D02*
X1442849Y169421D01*
G01X1442020Y168591D02*
X1447564Y160277D01*
G01X1454141Y157275D02*
X1448394Y161107D01*
G01X1447564Y160277D02*
X1453113Y156577D01*
G01X1457839Y180092D02*
X1457105Y180700D01*
G01D02*
X1440504Y194459D01*
G01X1456790Y179466D02*
X1439520Y193780D01*
G01X1440504Y194459D02*
X1436066Y207458D01*
G01X1439520Y193780D02*
X1434875Y207386D01*
G01X1436066Y207458D02*
X1439380Y223130D01*
G01X1434875Y207386D02*
X1438173Y222981D01*
G01X1436663Y222744D02*
X1433196Y206408D01*
G01X1435455Y222595D02*
X1432005Y206337D01*
G01X1433196Y206408D02*
X1437603Y193498D01*
G01X1432005Y206337D02*
X1436619Y192819D01*
G01X1437603Y193498D02*
X1455441Y178717D01*
G01X1436619Y192819D02*
X1454393Y178091D01*
G01X1432732Y222186D02*
X1429213Y205603D01*
G01X1433940Y222335D02*
X1430404Y205674D01*
G01X1429213Y205603D02*
X1434191Y190998D01*
G01X1430404Y205674D02*
X1435176Y191677D01*
G01X1434191Y190998D02*
X1444510Y182449D01*
G01X1435176Y191677D02*
X1445558Y183075D01*
G01X1444510Y182449D02*
X1444861Y180700D01*
G01D02*
X1444978Y180114D01*
G01X1445558Y183075D02*
X1446034Y180700D01*
G01X1444861D02*
X1444978Y180114D01*
G01X1446034Y180700D02*
X1446151Y180114D01*
G01X1444978D02*
X1444083Y175637D01*
G01X1446151Y180114D02*
X1445256Y175637D01*
G01X1444083D02*
X1445655Y167774D01*
G01X1445256Y175637D02*
X1446740Y168220D01*
G01X1445655Y167774D02*
X1448947Y162837D01*
G01X1446740Y168220D02*
X1449777Y163667D01*
G01X1448947Y162837D02*
X1455641Y158374D01*
G01X1449777Y163667D02*
X1456675Y159067D01*
G01X1447564Y160277D02*
X1453113Y156577D01*
G01X1454141Y157275D02*
X1448394Y161107D01*
G01X1442020Y168591D02*
X1447564Y160277D01*
G01X1448394Y161107D02*
X1442977Y169229D01*
G01X1442020Y168591D02*
X1447564Y160277D01*
G01X1442977Y169230D02*
X1442849Y169421D01*
G01X1438702Y170802D02*
X1442020Y168591D01*
G01X1442849Y169421D02*
X1439532Y171632D01*
G01X1436796Y173660D02*
X1438702Y170802D01*
G01X1439532Y171632D02*
X1437879Y174109D01*
G01X1436053Y177364D02*
X1436796Y173660D01*
G01X1437879Y174109D02*
X1437136Y177815D01*
G01X1428617Y188444D02*
X1436053Y177364D01*
G01X1437136Y177815D02*
X1429700Y188894D01*
G01X1425875Y202144D02*
X1428617Y188444D01*
G01X1429700Y188894D02*
X1427050Y202137D01*
G01X1430062Y221849D02*
X1425875Y202144D01*
G01X1427050Y202137D02*
X1431270Y221997D01*
G01X1456790Y179466D02*
X1439520Y193780D01*
G01X1457839Y180092D02*
X1457105Y180700D01*
G01X1456790Y179466D02*
X1439520Y193780D01*
G01X1457105Y180700D02*
X1440504Y194459D01*
G01X1439520Y193780D02*
X1434875Y207386D01*
G01X1440504Y194459D02*
X1436066Y207458D01*
G01X1434875Y207386D02*
X1438173Y222981D01*
G01X1436066Y207458D02*
X1439380Y223130D01*
G01X1435455Y222595D02*
X1432005Y206337D01*
G01X1436663Y222744D02*
X1433196Y206408D01*
G01X1432005Y206337D02*
X1436619Y192819D01*
G01X1433196Y206408D02*
X1437603Y193498D01*
G01X1436619Y192819D02*
X1454393Y178091D01*
G01X1437603Y193498D02*
X1455441Y178717D01*
G01X1404728Y275352D02*
X1411776Y290619D01*
G01X1409226Y259683D02*
X1404999Y265663D01*
G01X1403958Y265143D02*
X1408149Y259214D01*
G01X1414961Y232685D02*
X1409226Y259683D01*
G01X1408149Y259214D02*
X1413785Y232686D01*
G01X1412186Y219625D02*
X1412467Y220946D01*
G01X1413018Y223539D02*
X1413299Y224859D01*
G01X1413849Y227451D02*
X1414130Y228772D01*
G01X1414680Y231364D02*
X1414961Y232685D01*
G01X1412186Y219625D02*
X1412467Y220946D01*
G01X1413018Y223539D02*
X1413299Y224859D01*
G01X1413849Y227451D02*
X1414130Y228772D01*
G01X1414680Y231364D02*
X1414961Y232685D01*
G01X1408149Y259214D02*
X1413785Y232686D01*
G01X1414961Y232685D02*
X1409226Y259683D01*
G01X1403958Y265143D02*
X1408149Y259214D01*
G01X1409226Y259683D02*
X1404999Y265663D01*
G01X1404728Y275352D02*
X1411776Y290619D01*
G01X1422725Y233406D02*
X1428359Y221855D01*
G01X1427120Y221771D02*
X1421629Y233029D01*
G01X1416085Y264658D02*
X1422725Y233406D01*
G01X1421629Y233029D02*
X1414910Y264651D01*
G01X1416713Y267798D02*
X1416085Y264658D01*
G01X1414910Y264651D02*
X1415540Y267798D01*
G01X1415903Y271852D02*
X1416713Y267798D01*
G01X1415540D02*
X1414728Y271859D01*
G01X1419241Y287569D02*
X1415903Y271852D01*
G01X1414728Y271859D02*
X1418127Y287861D01*
G01X1417306Y290435D02*
X1409832Y274239D01*
G01X1416230Y290850D02*
X1408729Y274594D01*
G01X1409832Y274239D02*
X1409033Y270108D01*
G01X1408729Y274594D02*
X1407847Y270036D01*
G01X1409033Y270108D02*
X1409550Y268506D01*
G01X1407847Y270036D02*
X1408509Y267985D01*
G01X1409550Y268506D02*
X1414023Y262176D01*
G01X1408509Y267985D02*
X1412946Y261705D01*
G01X1414023Y262176D02*
X1420970Y229480D01*
G01X1412946Y261705D02*
X1419794Y229480D01*
G01X1414742Y290959D02*
X1407379Y275010D01*
G01X1413653Y291344D02*
X1406277Y275369D01*
G01X1407379Y275010D02*
X1406387Y270028D01*
G01X1406277Y275369D02*
X1405200Y269960D01*
G01X1406387Y270028D02*
X1407307Y267166D01*
G01X1405200Y269960D02*
X1406266Y266646D01*
G01X1407307Y267166D02*
X1411588Y261110D01*
G01X1406266Y266646D02*
X1410512Y260639D01*
G01X1411588Y261110D02*
X1418030Y230776D01*
G01X1410512Y260639D02*
X1416854Y230776D01*
G01X1414728Y271859D02*
X1418127Y287861D01*
G01X1419241Y287569D02*
X1415903Y271852D01*
G01X1415540Y267798D02*
X1414728Y271859D01*
G01X1415903Y271852D02*
X1416713Y267798D01*
G01X1414910Y264651D02*
X1415540Y267798D01*
G01X1416713D02*
X1416085Y264658D01*
G01X1421629Y233029D02*
X1414910Y264651D01*
G01X1416085Y264658D02*
X1422725Y233406D01*
G01X1427120Y221771D02*
X1421629Y233029D01*
G01X1422725Y233406D02*
X1428359Y221855D01*
G01X1416230Y290850D02*
X1408729Y274594D01*
G01X1417306Y290435D02*
X1409832Y274239D01*
G01X1408729Y274594D02*
X1407847Y270036D01*
G01X1409832Y274239D02*
X1409033Y270108D01*
G01X1407847Y270036D02*
X1408509Y267985D01*
G01X1409033Y270108D02*
X1409550Y268506D01*
G01X1408509Y267985D02*
X1412946Y261705D01*
G01X1409550Y268506D02*
X1414023Y262176D01*
G01X1412946Y261705D02*
X1419794Y229480D01*
G01X1414023Y262176D02*
X1420970Y229480D01*
G01X1413653Y291344D02*
X1406277Y275369D01*
G01X1414742Y290959D02*
X1407379Y275010D01*
G01X1406277Y275369D02*
X1405200Y269960D01*
G01X1407379Y275010D02*
X1406387Y270028D01*
G01X1405200Y269960D02*
X1406266Y266646D01*
G01X1406387Y270028D02*
X1407307Y267166D01*
G01X1406266Y266646D02*
X1410512Y260639D01*
G01X1407307Y267166D02*
X1411588Y261110D01*
G01X1410512Y260639D02*
X1416854Y230776D01*
G01X1411588Y261110D02*
X1418030Y230776D01*
G01X1424278Y285991D02*
X1421372Y272307D01*
G01X1423163Y286281D02*
X1420197Y272313D01*
G01X1421372Y272307D02*
X1422103Y268649D01*
G01X1420197Y272313D02*
X1420930Y268649D01*
G01X1422103D02*
X1421349Y264881D01*
G01X1420930Y268649D02*
X1420174Y264874D01*
G01X1421349Y264881D02*
X1427642Y235245D01*
G01X1420174Y264874D02*
X1426546Y234868D01*
G01X1427642Y235245D02*
X1433940Y222335D01*
G01X1426546Y234868D02*
X1432732Y222186D01*
G01X1418702Y272051D02*
X1421697Y286150D01*
G01X1420582Y286440D02*
X1417527Y272058D01*
G01X1419463Y268246D02*
X1418702Y272051D01*
G01X1417527Y272058D02*
X1418290Y268246D01*
G01X1418756Y264715D02*
X1419463Y268246D01*
G01X1418290D02*
X1417581Y264708D01*
G01X1425174Y234496D02*
X1418756Y264715D01*
G01X1417581Y264708D02*
X1424078Y234119D01*
G01X1431270Y221997D02*
X1425174Y234496D01*
G01X1424078Y234119D02*
X1430062Y221849D01*
G01X1439380Y223130D02*
X1432384Y237475D01*
G01X1438173Y222981D02*
X1431288Y237098D01*
G01X1432384Y237475D02*
X1427698Y259530D01*
G01X1431288Y237098D02*
X1426522Y259530D01*
G01X1427698D02*
X1428498Y263295D01*
G01X1426522Y259530D02*
X1427419Y263752D01*
G01X1428498Y263295D02*
X1430807Y266763D01*
G01X1427419Y263752D02*
X1429724Y267212D01*
G01X1430807Y266763D02*
X1431197Y268700D01*
G01X1429724Y267212D02*
X1430016Y268665D01*
G01X1431197Y268700D02*
X1429493Y275178D01*
G01X1430016Y268665D02*
X1428311Y275150D01*
G01X1429493Y275178D02*
X1433138Y292338D01*
G01X1428311Y275150D02*
X1432083Y292911D01*
G01X1426379Y283841D02*
X1424027Y272770D01*
G01X1425265Y284133D02*
X1422852Y272777D01*
G01X1424027Y272770D02*
X1424808Y268877D01*
G01X1422852Y272777D02*
X1423635Y268876D01*
G01X1424808Y268877D02*
X1423977Y264718D01*
G01X1423635Y268876D02*
X1422802Y264711D01*
G01X1423977Y264718D02*
X1429982Y236441D01*
G01X1422802Y264711D02*
X1428886Y236064D01*
G01X1429982Y236441D02*
X1436663Y222744D01*
G01X1428886Y236064D02*
X1435455Y222595D01*
G01X1423163Y286281D02*
X1420197Y272313D01*
G01X1424278Y285991D02*
X1421372Y272307D01*
G01X1420197Y272313D02*
X1420930Y268649D01*
G01X1421372Y272307D02*
X1422103Y268649D01*
G01X1420930D02*
X1420174Y264874D01*
G01X1422103Y268649D02*
X1421349Y264881D01*
G01X1420174Y264874D02*
X1426546Y234868D01*
G01X1421349Y264881D02*
X1427642Y235245D01*
G01X1426546Y234868D02*
X1432732Y222186D01*
G01X1427642Y235245D02*
X1433940Y222335D01*
G01X1424078Y234119D02*
X1430062Y221849D01*
G01X1431270Y221997D02*
X1425174Y234496D01*
G01X1417581Y264708D02*
X1424078Y234119D01*
G01X1425174Y234496D02*
X1418756Y264715D01*
G01X1418290Y268246D02*
X1417581Y264708D01*
G01X1418756Y264715D02*
X1419463Y268246D01*
G01X1417527Y272058D02*
X1418290Y268246D01*
G01X1419463D02*
X1418702Y272051D01*
G01X1420582Y286440D02*
X1417527Y272058D01*
G01X1418702Y272051D02*
X1421697Y286150D01*
G01X1438173Y222981D02*
X1431288Y237098D01*
G01X1439380Y223130D02*
X1432384Y237475D01*
G01X1431288Y237098D02*
X1426522Y259530D01*
G01X1432384Y237475D02*
X1427698Y259530D01*
G01X1426522D02*
X1427419Y263752D01*
G01X1427698Y259530D02*
X1428498Y263295D01*
G01X1427419Y263752D02*
X1429724Y267212D01*
G01X1428498Y263295D02*
X1430807Y266763D01*
G01X1429724Y267212D02*
X1430016Y268665D01*
G01X1430807Y266763D02*
X1431197Y268700D01*
G01X1430016Y268665D02*
X1428311Y275150D01*
G01X1431197Y268700D02*
X1429493Y275178D01*
G01X1428311Y275150D02*
X1432083Y292911D01*
G01X1429493Y275178D02*
X1433138Y292338D01*
G01X1425265Y284133D02*
X1422852Y272777D01*
G01X1426379Y283841D02*
X1424027Y272770D01*
G01X1422852Y272777D02*
X1423635Y268876D01*
G01X1424027Y272770D02*
X1424808Y268877D01*
G01X1423635Y268876D02*
X1422802Y264711D01*
G01X1424808Y268877D02*
X1423977Y264718D01*
G01X1422802Y264711D02*
X1428886Y236064D01*
G01X1423977Y264718D02*
X1429982Y236441D01*
G01X1428886Y236064D02*
X1435455Y222595D01*
G01X1429982Y236441D02*
X1436663Y222744D01*
G01X1413959Y341056D02*
X1412024Y350170D01*
G01X1407105Y367795D02*
X1412809Y340935D01*
G01X1413959Y331252D02*
Y341056D01*
G01X1412809Y340935D02*
Y331729D01*
G01X1408278Y325571D02*
X1413959Y331252D01*
G01X1412809Y331729D02*
X1407128Y326048D01*
G01X1408278Y315722D02*
Y325571D01*
G01X1407128Y326048D02*
Y315245D01*
G01X1411776Y312226D02*
X1408278Y315722D01*
G01X1407128Y315245D02*
X1410626Y311749D01*
G01X1411776Y290619D02*
Y312226D01*
G01X1410626Y311749D02*
Y290873D01*
G01Y311749D02*
Y290873D01*
G01X1411776Y290619D02*
Y312226D01*
G01X1407128Y315245D02*
X1410626Y311749D01*
G01X1411776Y312226D02*
X1408278Y315722D01*
G01X1407128Y326048D02*
Y315245D01*
G01X1408278Y315722D02*
Y325571D01*
G01X1412809Y331729D02*
X1407128Y326048D01*
G01X1408278Y325571D02*
X1413959Y331252D01*
G01X1412809Y340935D02*
Y331729D01*
G01X1413959Y331252D02*
Y341056D01*
G01X1407105Y367795D02*
X1412809Y340935D01*
G01X1413959Y341056D02*
X1412024Y350170D01*
G01X1407105Y367795D02*
X1412809Y340935D01*
G01X1407105Y367795D02*
X1412809Y340935D01*
G01X1407105Y367795D02*
X1412809Y340935D01*
G01X1407105Y367795D02*
X1412809Y340935D01*
G01X1421859Y295932D02*
X1419241Y287569D01*
G01X1418127Y287862D02*
X1420846Y296547D01*
G01X1424900Y298974D02*
X1421859Y295932D01*
G01X1420846Y296547D02*
X1423750Y299451D01*
G01X1424900Y360039D02*
Y298974D01*
G01X1423750Y299451D02*
Y360160D01*
G01X1422400Y361527D02*
Y300573D01*
G01X1421250Y361648D02*
Y301050D01*
G01X1422400Y300573D02*
X1419605Y297777D01*
G01X1421250Y301050D02*
X1418591Y298391D01*
G01X1419605Y297777D02*
X1417306Y290435D01*
G01X1418591Y298391D02*
X1416230Y290850D01*
G01X1419150Y361768D02*
Y324788D01*
G01X1418000Y361291D02*
Y325265D01*
G01X1419150Y324788D02*
X1417205Y322843D01*
G01X1418000Y325265D02*
X1416055Y323320D01*
G01X1417205Y322843D02*
Y300700D01*
G01X1416055Y323320D02*
Y300844D01*
G01X1417205Y300700D02*
X1414742Y290959D01*
G01X1416055Y300844D02*
X1413653Y291344D01*
G01X1423750Y299451D02*
Y360160D01*
G01X1424900Y360039D02*
Y298974D01*
G01X1420846Y296547D02*
X1423750Y299451D01*
G01X1424900Y298974D02*
X1421859Y295932D01*
G01X1418127Y287862D02*
X1420846Y296547D01*
G01X1421859Y295932D02*
X1419241Y287569D01*
G01X1421250Y361648D02*
Y301050D01*
G01X1422400Y361527D02*
Y300573D01*
G01X1421250Y301050D02*
X1418591Y298391D01*
G01X1422400Y300573D02*
X1419605Y297777D01*
G01X1418591Y298391D02*
X1416230Y290850D01*
G01X1419605Y297777D02*
X1417306Y290435D01*
G01X1418000Y361291D02*
Y325265D01*
G01X1419150Y361768D02*
Y324788D01*
G01X1418000Y325265D02*
X1416055Y323320D01*
G01X1419150Y324788D02*
X1417205Y322843D01*
G01X1416055Y323320D02*
Y300844D01*
G01X1417205Y322843D02*
Y300700D01*
G01X1416055Y300844D02*
X1413653Y291344D01*
G01X1417205Y300700D02*
X1414742Y290959D01*
G01X1429900Y354290D02*
Y296559D01*
G01X1428750Y354405D02*
Y297036D01*
G01X1429900Y296559D02*
X1426532Y293191D01*
G01X1428750Y297036D02*
X1425520Y293806D01*
G01X1426530Y293185D02*
X1424278Y285991D01*
G01X1425518Y293805D02*
X1423164Y286283D01*
G01X1427400Y297772D02*
Y357767D01*
G01X1426250Y357883D02*
Y298249D01*
G01X1424392Y294763D02*
X1427400Y297772D01*
G01X1426250Y298249D02*
X1423378Y295377D01*
G01X1421697Y286150D02*
X1424392Y294763D01*
G01X1423378Y295377D02*
X1420583Y286442D01*
G01X1433138Y292338D02*
X1434900Y294100D01*
G01X1432083Y292911D02*
X1433750Y294577D01*
G01X1434900Y294100D02*
Y351788D01*
G01X1433750Y294577D02*
Y351910D01*
G01X1432400Y352711D02*
Y295300D01*
G01X1431250Y352827D02*
Y295777D01*
G01X1432400Y295300D02*
X1428868Y291768D01*
G01X1431250Y295777D02*
X1427855Y292382D01*
G01X1428868Y291768D02*
X1426379Y283841D01*
G01X1427855Y292382D02*
X1425265Y284133D01*
G01X1428750Y354405D02*
Y297036D01*
G01X1429900Y354290D02*
Y296559D01*
G01X1428750Y297036D02*
X1425520Y293806D01*
G01X1429900Y296559D02*
X1426532Y293191D01*
G01X1425518Y293805D02*
X1423164Y286283D01*
G01X1426530Y293185D02*
X1424278Y285991D01*
G01X1423378Y295377D02*
X1420583Y286442D01*
G01X1421697Y286150D02*
X1424392Y294763D01*
G01X1426250Y298249D02*
X1423378Y295377D01*
G01X1424392Y294763D02*
X1427400Y297772D01*
G01X1426250Y357883D02*
Y298249D01*
G01X1427400Y297772D02*
Y357767D01*
G01X1432083Y292911D02*
X1433750Y294577D01*
G01X1433138Y292338D02*
X1434900Y294100D01*
G01X1433750Y294577D02*
Y351910D01*
G01X1434900Y294100D02*
Y351788D01*
G01X1431250Y352827D02*
Y295777D01*
G01X1432400Y352711D02*
Y295300D01*
G01X1431250Y295777D02*
X1427855Y292382D01*
G01X1432400Y295300D02*
X1428868Y291768D01*
G01X1427855Y292382D02*
X1425265Y284133D01*
G01X1428868Y291768D02*
X1426379Y283841D01*
G01X1406014Y389185D02*
X1410500Y410322D01*
G01X1409350Y410443D02*
X1404838Y389185D01*
G01X1409419Y373155D02*
X1406014Y389185D01*
G01X1404838D02*
X1408243Y373153D01*
G01X1408281Y367795D02*
X1409419Y373155D01*
G01X1408242Y373153D02*
X1407105Y367795D01*
G01X1411474Y352763D02*
X1411194Y354084D01*
G01X1410643Y356676D02*
X1410362Y357997D01*
G01X1409812Y360589D02*
X1409531Y361909D01*
G01X1408981Y364501D02*
X1408281Y367795D01*
G01X1411474Y352763D02*
X1411194Y354084D01*
G01X1410643Y356676D02*
X1410362Y357997D01*
G01X1409812Y360589D02*
X1409531Y361909D01*
G01X1408981Y364501D02*
X1408281Y367795D01*
G01X1408242Y373153D02*
X1407105Y367795D01*
G01X1408281D02*
X1409419Y373155D01*
G01X1404838Y389185D02*
X1408243Y373153D01*
G01X1409419Y373155D02*
X1406014Y389185D01*
G01X1409350Y410443D02*
X1404838Y389185D01*
G01X1406014D02*
X1410500Y410322D01*
G01X1428166Y375407D02*
X1424900Y360039D01*
G01X1423750Y360160D02*
X1427016Y375528D01*
G01X1428166Y391579D02*
Y375407D01*
G01X1427016Y375528D02*
Y391462D01*
G01X1425309Y405528D02*
X1428166Y391579D01*
G01X1427016Y391462D02*
X1424159Y405411D01*
G01X1422058Y408877D02*
X1425664Y391265D01*
G01X1420908Y408760D02*
X1424514Y391148D01*
G01X1425664Y391265D02*
Y376917D01*
G01X1424514Y391148D02*
Y377038D01*
G01X1425664Y376917D02*
X1422400Y361527D01*
G01X1424514Y377038D02*
X1421250Y361648D01*
G01X1418856Y403731D02*
Y398503D01*
G01X1417706Y403254D02*
Y398980D01*
G01X1418856Y398503D02*
X1417460Y397107D01*
G01X1417706Y398980D02*
X1416310Y397584D01*
G01X1417460Y397107D02*
Y388813D01*
G01X1416310Y397584D02*
Y389290D01*
G01X1417460Y388813D02*
X1414575Y385928D01*
G01X1416310Y389290D02*
X1413425Y386405D01*
G01X1414575Y385928D02*
Y366343D01*
G01X1413425Y386405D02*
Y365866D01*
G01X1414575Y366343D02*
X1419150Y361768D01*
G01X1413425Y365866D02*
X1418000Y361291D01*
G01X1427016Y391462D02*
X1424159Y405411D01*
G01X1425309Y405528D02*
X1428166Y391579D01*
G01X1427016Y375528D02*
Y391462D01*
G01X1428166Y391579D02*
Y375407D01*
G01X1423750Y360160D02*
X1427016Y375528D01*
G01X1428166Y375407D02*
X1424900Y360039D01*
G01X1420908Y408760D02*
X1424514Y391148D01*
G01X1422058Y408877D02*
X1425664Y391265D01*
G01X1424514Y391148D02*
Y377038D01*
G01X1425664Y391265D02*
Y376917D01*
G01X1424514Y377038D02*
X1421250Y361648D01*
G01X1425664Y376917D02*
X1422400Y361527D01*
G01X1417706Y403254D02*
Y398980D01*
G01X1418856Y403731D02*
Y398503D01*
G01X1417706Y398980D02*
X1416310Y397584D01*
G01X1418856Y398503D02*
X1417460Y397107D01*
G01X1416310Y397584D02*
Y389290D01*
G01X1417460Y397107D02*
Y388813D01*
G01X1416310Y389290D02*
X1413425Y386405D01*
G01X1417460Y388813D02*
X1414575Y385928D01*
G01X1413425Y386405D02*
Y365866D01*
G01X1414575Y385928D02*
Y366343D01*
G01X1413425Y365866D02*
X1418000Y361291D01*
G01X1414575Y366343D02*
X1419150Y361768D01*
G01X1433216Y413084D02*
Y370712D01*
G01X1432066Y412607D02*
Y370827D01*
G01X1433216Y370712D02*
X1429900Y354290D01*
G01X1432066Y370827D02*
X1428750Y354405D01*
G01X1430666Y373889D02*
Y411934D01*
G01X1429516Y411457D02*
Y374005D01*
G01X1427400Y357767D02*
X1430666Y373889D01*
G01X1429516Y374005D02*
X1426250Y357883D01*
G01X1434900Y351788D02*
X1439041Y371173D01*
G01X1433750Y351910D02*
X1437891Y371295D01*
G01X1439041Y371173D02*
Y397315D01*
G01X1437891Y371295D02*
Y397792D01*
G01X1439041Y397315D02*
X1452050Y410324D01*
G01X1437891Y397792D02*
X1450900Y410801D01*
G01X1435816Y414184D02*
Y369560D01*
G01X1434666Y413707D02*
Y369678D01*
G01X1435816Y369560D02*
X1432400Y352711D01*
G01X1434666Y369678D02*
X1431250Y352827D01*
G01X1432066Y412607D02*
Y370827D01*
G01X1433216Y413084D02*
Y370712D01*
G01X1432066Y370827D02*
X1428750Y354405D01*
G01X1433216Y370712D02*
X1429900Y354290D01*
G01X1429516Y374005D02*
X1426250Y357883D01*
G01X1427400Y357767D02*
X1430666Y373889D01*
G01X1429516Y411457D02*
Y374005D01*
G01X1430666Y373889D02*
Y411934D01*
G01X1433750Y351910D02*
X1437891Y371295D01*
G01X1434900Y351788D02*
X1439041Y371173D01*
G01X1437891Y371295D02*
Y397792D01*
G01X1439041Y371173D02*
Y397315D01*
G01X1437891Y397792D02*
X1450900Y410801D01*
G01X1439041Y397315D02*
X1452050Y410324D01*
G01X1434666Y413707D02*
Y369678D01*
G01X1435816Y414184D02*
Y369560D01*
G01X1434666Y369678D02*
X1431250Y352827D01*
G01X1435816Y369560D02*
X1432400Y352711D01*
G01X1415684Y460085D02*
X1411382Y463371D01*
G01X1410889Y462299D02*
X1414646Y459430D01*
G01X1418793Y445430D02*
X1415684Y460085D01*
G01X1414646Y459430D02*
X1417617Y445430D01*
G01X1414949Y427332D02*
X1418793Y445430D01*
G01X1417617D02*
X1413921Y428029D01*
G01X1411124Y424783D02*
X1414949Y427332D01*
G01X1413921Y428029D02*
X1410245Y425580D01*
G01X1410500Y423612D02*
X1411124Y424783D01*
G01X1410245Y425580D02*
X1409350Y423900D01*
G01X1410500Y410322D02*
Y418182D01*
G01Y420832D02*
Y423612D01*
G01X1409350Y423900D02*
Y410443D01*
G01Y423900D02*
Y410443D01*
G01X1410500Y410322D02*
Y418182D01*
G01X1409350Y423900D02*
Y410443D01*
G01X1410500Y420832D02*
Y423612D01*
G01X1410245Y425580D02*
X1409350Y423900D01*
G01X1410500Y423612D02*
X1411124Y424783D01*
G01X1413921Y428029D02*
X1410245Y425580D01*
G01X1411124Y424783D02*
X1414949Y427332D01*
G01X1417617Y445430D02*
X1413921Y428029D01*
G01X1414949Y427332D02*
X1418793Y445430D01*
G01X1414646Y459430D02*
X1417617Y445430D01*
G01X1418793D02*
X1415684Y460085D01*
G01X1410889Y462299D02*
X1414646Y459430D01*
G01X1415684Y460085D02*
X1411382Y463371D01*
G01X1425309Y437844D02*
Y405528D01*
G01X1424159Y405411D02*
Y412735D01*
G01X1425309Y437844D02*
Y405528D01*
G01X1424159Y415385D02*
Y416735D01*
G01X1425309Y437844D02*
Y405528D01*
G01X1424159Y419385D02*
Y426640D01*
G01X1425309Y437844D02*
Y405528D01*
G01X1424159Y429290D02*
Y430640D01*
G01X1425309Y437844D02*
Y405528D01*
G01X1424159Y433290D02*
Y437965D01*
G01X1427130Y446419D02*
X1425309Y437844D01*
G01X1424159Y437965D02*
X1425954Y446419D01*
G01X1423346Y464238D02*
X1427130Y446419D01*
G01X1425954D02*
X1422309Y463582D01*
G01X1414399Y471071D02*
X1423346Y464238D01*
G01X1422309Y463582D02*
X1413906Y469999D01*
G01X1413716Y468256D02*
X1421140Y462584D01*
G01X1413223Y467184D02*
X1420103Y461928D01*
G01X1421140Y462584D02*
X1424551Y446521D01*
G01X1420103Y461928D02*
X1423375Y446521D01*
G01X1424551D02*
X1422058Y434786D01*
G01X1423375Y446521D02*
X1420908Y434907D01*
G01X1422058Y434786D02*
Y408877D01*
G01X1420908Y434907D02*
Y430469D01*
G01X1422058Y434786D02*
Y408877D01*
G01X1420908Y427819D02*
Y426469D01*
G01X1422058Y434786D02*
Y408877D01*
G01X1420908Y423819D02*
Y422469D01*
G01X1422058Y434786D02*
Y408877D01*
G01X1420908Y419819D02*
Y418469D01*
G01X1422058Y434786D02*
Y408877D01*
G01X1420908Y415819D02*
Y408760D01*
G01X1412717Y465686D02*
X1418932Y460939D01*
G01X1412224Y464614D02*
X1417895Y460283D01*
G01X1418932Y460939D02*
X1421889Y447013D01*
G01X1417895Y460283D02*
X1419051Y454839D01*
G01X1418932Y460939D02*
X1421889Y447013D01*
G01X1419602Y452247D02*
X1419882Y450926D01*
G01X1418932Y460939D02*
X1421889Y447013D01*
G01X1420433Y448334D02*
X1420713Y447013D01*
G01X1421889D02*
X1418856Y432740D01*
G01X1420713Y447013D02*
X1417706Y432861D01*
G01X1418856Y432740D02*
Y414127D01*
G01X1417706Y432861D02*
Y414604D01*
G01X1418856Y414127D02*
X1417733Y413004D01*
G01X1417706Y414604D02*
X1417256Y414154D01*
G01X1417733Y413004D02*
X1414515D01*
G01X1417256Y414154D02*
X1414038D01*
G01X1414515Y413004D02*
X1414065Y412554D01*
G01X1414038Y414154D02*
X1412915Y413031D01*
G01X1414065Y412554D02*
Y411504D01*
G01X1412915Y413031D02*
Y411027D01*
G01X1414065Y411504D02*
X1414515Y411054D01*
G01X1412915Y411027D02*
X1414038Y409904D01*
G01X1414515Y411054D02*
X1417733D01*
G01X1414038Y409904D02*
X1417256D01*
G01X1417733Y411054D02*
X1418856Y409931D01*
G01X1417256Y409904D02*
X1417706Y409454D01*
G01X1418856Y409931D02*
Y407927D01*
G01X1417706Y409454D02*
Y408404D01*
G01X1418856Y407927D02*
X1417733Y406804D01*
G01X1417706Y408404D02*
X1417256Y407954D01*
G01X1417733Y406804D02*
X1414515D01*
G01X1417256Y407954D02*
X1414038D01*
G01X1414515Y406804D02*
X1414065Y406354D01*
G01X1414038Y407954D02*
X1412915Y406831D01*
G01X1414065Y406354D02*
Y405304D01*
G01X1412915Y406831D02*
Y404827D01*
G01X1414065Y405304D02*
X1414515Y404854D01*
G01X1412915Y404827D02*
X1414038Y403704D01*
G01X1414515Y404854D02*
X1417733D01*
G01X1414038Y403704D02*
X1417256D01*
G01X1417733Y404854D02*
X1418856Y403731D01*
G01X1417256Y403704D02*
X1417706Y403254D01*
G01X1422309Y463582D02*
X1413906Y469999D01*
G01X1414399Y471071D02*
X1423346Y464238D01*
G01X1425954Y446419D02*
X1422309Y463582D01*
G01X1423346Y464238D02*
X1427130Y446419D01*
G01X1424159Y437965D02*
X1425954Y446419D01*
G01X1427130D02*
X1425309Y437844D01*
G01X1424159Y405411D02*
Y412735D01*
G01Y415385D02*
Y416735D01*
G01Y419385D02*
Y426640D01*
G01Y429290D02*
Y430640D01*
G01Y433290D02*
Y437965D01*
G01X1425309Y437844D02*
Y405528D01*
G01X1413223Y467184D02*
X1420103Y461928D01*
G01X1413716Y468256D02*
X1421140Y462584D01*
G01X1420103Y461928D02*
X1423375Y446521D01*
G01X1421140Y462584D02*
X1424551Y446521D01*
G01X1423375D02*
X1420908Y434907D01*
G01X1424551Y446521D02*
X1422058Y434786D01*
G01X1420908Y434907D02*
Y430469D01*
G01Y427819D02*
Y426469D01*
G01Y423819D02*
Y422469D01*
G01Y419819D02*
Y418469D01*
G01Y415819D02*
Y408760D01*
G01X1422058Y434786D02*
Y408877D01*
G01X1412224Y464614D02*
X1417895Y460283D01*
G01X1412717Y465686D02*
X1418932Y460939D01*
G01X1417895Y460283D02*
X1419051Y454839D01*
G01X1419602Y452247D02*
X1419882Y450926D01*
G01X1420433Y448334D02*
X1420713Y447013D01*
G01X1418932Y460939D02*
X1421889Y447013D01*
G01X1420713D02*
X1417706Y432861D01*
G01X1421889Y447013D02*
X1418856Y432740D01*
G01X1417706Y432861D02*
Y414604D01*
G01X1418856Y432740D02*
Y414127D01*
G01X1417706Y414604D02*
X1417256Y414154D01*
G01X1418856Y414127D02*
X1417733Y413004D01*
G01X1417256Y414154D02*
X1414038D01*
G01X1417733Y413004D02*
X1414515D01*
G01X1414038Y414154D02*
X1412915Y413031D01*
G01X1414515Y413004D02*
X1414065Y412554D01*
G01X1412915Y413031D02*
Y411027D01*
G01X1414065Y412554D02*
Y411504D01*
G01X1412915Y411027D02*
X1414038Y409904D01*
G01X1414065Y411504D02*
X1414515Y411054D01*
G01X1414038Y409904D02*
X1417256D01*
G01X1414515Y411054D02*
X1417733D01*
G01X1417256Y409904D02*
X1417706Y409454D01*
G01X1417733Y411054D02*
X1418856Y409931D01*
G01X1417706Y409454D02*
Y408404D01*
G01X1418856Y409931D02*
Y407927D01*
G01X1417706Y408404D02*
X1417256Y407954D01*
G01X1418856Y407927D02*
X1417733Y406804D01*
G01X1417256Y407954D02*
X1414038D01*
G01X1417733Y406804D02*
X1414515D01*
G01X1414038Y407954D02*
X1412915Y406831D01*
G01X1414515Y406804D02*
X1414065Y406354D01*
G01X1412915Y406831D02*
Y404827D01*
G01X1414065Y406354D02*
Y405304D01*
G01X1412915Y404827D02*
X1414038Y403704D01*
G01X1414065Y405304D02*
X1414515Y404854D01*
G01X1414038Y403704D02*
X1417256D01*
G01X1414515Y404854D02*
X1417733D01*
G01X1417256Y403704D02*
X1417706Y403254D01*
G01X1417733Y404854D02*
X1418856Y403731D01*
G01X1424116Y478127D02*
X1438836Y463407D01*
G01X1424116Y478127D02*
X1438836Y463407D01*
G01X1424116Y478127D02*
X1438836Y463407D01*
G01X1424116Y478127D02*
X1438836Y463407D01*
G01X1424116Y478127D02*
X1438836Y463407D01*
G01X1436655Y463961D02*
X1437686Y462930D01*
G01X1438836Y463407D02*
Y436264D01*
G01X1437686Y462930D02*
Y458729D01*
G01X1438836Y463407D02*
Y436264D01*
G01X1437686Y456079D02*
Y454729D01*
G01X1438836Y463407D02*
Y436264D01*
G01X1437686Y452079D02*
Y444741D01*
G01X1438836Y463407D02*
Y436264D01*
G01X1437686Y442091D02*
Y440741D01*
G01X1438836Y463407D02*
Y436264D01*
G01X1437686Y438091D02*
Y436741D01*
G01X1438836Y436264D02*
X1430454Y427882D01*
G01X1437686Y436741D02*
X1429304Y428359D01*
G01X1430454Y427882D02*
Y415846D01*
G01X1429304Y428359D02*
Y415369D01*
G01X1430454Y415846D02*
X1433216Y413084D01*
G01X1429304Y415369D02*
X1432066Y412607D01*
G01X1435575Y461071D02*
X1422200Y474446D01*
G01X1421723Y473296D02*
X1434425Y460594D01*
G01X1435575Y436559D02*
Y461071D01*
G01X1434425Y460594D02*
Y437036D01*
G01X1427954Y428938D02*
X1435575Y436559D01*
G01X1434425Y437036D02*
X1426804Y429415D01*
G01X1427954Y414646D02*
Y428938D01*
G01X1426804Y429415D02*
Y414169D01*
G01X1430666Y411934D02*
X1427954Y414646D01*
G01X1426804Y414169D02*
X1429516Y411457D01*
G01X1452050Y410324D02*
Y447960D01*
G01X1450900Y410801D02*
Y447483D01*
G01X1452050Y447960D02*
X1444850Y455160D01*
G01X1450900Y447483D02*
X1443700Y454683D01*
G01X1444850Y455160D02*
Y466518D01*
G01X1443700Y454683D02*
Y466041D01*
G01X1441391Y465426D02*
Y435270D01*
G01X1440241Y464949D02*
Y435747D01*
G01X1441391Y435270D02*
X1432954Y426833D01*
G01X1440241Y435747D02*
X1431804Y427310D01*
G01X1432954Y426833D02*
Y417046D01*
G01X1431804Y427310D02*
Y416569D01*
G01X1432954Y417046D02*
X1435816Y414184D01*
G01X1431804Y416569D02*
X1434666Y413707D01*
G01X1436655Y463961D02*
X1437686Y462930D01*
G01X1424116Y478127D02*
X1438836Y463407D01*
G01X1437686Y462930D02*
Y458729D01*
G01Y456079D02*
Y454729D01*
G01Y452079D02*
Y444741D01*
G01Y442091D02*
Y440741D01*
G01Y438091D02*
Y436741D01*
G01X1438836Y463407D02*
Y436264D01*
G01X1437686Y436741D02*
X1429304Y428359D01*
G01X1438836Y436264D02*
X1430454Y427882D01*
G01X1429304Y428359D02*
Y415369D01*
G01X1430454Y427882D02*
Y415846D01*
G01X1429304Y415369D02*
X1432066Y412607D01*
G01X1430454Y415846D02*
X1433216Y413084D01*
G01X1426804Y414169D02*
X1429516Y411457D01*
G01X1430666Y411934D02*
X1427954Y414646D01*
G01X1426804Y429415D02*
Y414169D01*
G01X1427954Y414646D02*
Y428938D01*
G01X1434425Y437036D02*
X1426804Y429415D01*
G01X1427954Y428938D02*
X1435575Y436559D01*
G01X1434425Y460594D02*
Y437036D01*
G01X1435575Y436559D02*
Y461071D01*
G01X1421723Y473296D02*
X1434425Y460594D01*
G01X1435575Y461071D02*
X1422200Y474446D01*
G01X1450900Y410801D02*
Y447483D01*
G01X1452050Y410324D02*
Y447960D01*
G01X1450900Y447483D02*
X1443700Y454683D01*
G01X1452050Y447960D02*
X1444850Y455160D01*
G01X1443700Y454683D02*
Y466041D01*
G01X1444850Y455160D02*
Y466518D01*
G01X1440241Y464949D02*
Y435747D01*
G01X1441391Y465426D02*
Y435270D01*
G01X1440241Y435747D02*
X1431804Y427310D01*
G01X1441391Y435270D02*
X1432954Y426833D01*
G01X1431804Y427310D02*
Y416569D01*
G01X1432954Y426833D02*
Y417046D01*
G01X1431804Y416569D02*
X1434666Y413707D01*
G01X1432954Y417046D02*
X1435816Y414184D01*
G01X1462895Y482173D02*
X1465656Y479412D01*
G01X1478119Y468576D02*
X1464045Y482650D01*
G01X1462895Y491465D02*
Y482173D01*
G01X1464045Y482650D02*
Y491942D01*
G01X1459815Y494545D02*
X1462895Y491465D01*
G01X1464045Y491942D02*
X1460965Y495022D01*
G01X1459815Y500158D02*
Y494545D01*
G01X1460965Y495022D02*
Y500634D01*
G01X1444773Y515200D02*
X1445728Y514245D01*
G01X1447601Y512372D02*
X1448556Y511417D01*
G01X1450430Y509543D02*
X1451385Y508588D01*
G01X1453258Y506715D02*
X1459815Y500158D01*
G01X1460965Y500634D02*
X1445250Y516350D01*
G01X1429273Y515200D02*
X1430623D01*
G01X1433273D02*
X1434623D01*
G01X1437273D02*
X1438623D01*
G01X1441273D02*
X1444773D01*
G01X1445250Y516350D02*
X1429750D01*
G01X1425300Y519173D02*
X1429273Y515200D01*
G01X1429750Y516350D02*
X1426450Y519650D01*
G01X1425300Y526370D02*
Y519173D01*
G01X1426450Y519650D02*
Y526847D01*
G01X1421281Y530389D02*
X1425300Y526370D01*
G01X1421281Y530389D02*
X1425300Y526370D01*
G01X1426450Y519650D02*
Y526847D01*
G01X1425300Y526370D02*
Y519173D01*
G01X1429750Y516350D02*
X1426450Y519650D01*
G01X1425300Y519173D02*
X1429273Y515200D01*
G01X1445250Y516350D02*
X1429750D01*
G01X1429273Y515200D02*
X1430623D01*
G01X1445250Y516350D02*
X1429750D01*
G01X1433273Y515200D02*
X1434623D01*
G01X1445250Y516350D02*
X1429750D01*
G01X1437273Y515200D02*
X1438623D01*
G01X1445250Y516350D02*
X1429750D01*
G01X1441273Y515200D02*
X1444773D01*
G01X1460965Y500634D02*
X1445250Y516350D01*
G01X1444773Y515200D02*
X1445728Y514245D01*
G01X1460965Y500634D02*
X1445250Y516350D01*
G01X1447601Y512372D02*
X1448556Y511417D01*
G01X1460965Y500634D02*
X1445250Y516350D01*
G01X1450430Y509543D02*
X1451385Y508588D01*
G01X1460965Y500634D02*
X1445250Y516350D01*
G01X1453258Y506715D02*
X1459815Y500158D01*
G01X1460965Y495022D02*
Y500634D01*
G01X1459815Y500158D02*
Y494545D01*
G01X1464045Y491942D02*
X1460965Y495022D01*
G01X1459815Y494545D02*
X1462895Y491465D01*
G01X1464045Y482650D02*
Y491942D01*
G01X1462895Y491465D02*
Y482173D01*
G01X1478119Y468576D02*
X1464045Y482650D01*
G01X1462895Y482173D02*
X1465656Y479412D01*
G01X1478119Y468576D02*
X1464045Y482650D01*
G01X1478119Y468576D02*
X1464045Y482650D01*
G01X1478119Y468576D02*
X1464045Y482650D01*
G01X1478119Y468576D02*
X1464045Y482650D01*
G01X1411809Y501023D02*
X1439058D01*
G01X1411960Y502173D02*
X1439272D01*
G01X1439058Y501023D02*
X1442317Y499772D01*
G01X1439272Y502173D02*
X1442958Y500759D01*
G01X1442317Y499772D02*
X1453813Y488276D01*
G01X1442958Y500759D02*
X1454963Y488753D01*
G01X1453813Y488276D02*
Y483559D01*
G01X1454963Y488753D02*
Y484036D01*
G01X1453813Y483559D02*
X1457322Y480050D01*
G01X1454963Y484036D02*
X1457799Y481200D01*
G01X1457322Y480050D02*
X1459223D01*
G01X1457799Y481200D02*
X1459700D01*
G01X1459223Y480050D02*
X1474000Y465273D01*
G01X1459700Y481200D02*
X1475150Y465750D01*
G01X1411960Y502173D02*
X1439272D01*
G01X1411809Y501023D02*
X1439058D01*
G01X1439272Y502173D02*
X1442958Y500759D01*
G01X1439058Y501023D02*
X1442317Y499772D01*
G01X1442958Y500759D02*
X1454963Y488753D01*
G01X1442317Y499772D02*
X1453813Y488276D01*
G01X1454963Y488753D02*
Y484036D01*
G01X1453813Y488276D02*
Y483559D01*
G01X1454963Y484036D02*
X1457799Y481200D01*
G01X1453813Y483559D02*
X1457322Y480050D01*
G01X1457799Y481200D02*
X1459700D01*
G01X1457322Y480050D02*
X1459223D01*
G01X1459700Y481200D02*
X1475150Y465750D01*
G01X1459223Y480050D02*
X1474000Y465273D01*
G01X1420315Y492449D02*
X1421766D01*
G01X1420017Y491299D02*
X1421289D01*
G01X1421766Y492449D02*
X1424116Y490099D01*
G01X1421289Y491299D02*
X1422966Y489622D01*
G01X1424116Y490099D02*
Y478127D01*
G01X1422966Y489622D02*
Y485650D01*
G01X1424116Y490099D02*
Y478127D01*
G01X1422966Y483000D02*
Y481650D01*
G01X1424116Y490099D02*
Y478127D01*
G01X1422966Y479000D02*
Y477650D01*
G01D02*
X1426298Y474318D01*
G01X1428171Y472445D02*
X1429126Y471490D01*
G01X1430999Y469617D02*
X1431954Y468662D01*
G01X1433827Y466789D02*
X1434782Y465834D01*
G01X1411201Y479500D02*
X1417982D01*
G01X1417820Y480650D02*
X1410724D01*
G01X1410200Y478499D02*
X1411201Y479500D01*
G01X1410724Y480650D02*
X1409050Y478976D01*
G01X1410200Y476501D02*
Y478499D01*
G01X1409050Y478976D02*
Y476024D01*
G01X1412255Y474446D02*
X1410200Y476501D01*
G01X1409050Y476024D02*
X1411778Y473296D01*
G01X1422200Y474446D02*
X1412255D01*
G01X1411778Y473296D02*
X1421723D01*
G01X1444850Y466518D02*
X1434300Y477068D01*
G01X1443700Y466041D02*
X1433150Y476591D01*
G01X1434300Y477068D02*
Y478302D01*
G01X1433150Y476591D02*
Y478779D01*
G01X1434300Y478302D02*
X1435574Y479576D01*
G01X1433150Y478779D02*
X1435097Y480726D01*
G01X1435574Y479576D02*
X1441691D01*
G01X1435097Y480726D02*
X1441252D01*
G01X1441590Y491350D02*
X1432962D01*
G01X1441398Y492500D02*
X1432485D01*
G01X1432962Y491350D02*
X1430680Y489068D01*
G01X1432485Y492500D02*
X1429530Y489545D01*
G01X1430680Y489068D02*
Y476137D01*
G01X1429530Y489545D02*
Y475660D01*
G01X1430680Y476137D02*
X1441391Y465426D01*
G01X1429530Y475660D02*
X1440241Y464949D01*
G01X1420017Y491299D02*
X1421289D01*
G01X1420315Y492449D02*
X1421766D01*
G01X1421289Y491299D02*
X1422966Y489622D01*
G01X1421766Y492449D02*
X1424116Y490099D01*
G01X1422966Y489622D02*
Y485650D01*
G01Y483000D02*
Y481650D01*
G01Y479000D02*
Y477650D01*
G01X1424116Y490099D02*
Y478127D01*
G01X1422966Y477650D02*
X1426298Y474318D01*
G01X1428171Y472445D02*
X1429126Y471490D01*
G01X1430999Y469617D02*
X1431954Y468662D01*
G01X1433827Y466789D02*
X1434782Y465834D01*
G01X1411778Y473296D02*
X1421723D01*
G01X1422200Y474446D02*
X1412255D01*
G01X1409050Y476024D02*
X1411778Y473296D01*
G01X1412255Y474446D02*
X1410200Y476501D01*
G01X1409050Y478976D02*
Y476024D01*
G01X1410200Y476501D02*
Y478499D01*
G01X1410724Y480650D02*
X1409050Y478976D01*
G01X1410200Y478499D02*
X1411201Y479500D01*
G01X1417820Y480650D02*
X1410724D01*
G01X1411201Y479500D02*
X1417982D01*
G01X1443700Y466041D02*
X1433150Y476591D01*
G01X1444850Y466518D02*
X1434300Y477068D01*
G01X1433150Y476591D02*
Y478779D01*
G01X1434300Y477068D02*
Y478302D01*
G01X1433150Y478779D02*
X1435097Y480726D01*
G01X1434300Y478302D02*
X1435574Y479576D01*
G01X1435097Y480726D02*
X1441252D01*
G01X1435574Y479576D02*
X1441691D01*
G01X1441398Y492500D02*
X1432485D01*
G01X1441590Y491350D02*
X1432962D01*
G01X1432485Y492500D02*
X1429530Y489545D01*
G01X1432962Y491350D02*
X1430680Y489068D01*
G01X1429530Y489545D02*
Y475660D01*
G01X1430680Y489068D02*
Y476137D01*
G01X1429530Y475660D02*
X1440241Y464949D01*
G01X1430680Y476137D02*
X1441391Y465426D01*
G01X1426450Y526847D02*
X1422431Y530866D01*
G01X1421281Y532329D02*
Y530389D01*
G01X1422431Y530866D02*
Y532806D01*
G01X1413360Y540250D02*
X1421281Y532329D01*
G01X1422431Y532806D02*
X1413837Y541400D01*
G01X1422431Y532806D02*
X1413837Y541400D01*
G01X1413360Y540250D02*
X1421281Y532329D01*
G01X1422431Y530866D02*
Y532806D01*
G01X1421281Y532329D02*
Y530389D01*
G01X1426450Y526847D02*
X1422431Y530866D01*
G01X1406066Y644153D02*
X1404762Y643237D01*
G01X1406066Y644153D02*
X1404762Y643237D01*
G01X1404491Y644453D02*
X1405015Y644821D01*
G01X1407687Y653346D02*
X1406066Y644153D01*
G01X1405015Y644821D02*
X1406637Y654015D01*
G01X1408173Y644884D02*
X1409605Y653007D01*
G01X1410821Y653276D02*
X1409389Y645155D01*
G01X1409088Y643584D02*
X1408173Y644884D01*
G01X1409389Y645155D02*
X1409755Y644635D01*
G01X1412360Y644148D02*
X1411057Y643239D01*
G01D02*
X1409088Y643584D01*
G01X1409755Y644635D02*
X1410788Y644454D01*
G01X1412360Y644148D02*
X1411057Y643239D01*
G01X1410788Y644454D02*
X1411310Y644818D01*
G01X1413975Y653312D02*
X1412360Y644148D01*
G01X1411310Y644818D02*
X1412924Y653982D01*
G01X1414476Y644923D02*
X1415896Y652974D01*
G01X1417112Y653243D02*
X1415692Y645192D01*
G01X1415388Y643619D02*
X1414476Y644923D01*
G01X1415692Y645192D02*
X1416057Y644670D01*
G01X1418663Y644184D02*
X1417360Y643274D01*
G01D02*
X1415388Y643619D01*
G01X1416057Y644670D02*
X1417090Y644489D01*
G01X1418663Y644184D02*
X1417360Y643274D01*
G01X1417090Y644489D02*
X1417612Y644854D01*
G01X1420270Y653313D02*
X1418663Y644184D01*
G01X1417612Y644854D02*
X1419220Y653983D01*
G01X1420768Y644909D02*
X1422192Y652975D01*
G01X1423408Y653244D02*
X1421984Y645177D01*
G01X1421677Y643605D02*
X1420768Y644909D01*
G01X1421984Y645177D02*
X1422349Y644654D01*
G01X1424955Y644171D02*
X1423651Y643257D01*
G01D02*
X1421677Y643605D01*
G01X1422349Y644654D02*
X1423381Y644473D01*
G01X1424955Y644171D02*
X1423651Y643257D01*
G01X1423381Y644473D02*
X1423905Y644840D01*
G01X1426571Y653333D02*
X1424955Y644171D01*
G01X1423905Y644840D02*
X1425521Y654002D01*
G01X1427075Y644970D02*
X1428491Y652989D01*
G01X1429707Y653259D02*
X1428292Y645240D01*
G01X1427986Y643667D02*
X1427075Y644970D01*
G01X1428292Y645240D02*
X1428657Y644717D01*
G01X1431262Y644232D02*
X1429960Y643320D01*
G01D02*
X1427986Y643667D01*
G01X1428657Y644717D02*
X1429690Y644536D01*
G01X1431262Y644232D02*
X1429960Y643320D01*
G01X1429690Y644536D02*
X1430212Y644901D01*
G01X1432878Y653394D02*
X1431262Y644232D01*
G01X1430212Y644901D02*
X1431828Y654063D01*
G01X1433385Y645049D02*
X1434798Y653050D01*
G01X1436014Y653320D02*
X1434601Y645318D01*
G01X1434296Y643745D02*
X1433385Y645049D01*
G01X1434601Y645318D02*
X1434966Y644796D01*
G01X1437572Y644310D02*
X1436270Y643398D01*
G01D02*
X1434296Y643745D01*
G01X1434966Y644796D02*
X1436000Y644614D01*
G01X1437572Y644310D02*
X1436270Y643398D01*
G01X1436000Y644614D02*
X1436521Y644979D01*
G01X1439185Y653455D02*
X1437572Y644310D01*
G01X1436521Y644979D02*
X1438135Y654124D01*
G01X1439672Y644996D02*
X1441105Y653111D01*
G01X1442321Y653381D02*
X1440888Y645265D01*
G01X1440583Y643692D02*
X1439672Y644996D01*
G01X1440888Y645265D02*
X1441253Y644743D01*
G01X1443859Y644257D02*
X1442557Y643345D01*
G01D02*
X1440583Y643692D01*
G01X1441253Y644743D02*
X1442287Y644561D01*
G01X1443859Y644257D02*
X1442557Y643345D01*
G01X1442287Y644561D02*
X1442808Y644926D01*
G01X1445492Y653516D02*
X1443859Y644257D01*
G01X1442808Y644926D02*
X1444442Y654185D01*
G01X1445979Y645057D02*
X1447412Y653172D01*
G01X1448628Y653442D02*
X1447195Y645326D01*
G01X1446890Y643753D02*
X1445979Y645057D01*
G01X1447195Y645326D02*
X1447560Y644804D01*
G01X1450165Y644317D02*
X1448864Y643406D01*
G01D02*
X1446890Y643753D01*
G01X1447560Y644804D02*
X1448594Y644622D01*
G01X1450165Y644317D02*
X1448864Y643406D01*
G01X1448594Y644622D02*
X1449115Y644987D01*
G01X1451818Y653663D02*
X1450165Y644317D01*
G01X1449115Y644987D02*
X1450768Y654333D01*
G01X1452265Y644952D02*
X1453741Y653326D01*
G01X1454957Y653594D02*
X1453481Y645221D01*
G01X1453202Y643610D02*
X1452265Y644952D01*
G01X1453481Y645221D02*
X1453872Y644661D01*
G01X1456450Y644214D02*
X1455110Y643275D01*
G01D02*
X1453202Y643610D01*
G01X1453872Y644661D02*
X1454840Y644491D01*
G01X1456450Y644214D02*
X1455110Y643275D01*
G01X1454840Y644491D02*
X1455400Y644883D01*
G01X1458116Y653670D02*
X1456450Y644214D01*
G01X1455400Y644883D02*
X1457066Y654340D01*
G01X1458552Y644906D02*
X1460038Y653330D01*
G01X1461254Y653599D02*
X1459768Y645174D01*
G01X1459463Y643599D02*
X1458552Y644906D01*
G01X1459768Y645174D02*
X1460133Y644650D01*
G01X1462740Y644164D02*
X1461434Y643255D01*
G01D02*
X1459463Y643599D01*
G01X1460133Y644650D02*
X1461165Y644470D01*
G01X1462740Y644164D02*
X1461434Y643255D01*
G01X1461165Y644470D02*
X1461689Y644835D01*
G01X1464406Y653637D02*
X1462740Y644164D01*
G01X1461689Y644835D02*
X1463356Y654307D01*
G01X1464850Y644922D02*
X1466328Y653297D01*
G01X1465761Y643618D02*
X1464850Y644922D01*
G01X1465761Y643618D02*
X1464850Y644922D01*
G01D02*
X1466328Y653297D01*
G01X1461689Y644835D02*
X1463356Y654307D01*
G01X1464406Y653637D02*
X1462740Y644164D01*
G01X1460133Y644650D02*
X1461165Y644470D01*
G01D02*
X1461689Y644835D01*
G01X1462740Y644164D02*
X1461434Y643255D01*
G01X1460133Y644650D02*
X1461165Y644470D01*
G01X1461434Y643255D02*
X1459463Y643599D01*
G01X1459768Y645174D02*
X1460133Y644650D01*
G01X1459463Y643599D02*
X1458552Y644906D01*
G01X1461254Y653599D02*
X1459768Y645174D01*
G01X1458552Y644906D02*
X1460038Y653330D01*
G01X1455400Y644883D02*
X1457066Y654340D01*
G01X1458116Y653670D02*
X1456450Y644214D01*
G01X1453872Y644661D02*
X1454840Y644491D01*
G01D02*
X1455400Y644883D01*
G01X1456450Y644214D02*
X1455110Y643275D01*
G01X1453872Y644661D02*
X1454840Y644491D01*
G01X1455110Y643275D02*
X1453202Y643610D01*
G01X1453481Y645221D02*
X1453872Y644661D01*
G01X1453202Y643610D02*
X1452265Y644952D01*
G01X1454957Y653594D02*
X1453481Y645221D01*
G01X1452265Y644952D02*
X1453741Y653326D01*
G01X1449115Y644987D02*
X1450768Y654333D01*
G01X1451818Y653663D02*
X1450165Y644317D01*
G01X1447560Y644804D02*
X1448594Y644622D01*
G01D02*
X1449115Y644987D01*
G01X1450165Y644317D02*
X1448864Y643406D01*
G01X1447560Y644804D02*
X1448594Y644622D01*
G01X1448864Y643406D02*
X1446890Y643753D01*
G01X1447195Y645326D02*
X1447560Y644804D01*
G01X1446890Y643753D02*
X1445979Y645057D01*
G01X1448628Y653442D02*
X1447195Y645326D01*
G01X1445979Y645057D02*
X1447412Y653172D01*
G01X1442808Y644926D02*
X1444442Y654185D01*
G01X1445492Y653516D02*
X1443859Y644257D01*
G01X1441253Y644743D02*
X1442287Y644561D01*
G01D02*
X1442808Y644926D01*
G01X1443859Y644257D02*
X1442557Y643345D01*
G01X1441253Y644743D02*
X1442287Y644561D01*
G01X1442557Y643345D02*
X1440583Y643692D01*
G01X1440888Y645265D02*
X1441253Y644743D01*
G01X1440583Y643692D02*
X1439672Y644996D01*
G01X1442321Y653381D02*
X1440888Y645265D01*
G01X1439672Y644996D02*
X1441105Y653111D01*
G01X1436521Y644979D02*
X1438135Y654124D01*
G01X1439185Y653455D02*
X1437572Y644310D01*
G01X1434966Y644796D02*
X1436000Y644614D01*
G01D02*
X1436521Y644979D01*
G01X1437572Y644310D02*
X1436270Y643398D01*
G01X1434966Y644796D02*
X1436000Y644614D01*
G01X1436270Y643398D02*
X1434296Y643745D01*
G01X1434601Y645318D02*
X1434966Y644796D01*
G01X1434296Y643745D02*
X1433385Y645049D01*
G01X1436014Y653320D02*
X1434601Y645318D01*
G01X1433385Y645049D02*
X1434798Y653050D01*
G01X1430212Y644901D02*
X1431828Y654063D01*
G01X1432878Y653394D02*
X1431262Y644232D01*
G01X1428657Y644717D02*
X1429690Y644536D01*
G01D02*
X1430212Y644901D01*
G01X1431262Y644232D02*
X1429960Y643320D01*
G01X1428657Y644717D02*
X1429690Y644536D01*
G01X1429960Y643320D02*
X1427986Y643667D01*
G01X1428292Y645240D02*
X1428657Y644717D01*
G01X1427986Y643667D02*
X1427075Y644970D01*
G01X1429707Y653259D02*
X1428292Y645240D01*
G01X1427075Y644970D02*
X1428491Y652989D01*
G01X1423905Y644840D02*
X1425521Y654002D01*
G01X1426571Y653333D02*
X1424955Y644171D01*
G01X1422349Y644654D02*
X1423381Y644473D01*
G01D02*
X1423905Y644840D01*
G01X1424955Y644171D02*
X1423651Y643257D01*
G01X1422349Y644654D02*
X1423381Y644473D01*
G01X1423651Y643257D02*
X1421677Y643605D01*
G01X1421984Y645177D02*
X1422349Y644654D01*
G01X1421677Y643605D02*
X1420768Y644909D01*
G01X1423408Y653244D02*
X1421984Y645177D01*
G01X1420768Y644909D02*
X1422192Y652975D01*
G01X1417612Y644854D02*
X1419220Y653983D01*
G01X1420270Y653313D02*
X1418663Y644184D01*
G01X1416057Y644670D02*
X1417090Y644489D01*
G01D02*
X1417612Y644854D01*
G01X1418663Y644184D02*
X1417360Y643274D01*
G01X1416057Y644670D02*
X1417090Y644489D01*
G01X1417360Y643274D02*
X1415388Y643619D01*
G01X1415692Y645192D02*
X1416057Y644670D01*
G01X1415388Y643619D02*
X1414476Y644923D01*
G01X1417112Y653243D02*
X1415692Y645192D01*
G01X1414476Y644923D02*
X1415896Y652974D01*
G01X1411310Y644818D02*
X1412924Y653982D01*
G01X1413975Y653312D02*
X1412360Y644148D01*
G01X1409755Y644635D02*
X1410788Y644454D01*
G01D02*
X1411310Y644818D01*
G01X1412360Y644148D02*
X1411057Y643239D01*
G01X1409755Y644635D02*
X1410788Y644454D01*
G01X1411057Y643239D02*
X1409088Y643584D01*
G01X1409389Y645155D02*
X1409755Y644635D01*
G01X1409088Y643584D02*
X1408173Y644884D01*
G01X1410821Y653276D02*
X1409389Y645155D01*
G01X1408173Y644884D02*
X1409605Y653007D01*
G01X1405015Y644821D02*
X1406637Y654015D01*
G01X1407687Y653346D02*
X1406066Y644153D01*
G01X1404491Y644453D02*
X1405015Y644821D01*
G01X1406066Y644153D02*
X1404762Y643237D01*
G01X1409241Y653528D02*
X1408207Y653710D01*
G01D02*
X1407687Y653346D01*
G01X1406637Y654015D02*
X1407937Y654926D01*
G01X1409241Y653528D02*
X1408207Y653710D01*
G01X1407937Y654926D02*
X1409911Y654579D01*
G01X1409605Y653007D02*
X1409241Y653528D01*
G01X1409911Y654579D02*
X1410821Y653276D01*
G01X1415532Y653495D02*
X1414498Y653677D01*
G01D02*
X1413975Y653312D01*
G01X1412924Y653982D02*
X1414228Y654892D01*
G01X1415532Y653495D02*
X1414498Y653677D01*
G01X1414228Y654892D02*
X1416202Y654546D01*
G01X1415896Y652974D02*
X1415532Y653495D01*
G01X1416202Y654546D02*
X1417112Y653243D01*
G01X1421828Y653496D02*
X1420793Y653678D01*
G01D02*
X1420270Y653313D01*
G01X1419220Y653983D02*
X1420524Y654893D01*
G01X1421828Y653496D02*
X1420793Y653678D01*
G01X1420524Y654893D02*
X1422498Y654547D01*
G01X1422192Y652975D02*
X1421828Y653496D01*
G01X1422498Y654547D02*
X1423408Y653244D01*
G01X1428124Y653513D02*
X1427090Y653696D01*
G01D02*
X1426571Y653333D01*
G01X1425521Y654002D02*
X1426821Y654912D01*
G01X1428124Y653513D02*
X1427090Y653696D01*
G01X1426821Y654912D02*
X1428794Y654563D01*
G01X1428491Y652989D02*
X1428124Y653513D01*
G01X1428794Y654563D02*
X1429707Y653259D01*
G01X1434431Y653574D02*
X1433397Y653757D01*
G01D02*
X1432878Y653394D01*
G01X1431828Y654063D02*
X1433128Y654973D01*
G01X1434431Y653574D02*
X1433397Y653757D01*
G01X1433128Y654973D02*
X1435101Y654624D01*
G01X1434798Y653050D02*
X1434431Y653574D01*
G01X1435101Y654624D02*
X1436014Y653320D01*
G01X1440738Y653635D02*
X1439704Y653818D01*
G01D02*
X1439185Y653455D01*
G01X1438135Y654124D02*
X1439435Y655034D01*
G01X1440738Y653635D02*
X1439704Y653818D01*
G01X1439435Y655034D02*
X1441408Y654685D01*
G01X1441105Y653111D02*
X1440738Y653635D01*
G01X1441408Y654685D02*
X1442321Y653381D01*
G01X1447045Y653696D02*
X1446011Y653879D01*
G01D02*
X1445492Y653516D01*
G01X1444442Y654185D02*
X1445742Y655095D01*
G01X1447045Y653696D02*
X1446011Y653879D01*
G01X1445742Y655095D02*
X1447715Y654746D01*
G01X1447412Y653172D02*
X1447045Y653696D01*
G01X1447715Y654746D02*
X1448628Y653442D01*
G01X1453377Y653848D02*
X1452343Y654030D01*
G01D02*
X1451818Y653663D01*
G01X1450768Y654333D02*
X1452074Y655246D01*
G01X1453377Y653848D02*
X1452343Y654030D01*
G01X1452074Y655246D02*
X1454047Y654898D01*
G01X1453741Y653326D02*
X1453377Y653848D01*
G01X1454047Y654898D02*
X1454957Y653594D01*
G01X1459673Y653852D02*
X1458638Y654034D01*
G01D02*
X1458116Y653670D01*
G01X1457066Y654340D02*
X1458369Y655249D01*
G01X1459673Y653852D02*
X1458638Y654034D01*
G01X1458369Y655249D02*
X1460343Y654903D01*
G01X1460038Y653330D02*
X1459673Y653852D01*
G01X1460343Y654903D02*
X1461254Y653599D01*
G01X1465963Y653819D02*
X1464928Y654001D01*
G01D02*
X1464406Y653637D01*
G01X1463356Y654307D02*
X1464659Y655216D01*
G01X1465963Y653819D02*
X1464928Y654001D01*
G01X1464659Y655216D02*
X1466633Y654870D01*
G01X1463356Y654307D02*
X1464659Y655216D01*
G01D02*
X1466633Y654870D01*
G01X1465963Y653819D02*
X1464928Y654001D01*
G01X1463356Y654307D02*
X1464659Y655216D01*
G01X1464928Y654001D02*
X1464406Y653637D01*
G01X1460343Y654903D02*
X1461254Y653599D01*
G01X1460038Y653330D02*
X1459673Y653852D01*
G01X1457066Y654340D02*
X1458369Y655249D01*
G01D02*
X1460343Y654903D01*
G01X1459673Y653852D02*
X1458638Y654034D01*
G01X1457066Y654340D02*
X1458369Y655249D01*
G01X1458638Y654034D02*
X1458116Y653670D01*
G01X1454047Y654898D02*
X1454957Y653594D01*
G01X1453741Y653326D02*
X1453377Y653848D01*
G01X1450768Y654333D02*
X1452074Y655246D01*
G01D02*
X1454047Y654898D01*
G01X1453377Y653848D02*
X1452343Y654030D01*
G01X1450768Y654333D02*
X1452074Y655246D01*
G01X1452343Y654030D02*
X1451818Y653663D01*
G01X1447715Y654746D02*
X1448628Y653442D01*
G01X1447412Y653172D02*
X1447045Y653696D01*
G01X1444442Y654185D02*
X1445742Y655095D01*
G01D02*
X1447715Y654746D01*
G01X1447045Y653696D02*
X1446011Y653879D01*
G01X1444442Y654185D02*
X1445742Y655095D01*
G01X1446011Y653879D02*
X1445492Y653516D01*
G01X1441408Y654685D02*
X1442321Y653381D01*
G01X1441105Y653111D02*
X1440738Y653635D01*
G01X1438135Y654124D02*
X1439435Y655034D01*
G01D02*
X1441408Y654685D01*
G01X1440738Y653635D02*
X1439704Y653818D01*
G01X1438135Y654124D02*
X1439435Y655034D01*
G01X1439704Y653818D02*
X1439185Y653455D01*
G01X1435101Y654624D02*
X1436014Y653320D01*
G01X1434798Y653050D02*
X1434431Y653574D01*
G01X1431828Y654063D02*
X1433128Y654973D01*
G01D02*
X1435101Y654624D01*
G01X1434431Y653574D02*
X1433397Y653757D01*
G01X1431828Y654063D02*
X1433128Y654973D01*
G01X1433397Y653757D02*
X1432878Y653394D01*
G01X1428794Y654563D02*
X1429707Y653259D01*
G01X1428491Y652989D02*
X1428124Y653513D01*
G01X1425521Y654002D02*
X1426821Y654912D01*
G01D02*
X1428794Y654563D01*
G01X1428124Y653513D02*
X1427090Y653696D01*
G01X1425521Y654002D02*
X1426821Y654912D01*
G01X1427090Y653696D02*
X1426571Y653333D01*
G01X1422498Y654547D02*
X1423408Y653244D01*
G01X1422192Y652975D02*
X1421828Y653496D01*
G01X1419220Y653983D02*
X1420524Y654893D01*
G01D02*
X1422498Y654547D01*
G01X1421828Y653496D02*
X1420793Y653678D01*
G01X1419220Y653983D02*
X1420524Y654893D01*
G01X1420793Y653678D02*
X1420270Y653313D01*
G01X1416202Y654546D02*
X1417112Y653243D01*
G01X1415896Y652974D02*
X1415532Y653495D01*
G01X1412924Y653982D02*
X1414228Y654892D01*
G01D02*
X1416202Y654546D01*
G01X1415532Y653495D02*
X1414498Y653677D01*
G01X1412924Y653982D02*
X1414228Y654892D01*
G01X1414498Y653677D02*
X1413975Y653312D01*
G01X1409911Y654579D02*
X1410821Y653276D01*
G01X1409605Y653007D02*
X1409241Y653528D01*
G01X1406637Y654015D02*
X1407937Y654926D01*
G01D02*
X1409911Y654579D01*
G01X1409241Y653528D02*
X1408207Y653710D01*
G01X1406637Y654015D02*
X1407937Y654926D01*
G01X1408207Y653710D02*
X1407687Y653346D01*
G01X1497257Y38358D02*
X1539862Y29313D01*
G01X1497257Y37182D02*
X1539862Y28137D01*
G01X1538568Y7913D02*
X1526152Y10398D01*
G01X1538568Y6740D02*
X1525704Y9314D01*
G01X1526152Y10398D02*
X1525029Y11147D01*
G01X1523725Y12797D02*
X1522824Y12617D01*
G01D02*
X1521701Y13366D01*
G01X1520397Y15016D02*
X1519496Y14836D01*
G01D02*
X1518373Y15585D01*
G01X1517069Y17235D02*
X1516168Y17055D01*
G01D02*
X1515045Y17804D01*
G01X1513741Y19454D02*
X1512840Y19274D01*
G01D02*
X1495459Y30861D01*
G01X1525704Y9314D02*
X1495004Y29781D01*
G01X1495459Y30861D02*
X1485140Y33051D01*
G01X1495004Y29781D02*
X1485140Y31875D01*
G01Y33051D02*
X1480388Y32042D01*
G01X1485140Y31875D02*
X1480388Y30866D01*
G01Y32042D02*
X1475604Y33060D01*
G01X1480388Y30866D02*
X1475597Y31885D01*
G01X1475604Y33060D02*
X1469934Y31926D01*
G01X1475597Y31885D02*
X1469934Y30753D01*
G01Y31926D02*
X1465949Y32722D01*
G01X1469934Y30753D02*
X1465949Y31549D01*
G01X1497257Y37182D02*
X1539862Y28137D01*
G01X1497257Y38358D02*
X1539862Y29313D01*
G01X1538568Y6740D02*
X1525704Y9314D01*
G01X1538568Y7913D02*
X1526152Y10398D01*
G01X1525704Y9314D02*
X1495004Y29781D01*
G01X1526152Y10398D02*
X1525029Y11147D01*
G01X1525704Y9314D02*
X1495004Y29781D01*
G01X1523725Y12797D02*
X1522824Y12617D01*
G01X1525704Y9314D02*
X1495004Y29781D01*
G01X1522824Y12617D02*
X1521701Y13366D01*
G01X1525704Y9314D02*
X1495004Y29781D01*
G01X1520397Y15016D02*
X1519496Y14836D01*
G01X1525704Y9314D02*
X1495004Y29781D01*
G01X1519496Y14836D02*
X1518373Y15585D01*
G01X1525704Y9314D02*
X1495004Y29781D01*
G01X1517069Y17235D02*
X1516168Y17055D01*
G01X1525704Y9314D02*
X1495004Y29781D01*
G01X1516168Y17055D02*
X1515045Y17804D01*
G01X1525704Y9314D02*
X1495004Y29781D01*
G01X1513741Y19454D02*
X1512840Y19274D01*
G01X1525704Y9314D02*
X1495004Y29781D01*
G01X1512840Y19274D02*
X1495459Y30861D01*
G01X1495004Y29781D02*
X1485140Y31875D01*
G01X1495459Y30861D02*
X1485140Y33051D01*
G01Y31875D02*
X1480388Y30866D01*
G01X1485140Y33051D02*
X1480388Y32042D01*
G01Y30866D02*
X1475597Y31885D01*
G01X1480388Y32042D02*
X1475604Y33060D01*
G01X1475597Y31885D02*
X1469934Y30753D01*
G01X1475604Y33060D02*
X1469934Y31926D01*
G01Y30753D02*
X1465949Y31549D01*
G01X1469934Y31926D02*
X1465949Y32722D01*
G01X1465584Y40272D02*
X1465937Y41932D01*
G01D02*
X1466469Y42278D01*
G01X1466242Y43502D02*
X1493861Y37637D01*
G01X1466469Y42278D02*
X1493861Y36461D01*
G01Y37637D02*
X1497257Y38358D01*
G01X1493861Y36461D02*
X1497257Y37182D01*
G01X1465584Y40272D02*
X1465937Y41932D01*
G01D02*
X1466469Y42278D01*
G01D02*
X1493861Y36461D01*
G01X1466242Y43502D02*
X1493861Y37637D01*
G01Y36461D02*
X1497257Y37182D01*
G01X1493861Y37637D02*
X1497257Y38358D01*
G01X1493914Y48059D02*
X1497314Y48781D01*
G01X1493914Y46883D02*
X1497314Y47605D01*
G01Y48781D02*
X1526079Y42674D01*
G01X1497314Y47605D02*
X1526079Y41498D01*
G01Y42674D02*
X1542092Y46078D01*
G01X1526079Y41498D02*
X1542092Y44902D01*
G01X1493826Y45470D02*
X1497293Y46207D01*
G01X1493826Y44294D02*
X1497293Y45031D01*
G01Y46207D02*
X1526286Y40051D01*
G01X1497293Y45031D02*
X1526286Y38875D01*
G01Y40051D02*
X1542150Y43423D01*
G01X1526286Y38875D02*
X1542150Y42247D01*
G01X1493980Y42832D02*
X1497463Y43572D01*
G01X1493980Y41656D02*
X1497463Y42396D01*
G01Y43572D02*
X1530575Y36541D01*
G01X1497463Y42396D02*
X1538400Y33703D01*
G01X1494025Y40242D02*
X1497465Y40972D01*
G01X1494025Y39066D02*
X1497465Y39796D01*
G01Y40972D02*
X1538848Y32183D01*
G01X1497465Y39796D02*
X1538848Y31007D01*
G01X1467602Y64380D02*
X1469027Y62241D01*
G01D02*
X1482764Y53082D01*
G01X1468198Y61410D02*
X1482309Y52002D01*
G01X1482764Y53082D02*
X1494030Y50692D01*
G01X1482309Y52002D02*
X1494030Y49516D01*
G01Y50692D02*
X1497254Y51377D01*
G01X1494030Y49516D02*
X1497255Y50201D01*
G01X1497254Y51377D02*
X1525961Y45281D01*
G01X1497255Y50201D02*
X1525961Y44105D01*
G01Y45281D02*
X1542298Y48753D01*
G01X1525961Y44105D02*
X1542298Y47577D01*
G01X1493914Y46883D02*
X1497314Y47605D01*
G01X1493914Y48059D02*
X1497314Y48781D01*
G01Y47605D02*
X1526079Y41498D01*
G01X1497314Y48781D02*
X1526079Y42674D01*
G01Y41498D02*
X1542092Y44902D01*
G01X1526079Y42674D02*
X1542092Y46078D01*
G01X1493826Y44294D02*
X1497293Y45031D01*
G01X1493826Y45470D02*
X1497293Y46207D01*
G01Y45031D02*
X1526286Y38875D01*
G01X1497293Y46207D02*
X1526286Y40051D01*
G01Y38875D02*
X1542150Y42247D01*
G01X1526286Y40051D02*
X1542150Y43423D01*
G01X1493980Y41656D02*
X1497463Y42396D01*
G01X1493980Y42832D02*
X1497463Y43572D01*
G01Y42396D02*
X1538400Y33703D01*
G01X1497463Y43572D02*
X1530575Y36541D01*
G01X1497463Y42396D02*
X1538400Y33703D01*
G01X1497463Y42396D02*
X1538400Y33703D01*
G01X1494025Y39066D02*
X1497465Y39796D01*
G01X1494025Y40242D02*
X1497465Y40972D01*
G01Y39796D02*
X1538848Y31007D01*
G01X1497465Y40972D02*
X1538848Y32183D01*
G01X1467602Y64380D02*
X1469027Y62241D01*
G01X1468198Y61410D02*
X1482309Y52002D01*
G01X1469027Y62241D02*
X1482764Y53082D01*
G01X1482309Y52002D02*
X1494030Y49516D01*
G01X1482764Y53082D02*
X1494030Y50692D01*
G01Y49516D02*
X1497255Y50201D01*
G01X1494030Y50692D02*
X1497254Y51377D01*
G01X1497255Y50201D02*
X1525961Y44105D01*
G01X1497254Y51377D02*
X1525961Y45281D01*
G01Y44105D02*
X1542298Y47577D01*
G01X1525961Y45281D02*
X1542298Y48753D01*
G01X1483753Y55430D02*
X1475641Y60840D01*
G01X1474811Y60010D02*
X1483298Y54350D01*
G01X1493920Y53273D02*
X1483753Y55430D01*
G01X1483298Y54350D02*
X1493920Y52097D01*
G01X1497169Y53963D02*
X1493920Y53273D01*
G01Y52097D02*
X1497169Y52787D01*
G01X1525733Y47897D02*
X1497169Y53963D01*
G01Y52787D02*
X1525733Y46721D01*
G01X1533708Y49592D02*
X1525733Y47897D01*
G01Y46721D02*
X1542164Y50213D01*
G01X1525733Y46721D02*
X1542164Y50213D01*
G01X1525733Y46721D02*
X1542164Y50213D01*
G01X1525733Y46721D02*
X1542164Y50213D01*
G01X1533708Y49592D02*
X1525733Y47897D01*
G01X1497169Y52787D02*
X1525733Y46721D01*
G01Y47897D02*
X1497169Y53963D01*
G01X1493920Y52097D02*
X1497169Y52787D01*
G01Y53963D02*
X1493920Y53273D01*
G01X1483298Y54350D02*
X1493920Y52097D01*
G01Y53273D02*
X1483753Y55430D01*
G01X1474811Y60010D02*
X1483298Y54350D01*
G01X1483753Y55430D02*
X1475641Y60840D01*
G01X1485782Y58277D02*
X1478936Y62842D01*
G01X1478106Y62012D02*
X1485327Y57197D01*
G01X1494039Y56523D02*
X1485782Y58277D01*
G01X1485327Y57197D02*
X1494039Y55347D01*
G01X1497127Y57178D02*
X1494039Y56523D01*
G01Y55347D02*
X1497126Y56002D01*
G01X1525696Y51113D02*
X1497127Y57178D01*
G01X1497126Y56002D02*
X1525696Y49937D01*
G01X1542055Y54589D02*
X1525696Y51113D01*
G01Y49937D02*
X1542055Y53413D01*
G01X1525696Y49937D02*
X1542055Y53413D01*
G01Y54589D02*
X1525696Y51113D01*
G01X1497126Y56002D02*
X1525696Y49937D01*
G01Y51113D02*
X1497127Y57178D01*
G01X1494039Y55347D02*
X1497126Y56002D01*
G01X1497127Y57178D02*
X1494039Y56523D01*
G01X1485327Y57197D02*
X1494039Y55347D01*
G01Y56523D02*
X1485782Y58277D01*
G01X1478106Y62012D02*
X1485327Y57197D01*
G01X1485782Y58277D02*
X1478936Y62842D01*
G01X1524513Y59114D02*
X1540703Y62556D01*
G01Y61380D02*
X1524513Y57938D01*
G01X1495926Y65187D02*
X1524513Y59114D01*
G01Y57938D02*
X1495926Y64011D01*
G01X1493606Y64694D02*
X1495926Y65187D01*
G01Y64011D02*
X1493606Y63518D01*
G01X1488985Y65676D02*
X1493606Y64694D01*
G01Y63518D02*
X1488530Y64597D01*
G01X1485078Y68281D02*
X1488985Y65676D01*
G01X1488530Y64597D02*
X1484248Y67451D01*
G01X1465772Y97246D02*
X1485078Y68281D01*
G01X1483035Y66543D02*
X1488464Y62924D01*
G01X1482205Y65713D02*
X1488009Y61845D01*
G01X1488464Y62924D02*
X1493428Y61868D01*
G01X1488009Y61845D02*
X1493428Y60692D01*
G01Y61868D02*
X1496436Y62508D01*
G01X1493428Y60692D02*
X1496436Y61332D01*
G01Y62508D02*
X1525061Y56427D01*
G01X1496436Y61332D02*
X1525061Y55251D01*
G01Y56427D02*
X1541280Y59871D01*
G01X1525061Y55251D02*
X1541280Y58695D01*
G01X1480798Y64902D02*
X1487196Y60637D01*
G01X1479968Y64072D02*
X1486741Y59558D01*
G01X1487196Y60637D02*
X1493794Y59233D01*
G01X1486741Y59558D02*
X1493794Y58057D01*
G01Y59233D02*
X1496665Y59844D01*
G01X1493794Y58057D02*
X1496664Y58668D01*
G01X1496665Y59844D02*
X1525071Y53809D01*
G01X1496664Y58668D02*
X1525071Y52633D01*
G01Y53809D02*
X1541420Y57281D01*
G01X1525071Y52633D02*
X1541420Y56105D01*
G01X1465772Y97246D02*
X1485078Y68281D01*
G01X1488530Y64597D02*
X1484248Y67451D01*
G01X1485078Y68281D02*
X1488985Y65676D01*
G01X1493606Y63518D02*
X1488530Y64597D01*
G01X1488985Y65676D02*
X1493606Y64694D01*
G01X1495926Y64011D02*
X1493606Y63518D01*
G01Y64694D02*
X1495926Y65187D01*
G01X1524513Y57938D02*
X1495926Y64011D01*
G01Y65187D02*
X1524513Y59114D01*
G01X1540703Y61380D02*
X1524513Y57938D01*
G01Y59114D02*
X1540703Y62556D01*
G01X1482205Y65713D02*
X1488009Y61845D01*
G01X1483035Y66543D02*
X1488464Y62924D01*
G01X1488009Y61845D02*
X1493428Y60692D01*
G01X1488464Y62924D02*
X1493428Y61868D01*
G01Y60692D02*
X1496436Y61332D01*
G01X1493428Y61868D02*
X1496436Y62508D01*
G01Y61332D02*
X1525061Y55251D01*
G01X1496436Y62508D02*
X1525061Y56427D01*
G01Y55251D02*
X1541280Y58695D01*
G01X1525061Y56427D02*
X1541280Y59871D01*
G01X1479968Y64072D02*
X1486741Y59558D01*
G01X1480798Y64902D02*
X1487196Y60637D01*
G01X1486741Y59558D02*
X1493794Y58057D01*
G01X1487196Y60637D02*
X1493794Y59233D01*
G01Y58057D02*
X1496664Y58668D01*
G01X1493794Y59233D02*
X1496665Y59844D01*
G01X1496664Y58668D02*
X1525071Y52633D01*
G01X1496665Y59844D02*
X1525071Y53809D01*
G01Y52633D02*
X1541420Y56105D01*
G01X1525071Y53809D02*
X1541420Y57281D01*
G01X1470580Y99534D02*
X1488997Y71901D01*
G01X1469501Y99079D02*
X1488167Y71071D01*
G01X1488997Y71901D02*
X1490208Y71094D01*
G01X1488167Y71071D02*
X1489753Y70014D01*
G01X1490208Y71094D02*
X1494097Y70268D01*
G01X1489753Y70014D02*
X1494097Y69092D01*
G01Y70268D02*
X1495454Y70556D01*
G01X1494097Y69092D02*
X1495454Y69380D01*
G01Y70556D02*
X1524530Y64382D01*
G01X1495454Y69380D02*
X1524532Y63205D01*
G01X1524530Y64382D02*
X1540378Y67746D01*
G01X1524532Y63205D02*
X1540378Y66570D01*
G01X1487197Y69902D02*
X1468121Y98520D01*
G01X1467042Y98065D02*
X1486367Y69072D01*
G01X1489186Y68576D02*
X1487197Y69902D01*
G01X1486367Y69072D02*
X1488731Y67497D01*
G01X1494077Y67536D02*
X1489186Y68576D01*
G01X1488731Y67497D02*
X1494077Y66360D01*
G01X1495689Y67879D02*
X1494077Y67536D01*
G01Y66360D02*
X1495689Y66703D01*
G01X1524403Y61783D02*
X1495689Y67879D01*
G01Y66703D02*
X1524403Y60607D01*
G01X1540396Y65181D02*
X1524403Y61783D01*
G01Y60607D02*
X1540396Y64005D01*
G01X1540231Y72900D02*
X1526903Y70224D01*
G01D02*
X1524249Y69690D01*
G01X1540225Y71725D02*
X1524242Y68515D01*
G01X1524249Y69690D02*
X1499635Y74918D01*
G01X1524242Y68515D02*
X1499167Y73841D01*
G01X1499635Y74918D02*
X1493240Y79388D01*
G01X1499167Y73841D02*
X1492656Y78393D01*
G01X1493240Y79388D02*
X1488765Y81558D01*
G01X1492656Y78393D02*
X1487981Y80659D01*
G01X1488765Y81558D02*
X1480783Y93527D01*
G01X1487981Y80659D02*
X1479719Y93048D01*
G01X1480783Y93527D02*
X1477634Y105510D01*
G01X1479719Y93048D02*
X1476452Y105482D01*
G01X1472914Y100701D02*
X1487171Y79350D01*
G01X1471830Y100252D02*
X1486388Y78451D01*
G01X1487171Y79350D02*
X1492170Y76927D01*
G01X1486388Y78451D02*
X1491586Y75932D01*
G01X1492170Y76927D02*
X1498392Y72574D01*
G01X1491586Y75932D02*
X1497924Y71497D01*
G01X1498392Y72574D02*
X1524720Y66986D01*
G01X1497924Y71497D02*
X1524722Y65809D01*
G01X1524720Y66986D02*
X1540362Y70310D01*
G01X1524722Y65809D02*
X1540363Y69134D01*
G01X1469501Y99079D02*
X1488167Y71071D01*
G01X1470580Y99534D02*
X1488997Y71901D01*
G01X1488167Y71071D02*
X1489753Y70014D01*
G01X1488997Y71901D02*
X1490208Y71094D01*
G01X1489753Y70014D02*
X1494097Y69092D01*
G01X1490208Y71094D02*
X1494097Y70268D01*
G01Y69092D02*
X1495454Y69380D01*
G01X1494097Y70268D02*
X1495454Y70556D01*
G01Y69380D02*
X1524532Y63205D01*
G01X1495454Y70556D02*
X1524530Y64382D01*
G01X1524532Y63205D02*
X1540378Y66570D01*
G01X1524530Y64382D02*
X1540378Y67746D01*
G01X1524403Y60607D02*
X1540396Y64005D01*
G01Y65181D02*
X1524403Y61783D01*
G01X1495689Y66703D02*
X1524403Y60607D01*
G01Y61783D02*
X1495689Y67879D01*
G01X1494077Y66360D02*
X1495689Y66703D01*
G01Y67879D02*
X1494077Y67536D01*
G01X1488731Y67497D02*
X1494077Y66360D01*
G01Y67536D02*
X1489186Y68576D01*
G01X1486367Y69072D02*
X1488731Y67497D01*
G01X1489186Y68576D02*
X1487197Y69902D01*
G01X1467042Y98065D02*
X1486367Y69072D01*
G01X1487197Y69902D02*
X1468121Y98520D01*
G01X1540225Y71725D02*
X1524242Y68515D01*
G01X1540231Y72900D02*
X1526903Y70224D01*
G01X1540225Y71725D02*
X1524242Y68515D01*
G01X1526903Y70224D02*
X1524249Y69690D01*
G01X1524242Y68515D02*
X1499167Y73841D01*
G01X1524249Y69690D02*
X1499635Y74918D01*
G01X1499167Y73841D02*
X1492656Y78393D01*
G01X1499635Y74918D02*
X1493240Y79388D01*
G01X1492656Y78393D02*
X1487981Y80659D01*
G01X1493240Y79388D02*
X1488765Y81558D01*
G01X1487981Y80659D02*
X1479719Y93048D01*
G01X1488765Y81558D02*
X1480783Y93527D01*
G01X1479719Y93048D02*
X1476452Y105482D01*
G01X1480783Y93527D02*
X1477634Y105510D01*
G01X1471830Y100252D02*
X1486388Y78451D01*
G01X1472914Y100701D02*
X1487171Y79350D01*
G01X1486388Y78451D02*
X1491586Y75932D01*
G01X1487171Y79350D02*
X1492170Y76927D01*
G01X1491586Y75932D02*
X1497924Y71497D01*
G01X1492170Y76927D02*
X1498392Y72574D01*
G01X1497924Y71497D02*
X1524722Y65809D01*
G01X1498392Y72574D02*
X1524720Y66986D01*
G01X1524722Y65809D02*
X1540363Y69134D01*
G01X1524720Y66986D02*
X1540362Y70310D01*
G01X1477634Y105510D02*
X1479063Y112237D01*
G01X1476452Y105482D02*
X1477884Y112225D01*
G01X1479063Y112237D02*
X1476388Y123649D01*
G01X1477884Y112225D02*
X1475208Y123648D01*
G01X1476388Y123649D02*
X1478093Y131091D01*
G01X1475208Y123648D02*
X1476855Y130841D01*
G01X1478093Y131091D02*
X1475436Y134789D01*
G01X1476855Y130841D02*
X1474624Y133948D01*
G01X1475436Y134789D02*
X1465578Y141360D01*
G01X1465526Y129186D02*
X1467815Y125752D01*
G01Y125753D02*
X1467941Y125563D01*
G01D02*
X1472914Y100701D01*
G01X1466858Y125114D02*
X1471830Y100252D01*
G01X1476452Y105482D02*
X1477884Y112225D01*
G01X1477634Y105510D02*
X1479063Y112237D01*
G01X1477884Y112225D02*
X1475208Y123648D01*
G01X1479063Y112237D02*
X1476388Y123649D01*
G01X1475208Y123648D02*
X1476855Y130841D01*
G01X1476388Y123649D02*
X1478093Y131091D01*
G01X1476855Y130841D02*
X1474624Y133948D01*
G01X1478093Y131091D02*
X1475436Y134789D01*
G01D02*
X1465578Y141360D01*
G01X1465526Y129186D02*
X1467815Y125752D01*
G01Y125753D02*
X1467941Y125563D01*
G01X1466858Y125114D02*
X1471830Y100252D01*
G01X1467941Y125563D02*
X1472914Y100701D01*
G01X1474000Y465273D02*
Y458500D01*
G01X1475150Y465750D02*
Y458977D01*
G01X1474000Y458500D02*
X1479000Y453500D01*
G01X1475150Y458977D02*
X1480150Y453977D01*
G01X1479000Y453500D02*
Y442942D01*
G01X1480150Y453977D02*
Y442942D01*
G01X1475150Y465750D02*
Y458977D01*
G01X1474000Y465273D02*
Y458500D01*
G01X1475150Y458977D02*
X1480150Y453977D01*
G01X1474000Y458500D02*
X1479000Y453500D01*
G01X1480150Y453977D02*
Y442942D01*
G01X1479000Y453500D02*
Y442942D01*
G01X1476969Y468099D02*
Y466469D01*
G01X1478119D02*
Y468576D01*
G01X1467529Y477539D02*
X1468484Y476584D01*
G01X1470358Y474710D02*
X1471312Y473756D01*
G01X1473186Y471882D02*
X1474141Y470927D01*
G01X1476014Y469054D02*
X1476969Y468099D01*
G01X1467529Y477539D02*
X1468484Y476584D01*
G01X1470358Y474710D02*
X1471312Y473756D01*
G01X1473186Y471882D02*
X1474141Y470927D01*
G01X1476014Y469054D02*
X1476969Y468099D01*
G01X1478119Y466469D02*
Y468576D01*
G01X1476969Y468099D02*
Y466469D01*
G01X1523811Y491617D02*
Y493222D01*
G01Y497172D02*
Y507007D01*
G01X1522661Y491617D02*
Y507006D01*
G01X1523812D02*
G02X1524539Y508761I2482J0D01*
G01X1522661Y507006D02*
G02X1523725Y509575I3633J0D01*
G01X1524603Y508826D02*
G03X1526053Y512331I-3516J3507D01*
G01X1523789Y509639D02*
G03X1524903Y512332I-2701J2694D01*
G01X1526053Y512331D02*
Y513803D01*
G01X1524903Y512332D02*
Y513803D01*
G01X1526053D02*
G02X1526418Y514682I1244J-1D01*
G01X1524903Y513803D02*
G02X1525604Y515496I2395J0D01*
G01X1526418Y514682D02*
X1527372Y515637D01*
G01X1525604Y515496D02*
X1536234Y526131D01*
G01X1520446Y499352D02*
Y508500D01*
G01X1519296Y499352D02*
Y508499D01*
G01X1520447D02*
G02X1521048Y509951I2055J0D01*
G01X1519296Y508499D02*
G02X1520234Y510765I3206J0D01*
G01X1521049Y509952D02*
G03X1522747Y514051I-4099J4099D01*
G01X1520235Y510766D02*
G03X1521597Y514051I-3284J3286D01*
G01X1522747D02*
Y515518D01*
G01X1521597Y514051D02*
Y515519D01*
G01X1522747Y515518D02*
G02X1523334Y516935I2004J0D01*
G01X1521597Y515519D02*
G02X1522520Y517749I3155J0D01*
G01X1523334Y516935D02*
X1524289Y517890D01*
G01X1527082Y520683D02*
X1528037Y521638D01*
G01X1522520Y517749D02*
X1534511Y529740D01*
G01X1524935Y524307D02*
X1523980Y523352D01*
G01X1521187Y520559D02*
X1520232Y519604D01*
G01X1532767Y533767D02*
X1519417Y520417D01*
G01X1521187Y520559D02*
X1520232Y519604D01*
G01X1519417Y520417D02*
X1519418D01*
G01X1520232Y519604D02*
G03X1519600Y518077I1530J-1527D01*
G01X1519418Y520417D02*
G03X1518450Y518078I2344J-2340D01*
G01X1519600Y518077D02*
Y514279D01*
G01X1518450Y518078D02*
Y514278D01*
G01X1519600Y514279D02*
G02X1518658Y512002I-3220J-1D01*
G01X1518449Y514279D02*
G02X1517844Y512816I-2069J-1D01*
G01X1518658Y512002D02*
X1517704Y511048D01*
G01X1517844Y512816D02*
X1516890Y511862D01*
G01X1517704Y511048D02*
G03X1517316Y510112I935J-936D01*
G01X1516890Y511862D02*
G03X1516166Y510112I1750J-1749D01*
G01X1517316D02*
Y498920D01*
G01X1516166Y510112D02*
Y498920D01*
G01X1509550Y493687D02*
Y489487D01*
G01X1508400D02*
Y493687D01*
G01X1509081Y494819D02*
G02X1509550Y493687I-1132J-1132D01*
G01X1508400D02*
G03X1508267Y494005I-450J-1D01*
G01X1506095Y497805D02*
X1509081Y494819D01*
G01X1508267Y494005D02*
X1505282Y496991D01*
G01X1505909Y498252D02*
G03X1506095Y497805I632J1D01*
G01X1505282Y496991D02*
G02X1504759Y498251I1260J1261D01*
G01X1505909Y502754D02*
Y498252D01*
G01X1504759Y498251D02*
Y502753D01*
G01X1506495Y504168D02*
G03X1505910Y502753I1416J-1414D01*
G01X1504759D02*
G02X1505681Y504982I3152J1D01*
G01X1506662Y504336D02*
X1506495Y504168D01*
G01X1505681Y504982D02*
X1505847Y505148D01*
G01X1507785Y504801D02*
G03X1506662Y504336I0J-1588D01*
G01X1505847Y505148D02*
G02X1507785Y505951I1937J-1935D01*
G01X1511966Y504801D02*
X1507785D01*
G01Y505951D02*
X1511966D01*
G01X1514216Y507051D02*
G02X1511966Y504801I-2250J0D01*
G01Y505951D02*
G03X1513066Y507051I0J1100D01*
G01X1514216Y513896D02*
Y507051D01*
G01X1513066D02*
Y513896D01*
G01X1514572Y514752D02*
G03X1514216Y513896I855J-857D01*
G01X1513066D02*
G02X1513758Y515566I2361J0D01*
G01X1515452Y515632D02*
X1514572Y514752D01*
G01X1513758Y515566D02*
X1514638Y516446D01*
G01X1516350Y517799D02*
G02X1515452Y515632I-3066J1D01*
G01X1514638Y516446D02*
G03X1515200Y517800I-1353J1355D01*
G01X1516350Y520265D02*
Y517799D01*
G01X1515200Y517800D02*
Y520266D01*
G01X1516482Y520583D02*
G03X1516350Y520265I318J-318D01*
G01X1515200Y520266D02*
G02X1515668Y521397I1601J0D01*
G01X1532110Y536211D02*
X1516482Y520583D01*
G01X1515668Y521397D02*
X1531296Y537025D01*
G01X1522661Y491617D02*
Y507006D01*
G01X1523811Y491617D02*
Y493222D01*
G01X1522661Y491617D02*
Y507006D01*
G01X1523811Y497172D02*
Y507007D01*
G01X1522661Y507006D02*
G02X1523725Y509575I3633J0D01*
G01X1523812Y507006D02*
G02X1524539Y508761I2482J0D01*
G01X1523789Y509639D02*
G03X1524903Y512332I-2701J2694D01*
G01X1524603Y508826D02*
G03X1526053Y512331I-3516J3507D01*
G01X1524903Y512332D02*
Y513803D01*
G01X1526053Y512331D02*
Y513803D01*
G01X1524903D02*
G02X1525604Y515496I2395J0D01*
G01X1526053Y513803D02*
G02X1526418Y514682I1244J-1D01*
G01X1525604Y515496D02*
X1536234Y526131D01*
G01X1526418Y514682D02*
X1527372Y515637D01*
G01X1525604Y515496D02*
X1536234Y526131D01*
G01X1525604Y515496D02*
X1536234Y526131D01*
G01X1519296Y499352D02*
Y508499D01*
G01X1520446Y499352D02*
Y508500D01*
G01X1519296Y508499D02*
G02X1520234Y510765I3206J0D01*
G01X1520447Y508499D02*
G02X1521048Y509951I2055J0D01*
G01X1520235Y510766D02*
G03X1521597Y514051I-3284J3286D01*
G01X1521049Y509952D02*
G03X1522747Y514051I-4099J4099D01*
G01X1521597D02*
Y515519D01*
G01X1522747Y514051D02*
Y515518D01*
G01X1521597Y515519D02*
G02X1522520Y517749I3155J0D01*
G01X1522747Y515518D02*
G02X1523334Y516935I2004J0D01*
G01X1522520Y517749D02*
X1534511Y529740D01*
G01X1523334Y516935D02*
X1524289Y517890D01*
G01X1522520Y517749D02*
X1534511Y529740D01*
G01X1527082Y520683D02*
X1528037Y521638D01*
G01X1522520Y517749D02*
X1534511Y529740D01*
G01X1522520Y517749D02*
X1534511Y529740D01*
G01X1532767Y533767D02*
X1519417Y520417D01*
G01X1532767Y533767D02*
X1519417Y520417D01*
G01X1532767Y533767D02*
X1519417Y520417D01*
G01X1524935Y524307D02*
X1523980Y523352D01*
G01X1532767Y533767D02*
X1519417Y520417D01*
G01D02*
X1519418D01*
G01X1521187Y520559D02*
X1520232Y519604D01*
G01X1519418Y520417D02*
G03X1518450Y518078I2344J-2340D01*
G01X1520232Y519604D02*
G03X1519600Y518077I1530J-1527D01*
G01X1518450Y518078D02*
Y514278D01*
G01X1519600Y518077D02*
Y514279D01*
G01X1518449D02*
G02X1517844Y512816I-2069J-1D01*
G01X1519600Y514279D02*
G02X1518658Y512002I-3220J-1D01*
G01X1517844Y512816D02*
X1516890Y511862D01*
G01X1518658Y512002D02*
X1517704Y511048D01*
G01X1516890Y511862D02*
G03X1516166Y510112I1750J-1749D01*
G01X1517704Y511048D02*
G03X1517316Y510112I935J-936D01*
G01X1516166D02*
Y498920D01*
G01X1517316Y510112D02*
Y498920D01*
G01X1515668Y521397D02*
X1531296Y537025D01*
G01X1532110Y536211D02*
X1516482Y520583D01*
G01X1515200Y520266D02*
G02X1515668Y521397I1601J0D01*
G01X1516482Y520583D02*
G03X1516350Y520265I318J-318D01*
G01X1515200Y517800D02*
Y520266D01*
G01X1516350Y520265D02*
Y517799D01*
G01X1514638Y516446D02*
G03X1515200Y517800I-1353J1355D01*
G01X1516350Y517799D02*
G02X1515452Y515632I-3066J1D01*
G01X1513758Y515566D02*
X1514638Y516446D01*
G01X1515452Y515632D02*
X1514572Y514752D01*
G01X1513066Y513896D02*
G02X1513758Y515566I2361J0D01*
G01X1514572Y514752D02*
G03X1514216Y513896I855J-857D01*
G01X1513066Y507051D02*
Y513896D01*
G01X1514216D02*
Y507051D01*
G01X1511966Y505951D02*
G03X1513066Y507051I0J1100D01*
G01X1514216D02*
G02X1511966Y504801I-2250J0D01*
G01X1507785Y505951D02*
X1511966D01*
G01Y504801D02*
X1507785D01*
G01X1505847Y505148D02*
G02X1507785Y505951I1937J-1935D01*
G01Y504801D02*
G03X1506662Y504336I0J-1588D01*
G01X1505681Y504982D02*
X1505847Y505148D01*
G01X1506662Y504336D02*
X1506495Y504168D01*
G01X1504759Y502753D02*
G02X1505681Y504982I3152J1D01*
G01X1506495Y504168D02*
G03X1505910Y502753I1416J-1414D01*
G01X1504759Y498251D02*
Y502753D01*
G01X1505909Y502754D02*
Y498252D01*
G01X1505282Y496991D02*
G02X1504759Y498251I1260J1261D01*
G01X1505909Y498252D02*
G03X1506095Y497805I632J1D01*
G01X1508267Y494005D02*
X1505282Y496991D01*
G01X1506095Y497805D02*
X1509081Y494819D01*
G01X1508400Y493687D02*
G03X1508267Y494005I-450J-1D01*
G01X1509081Y494819D02*
G02X1509550Y493687I-1132J-1132D01*
G01X1508400Y489487D02*
Y493687D01*
G01X1509550D02*
Y489487D01*
G01X1467544Y653566D02*
X1466066Y645191D01*
G01D02*
X1466431Y644669D01*
G01X1469034Y644181D02*
X1467732Y643271D01*
G01D02*
X1465761Y643618D01*
G01X1466431Y644669D02*
X1467463Y644487D01*
G01X1469034Y644181D02*
X1467732Y643271D01*
G01X1467463Y644487D02*
X1467984Y644851D01*
G01X1470703Y653637D02*
X1469034Y644181D01*
G01X1467984Y644851D02*
X1469653Y654307D01*
G01X1471146Y644923D02*
X1472623Y653299D01*
G01X1473839Y653568D02*
X1472362Y645191D01*
G01X1472056Y643618D02*
X1471146Y644923D01*
G01X1472362Y645191D02*
X1472726Y644669D01*
G01X1475333Y644186D02*
X1474030Y643272D01*
G01D02*
X1472056Y643618D01*
G01X1472726Y644669D02*
X1473759Y644488D01*
G01X1475333Y644186D02*
X1474030Y643272D01*
G01X1473759Y644488D02*
X1474282Y644855D01*
G01X1477001Y653655D02*
X1475333Y644186D01*
G01X1474282Y644855D02*
X1475951Y654325D01*
G01X1477420Y644808D02*
X1478920Y653315D01*
G01X1480136Y653586D02*
X1478636Y645078D01*
G01X1478332Y643507D02*
X1477420Y644808D01*
G01X1478636Y645078D02*
X1479001Y644557D01*
G01X1481609Y644074D02*
X1480306Y643158D01*
G01D02*
X1478332Y643507D01*
G01X1479001Y644557D02*
X1480035Y644374D01*
G01X1481609Y644074D02*
X1480306Y643158D01*
G01X1480035Y644374D02*
X1480558Y644742D01*
G01X1483299Y653655D02*
X1481609Y644074D01*
G01X1480558Y644742D02*
X1482249Y654324D01*
G01X1483717Y644805D02*
X1485217Y653316D01*
G01X1486433Y653585D02*
X1484933Y645076D01*
G01X1484632Y643505D02*
X1483717Y644805D01*
G01X1484933Y645076D02*
X1485299Y644556D01*
G01X1487904Y644069D02*
X1486601Y643160D01*
G01D02*
X1484632Y643505D01*
G01X1485299Y644556D02*
X1486332Y644375D01*
G01X1487904Y644069D02*
X1486601Y643160D01*
G01X1486332Y644375D02*
X1486854Y644739D01*
G01X1489587Y653621D02*
X1487904Y644069D01*
G01X1486854Y644739D02*
X1488536Y654291D01*
G01X1490017Y644827D02*
X1491508Y653283D01*
G01X1492724Y653552D02*
X1491233Y645096D01*
G01X1490929Y643523D02*
X1490017Y644827D01*
G01X1491233Y645096D02*
X1491598Y644574D01*
G01X1494204Y644088D02*
X1492901Y643178D01*
G01D02*
X1490929Y643523D01*
G01X1491598Y644574D02*
X1492631Y644393D01*
G01X1494204Y644088D02*
X1492901Y643178D01*
G01X1492631Y644393D02*
X1493153Y644758D01*
G01X1495882Y653622D02*
X1494204Y644088D01*
G01X1493153Y644758D02*
X1494832Y654292D01*
G01X1496312Y644831D02*
X1497804Y653284D01*
G01X1499020Y653553D02*
X1497528Y645099D01*
G01X1497221Y643526D02*
X1496312Y644831D01*
G01X1497528Y645099D02*
X1497892Y644576D01*
G01X1500499Y644092D02*
X1499195Y643178D01*
G01D02*
X1497221Y643526D01*
G01X1497892Y644576D02*
X1498925Y644394D01*
G01X1500499Y644092D02*
X1499195Y643178D01*
G01X1498925Y644394D02*
X1499448Y644761D01*
G01X1502183Y653642D02*
X1500499Y644092D01*
G01X1499448Y644761D02*
X1501133Y654311D01*
G01X1502619Y644892D02*
X1504103Y653298D01*
G01X1505319Y653568D02*
X1503835Y645161D01*
G01X1503530Y643588D02*
X1502619Y644892D01*
G01X1503835Y645161D02*
X1504200Y644639D01*
G01X1506806Y644153D02*
X1505504Y643241D01*
G01D02*
X1503530Y643588D01*
G01X1504200Y644639D02*
X1505234Y644457D01*
G01X1506806Y644153D02*
X1505504Y643241D01*
G01X1505234Y644457D02*
X1505756Y644822D01*
G01X1507217Y646490D02*
X1506806Y644153D01*
G01X1505756Y644822D02*
X1506091Y646732D01*
G01X1507525Y647702D02*
X1507217Y646490D01*
G01X1506091Y646732D02*
X1506466Y648209D01*
G01X1507882Y648178D02*
X1507525Y647702D01*
G01X1506466Y648209D02*
X1507043Y648978D01*
G01X1509198Y648709D02*
X1508561Y648739D01*
G01D02*
X1507882Y648178D01*
G01X1507043Y648978D02*
X1508171Y649909D01*
G01X1509198Y648709D02*
X1508561Y648739D01*
G01X1507043Y648978D02*
X1508171Y649909D01*
G01X1509198Y648709D02*
X1508561Y648739D01*
G01X1507043Y648978D02*
X1508171Y649909D01*
G01X1508561Y648739D02*
X1507882Y648178D01*
G01X1506466Y648209D02*
X1507043Y648978D01*
G01X1507882Y648178D02*
X1507525Y647702D01*
G01X1506091Y646732D02*
X1506466Y648209D01*
G01X1507525Y647702D02*
X1507217Y646490D01*
G01X1505756Y644822D02*
X1506091Y646732D01*
G01X1507217Y646490D02*
X1506806Y644153D01*
G01X1504200Y644639D02*
X1505234Y644457D01*
G01D02*
X1505756Y644822D01*
G01X1506806Y644153D02*
X1505504Y643241D01*
G01X1504200Y644639D02*
X1505234Y644457D01*
G01X1505504Y643241D02*
X1503530Y643588D01*
G01X1503835Y645161D02*
X1504200Y644639D01*
G01X1503530Y643588D02*
X1502619Y644892D01*
G01X1505319Y653568D02*
X1503835Y645161D01*
G01X1502619Y644892D02*
X1504103Y653298D01*
G01X1499448Y644761D02*
X1501133Y654311D01*
G01X1502183Y653642D02*
X1500499Y644092D01*
G01X1497892Y644576D02*
X1498925Y644394D01*
G01D02*
X1499448Y644761D01*
G01X1500499Y644092D02*
X1499195Y643178D01*
G01X1497892Y644576D02*
X1498925Y644394D01*
G01X1499195Y643178D02*
X1497221Y643526D01*
G01X1497528Y645099D02*
X1497892Y644576D01*
G01X1497221Y643526D02*
X1496312Y644831D01*
G01X1499020Y653553D02*
X1497528Y645099D01*
G01X1496312Y644831D02*
X1497804Y653284D01*
G01X1493153Y644758D02*
X1494832Y654292D01*
G01X1495882Y653622D02*
X1494204Y644088D01*
G01X1491598Y644574D02*
X1492631Y644393D01*
G01D02*
X1493153Y644758D01*
G01X1494204Y644088D02*
X1492901Y643178D01*
G01X1491598Y644574D02*
X1492631Y644393D01*
G01X1492901Y643178D02*
X1490929Y643523D01*
G01X1491233Y645096D02*
X1491598Y644574D01*
G01X1490929Y643523D02*
X1490017Y644827D01*
G01X1492724Y653552D02*
X1491233Y645096D01*
G01X1490017Y644827D02*
X1491508Y653283D01*
G01X1486854Y644739D02*
X1488536Y654291D01*
G01X1489587Y653621D02*
X1487904Y644069D01*
G01X1485299Y644556D02*
X1486332Y644375D01*
G01D02*
X1486854Y644739D01*
G01X1487904Y644069D02*
X1486601Y643160D01*
G01X1485299Y644556D02*
X1486332Y644375D01*
G01X1486601Y643160D02*
X1484632Y643505D01*
G01X1484933Y645076D02*
X1485299Y644556D01*
G01X1484632Y643505D02*
X1483717Y644805D01*
G01X1486433Y653585D02*
X1484933Y645076D01*
G01X1483717Y644805D02*
X1485217Y653316D01*
G01X1480558Y644742D02*
X1482249Y654324D01*
G01X1483299Y653655D02*
X1481609Y644074D01*
G01X1479001Y644557D02*
X1480035Y644374D01*
G01D02*
X1480558Y644742D01*
G01X1481609Y644074D02*
X1480306Y643158D01*
G01X1479001Y644557D02*
X1480035Y644374D01*
G01X1480306Y643158D02*
X1478332Y643507D01*
G01X1478636Y645078D02*
X1479001Y644557D01*
G01X1478332Y643507D02*
X1477420Y644808D01*
G01X1480136Y653586D02*
X1478636Y645078D01*
G01X1477420Y644808D02*
X1478920Y653315D01*
G01X1474282Y644855D02*
X1475951Y654325D01*
G01X1477001Y653655D02*
X1475333Y644186D01*
G01X1472726Y644669D02*
X1473759Y644488D01*
G01D02*
X1474282Y644855D01*
G01X1475333Y644186D02*
X1474030Y643272D01*
G01X1472726Y644669D02*
X1473759Y644488D01*
G01X1474030Y643272D02*
X1472056Y643618D01*
G01X1472362Y645191D02*
X1472726Y644669D01*
G01X1472056Y643618D02*
X1471146Y644923D01*
G01X1473839Y653568D02*
X1472362Y645191D01*
G01X1471146Y644923D02*
X1472623Y653299D01*
G01X1467984Y644851D02*
X1469653Y654307D01*
G01X1470703Y653637D02*
X1469034Y644181D01*
G01X1466431Y644669D02*
X1467463Y644487D01*
G01D02*
X1467984Y644851D01*
G01X1469034Y644181D02*
X1467732Y643271D01*
G01X1466431Y644669D02*
X1467463Y644487D01*
G01X1467732Y643271D02*
X1465761Y643618D01*
G01X1466066Y645191D02*
X1466431Y644669D01*
G01X1467544Y653566D02*
X1466066Y645191D01*
G01X1466328Y653297D02*
X1465963Y653819D01*
G01X1466633Y654870D02*
X1467544Y653566D01*
G01X1472259Y653820D02*
X1471225Y654001D01*
G01D02*
X1470703Y653637D01*
G01X1469653Y654307D02*
X1470956Y655216D01*
G01X1472259Y653820D02*
X1471225Y654001D01*
G01X1470956Y655216D02*
X1472929Y654871D01*
G01X1472623Y653299D02*
X1472259Y653820D01*
G01X1472929Y654871D02*
X1473839Y653568D01*
G01X1478557Y653837D02*
X1477523Y654020D01*
G01D02*
X1477001Y653655D01*
G01X1475951Y654325D02*
X1477254Y655235D01*
G01X1478557Y653837D02*
X1477523Y654020D01*
G01X1477254Y655235D02*
X1479227Y654887D01*
G01X1478920Y653315D02*
X1478557Y653837D01*
G01X1479227Y654887D02*
X1480136Y653586D01*
G01X1484853Y653837D02*
X1483819Y654019D01*
G01D02*
X1483299Y653655D01*
G01X1482249Y654324D02*
X1483549Y655235D01*
G01X1484853Y653837D02*
X1483819Y654019D01*
G01X1483549Y655235D02*
X1485523Y654888D01*
G01X1485217Y653316D02*
X1484853Y653837D01*
G01X1485523Y654888D02*
X1486433Y653585D01*
G01X1491144Y653804D02*
X1490110Y653986D01*
G01D02*
X1489587Y653621D01*
G01X1488536Y654291D02*
X1489840Y655201D01*
G01X1491144Y653804D02*
X1490110Y653986D01*
G01X1489840Y655201D02*
X1491814Y654855D01*
G01X1491508Y653283D02*
X1491144Y653804D01*
G01X1491814Y654855D02*
X1492724Y653552D01*
G01X1497440Y653805D02*
X1496405Y653987D01*
G01D02*
X1495882Y653622D01*
G01X1494832Y654292D02*
X1496136Y655202D01*
G01X1497440Y653805D02*
X1496405Y653987D01*
G01X1496136Y655202D02*
X1498110Y654856D01*
G01X1497804Y653284D02*
X1497440Y653805D01*
G01X1498110Y654856D02*
X1499020Y653553D01*
G01X1503736Y653822D02*
X1502702Y654005D01*
G01D02*
X1502183Y653642D01*
G01X1501133Y654311D02*
X1502433Y655221D01*
G01X1503736Y653822D02*
X1502702Y654005D01*
G01X1502433Y655221D02*
X1504406Y654872D01*
G01X1504103Y653298D02*
X1503736Y653822D01*
G01X1504406Y654872D02*
X1505319Y653568D01*
G01X1508171Y649909D02*
X1509291Y649857D01*
G01X1508171Y649909D02*
X1509291Y649857D01*
G01X1504406Y654872D02*
X1505319Y653568D01*
G01X1504103Y653298D02*
X1503736Y653822D01*
G01X1501133Y654311D02*
X1502433Y655221D01*
G01D02*
X1504406Y654872D01*
G01X1503736Y653822D02*
X1502702Y654005D01*
G01X1501133Y654311D02*
X1502433Y655221D01*
G01X1502702Y654005D02*
X1502183Y653642D01*
G01X1498110Y654856D02*
X1499020Y653553D01*
G01X1497804Y653284D02*
X1497440Y653805D01*
G01X1494832Y654292D02*
X1496136Y655202D01*
G01D02*
X1498110Y654856D01*
G01X1497440Y653805D02*
X1496405Y653987D01*
G01X1494832Y654292D02*
X1496136Y655202D01*
G01X1496405Y653987D02*
X1495882Y653622D01*
G01X1491814Y654855D02*
X1492724Y653552D01*
G01X1491508Y653283D02*
X1491144Y653804D01*
G01X1488536Y654291D02*
X1489840Y655201D01*
G01D02*
X1491814Y654855D01*
G01X1491144Y653804D02*
X1490110Y653986D01*
G01X1488536Y654291D02*
X1489840Y655201D01*
G01X1490110Y653986D02*
X1489587Y653621D01*
G01X1485523Y654888D02*
X1486433Y653585D01*
G01X1485217Y653316D02*
X1484853Y653837D01*
G01X1482249Y654324D02*
X1483549Y655235D01*
G01D02*
X1485523Y654888D01*
G01X1484853Y653837D02*
X1483819Y654019D01*
G01X1482249Y654324D02*
X1483549Y655235D01*
G01X1483819Y654019D02*
X1483299Y653655D01*
G01X1479227Y654887D02*
X1480136Y653586D01*
G01X1478920Y653315D02*
X1478557Y653837D01*
G01X1475951Y654325D02*
X1477254Y655235D01*
G01D02*
X1479227Y654887D01*
G01X1478557Y653837D02*
X1477523Y654020D01*
G01X1475951Y654325D02*
X1477254Y655235D01*
G01X1477523Y654020D02*
X1477001Y653655D01*
G01X1472929Y654871D02*
X1473839Y653568D01*
G01X1472623Y653299D02*
X1472259Y653820D01*
G01X1469653Y654307D02*
X1470956Y655216D01*
G01D02*
X1472929Y654871D01*
G01X1472259Y653820D02*
X1471225Y654001D01*
G01X1469653Y654307D02*
X1470956Y655216D01*
G01X1471225Y654001D02*
X1470703Y653637D01*
G01X1466633Y654870D02*
X1467544Y653566D01*
G01X1466328Y653297D02*
X1465963Y653819D01*
G01X1539862Y29313D02*
X1542987Y29976D01*
G01X1539862Y28137D02*
X1542987Y28800D01*
G01Y29976D02*
X1547322Y29056D01*
G01X1549914Y28506D02*
X1551235Y28226D01*
G01X1553827Y27675D02*
X1559178Y26540D01*
G01X1542987Y28800D02*
X1558856Y25432D01*
G01X1559178Y26540D02*
X1589806Y15110D01*
G01X1558856Y25432D02*
X1589713Y13917D01*
G01X1587550Y7045D02*
X1586226Y7309D01*
G01X1583627Y7829D02*
X1573632Y9825D01*
G01X1591959Y4991D02*
X1573632Y8652D01*
G01Y9825D02*
X1568396Y8779D01*
G01X1573632Y8652D02*
X1568396Y7606D01*
G01Y8779D02*
X1562050Y10050D01*
G01X1568396Y7606D02*
X1562050Y8877D01*
G01Y10050D02*
X1553552Y8352D01*
G01X1562050Y8877D02*
X1553552Y7179D01*
G01Y8352D02*
X1547154Y9630D01*
G01X1553552Y7179D02*
X1547154Y8457D01*
G01Y9630D02*
X1538568Y7913D01*
G01X1547154Y8457D02*
X1538568Y6740D01*
G01X1539862Y28137D02*
X1542987Y28800D01*
G01X1539862Y29313D02*
X1542987Y29976D01*
G01Y28800D02*
X1558856Y25432D01*
G01X1542987Y29976D02*
X1547322Y29056D01*
G01X1542987Y28800D02*
X1558856Y25432D01*
G01X1549914Y28506D02*
X1551235Y28226D01*
G01X1542987Y28800D02*
X1558856Y25432D01*
G01X1553827Y27675D02*
X1559178Y26540D01*
G01X1558856Y25432D02*
X1589713Y13917D01*
G01X1559178Y26540D02*
X1589806Y15110D01*
G01X1591959Y4991D02*
X1573632Y8652D01*
G01X1591959Y4991D02*
X1573632Y8652D01*
G01X1587550Y7045D02*
X1586226Y7309D01*
G01X1591959Y4991D02*
X1573632Y8652D01*
G01X1583627Y7829D02*
X1573632Y9825D01*
G01Y8652D02*
X1568396Y7606D01*
G01X1573632Y9825D02*
X1568396Y8779D01*
G01Y7606D02*
X1562050Y8877D01*
G01X1568396Y8779D02*
X1562050Y10050D01*
G01Y8877D02*
X1553552Y7179D01*
G01X1562050Y10050D02*
X1553552Y8352D01*
G01Y7179D02*
X1547154Y8457D01*
G01X1553552Y8352D02*
X1547154Y9630D01*
G01Y8457D02*
X1538568Y6740D01*
G01X1547154Y9630D02*
X1538568Y7913D01*
G01X1571114Y34928D02*
X1582764Y30580D01*
G01X1570363Y33980D02*
X1582675Y29385D01*
G01X1582764Y30580D02*
X1590497Y32220D01*
G01X1582675Y29385D02*
X1590497Y31044D01*
G01X1568638Y31926D02*
X1569903Y31454D01*
G01X1572386Y30527D02*
X1573651Y30055D01*
G01X1576133Y29128D02*
X1577398Y28656D01*
G01X1579880Y27729D02*
X1581145Y27257D01*
G01X1561000Y33548D02*
X1581056Y26062D01*
G01X1581145Y27257D02*
X1591317Y29413D01*
G01X1581056Y26062D02*
X1591317Y28237D01*
G01X1555451Y34122D02*
X1591365Y20719D01*
G01X1555128Y33014D02*
X1591272Y19526D01*
G01X1538848Y32183D02*
X1543325Y33135D01*
G01X1538848Y31007D02*
X1543325Y31959D01*
G01Y33135D02*
X1555928Y30458D01*
G01X1543325Y31959D02*
X1555575Y29357D01*
G01X1543325Y33135D02*
X1555928Y30458D01*
G01X1555575Y29356D02*
X1555588Y29353D01*
G01X1543325Y33135D02*
X1555928Y30458D01*
G01D02*
X1589865Y17786D01*
G01X1555588Y29353D02*
X1555605Y29350D01*
G01X1555928Y30458D02*
X1589865Y17786D01*
G01X1555605Y29350D02*
X1589772Y16593D01*
G01X1579498Y34328D02*
X1584460Y32482D01*
G01D02*
X1590221Y33702D01*
G01X1570363Y33980D02*
X1582675Y29385D01*
G01X1571114Y34928D02*
X1582764Y30580D01*
G01X1582675Y29385D02*
X1590497Y31044D01*
G01X1582764Y30580D02*
X1590497Y32220D01*
G01X1561000Y33548D02*
X1581056Y26062D01*
G01X1561000Y33548D02*
X1581056Y26062D01*
G01X1561000Y33548D02*
X1581056Y26062D01*
G01X1568638Y31926D02*
X1569903Y31454D01*
G01X1561000Y33548D02*
X1581056Y26062D01*
G01X1572386Y30527D02*
X1573651Y30055D01*
G01X1561000Y33548D02*
X1581056Y26062D01*
G01X1576133Y29128D02*
X1577398Y28656D01*
G01X1561000Y33548D02*
X1581056Y26062D01*
G01X1579880Y27729D02*
X1581145Y27257D01*
G01X1581056Y26062D02*
X1591317Y28237D01*
G01X1581145Y27257D02*
X1591317Y29413D01*
G01X1555128Y33014D02*
X1591272Y19526D01*
G01X1555451Y34122D02*
X1591365Y20719D01*
G01X1538848Y31007D02*
X1543325Y31959D01*
G01X1538848Y32183D02*
X1543325Y33135D01*
G01Y31959D02*
X1555575Y29357D01*
G01Y29356D02*
X1555588Y29353D01*
G01D02*
X1555605Y29350D01*
G01X1543325Y33135D02*
X1555928Y30458D01*
G01X1555588Y29353D02*
X1555605Y29350D01*
G01D02*
X1589772Y16593D01*
G01X1555928Y30458D02*
X1589865Y17786D01*
G01X1579498Y34328D02*
X1584460Y32482D01*
G01D02*
X1590221Y33702D01*
G01X1542092Y46078D02*
X1567245Y40734D01*
G01X1542092Y44902D02*
X1566548Y39706D01*
G01X1567245Y40734D02*
X1571114Y34928D01*
G01X1566548Y39706D02*
X1570363Y33980D01*
G01X1542150Y43423D02*
X1548500Y42073D01*
G01X1542150Y42247D02*
X1547795Y41047D01*
G01X1548500Y42073D02*
X1549365Y40742D01*
G01X1547795Y41047D02*
X1548140Y40515D01*
G01X1549365Y40742D02*
X1548934Y38718D01*
G01X1548140Y40515D02*
X1547709Y38490D01*
G01X1548934Y38718D02*
X1549281Y38185D01*
G01X1547709Y38490D02*
X1548576Y37159D01*
G01X1549281Y38185D02*
X1550309Y37965D01*
G01X1548576Y37159D02*
X1550536Y36740D01*
G01X1550309Y37965D02*
X1550842Y38312D01*
G01X1550536Y36740D02*
X1551869Y37607D01*
G01X1550842Y38312D02*
X1551273Y40336D01*
G01X1551869Y37607D02*
X1552299Y39631D01*
G01X1551273Y40336D02*
X1552604Y41201D01*
G01X1552299Y39631D02*
X1552831Y39976D01*
G01X1552604Y41201D02*
X1557009Y40264D01*
G01X1552831Y39976D02*
X1556373Y39223D01*
G01X1557009Y40264D02*
X1561695Y34517D01*
G01X1556373Y39223D02*
X1561000Y33548D01*
G01X1561695Y34517D02*
X1565192Y33212D01*
G01D02*
X1566155Y32852D01*
G01X1533167Y35990D02*
X1534487Y35710D01*
G01X1537079Y35159D02*
X1538400Y34879D01*
G01D02*
X1545142Y36312D01*
G01X1538400Y33703D02*
X1545142Y35136D01*
G01Y36312D02*
X1555451Y34122D01*
G01X1545142Y35136D02*
X1555128Y33014D01*
G01X1542298Y48753D02*
X1576052Y41573D01*
G01X1542298Y47577D02*
X1575354Y40545D01*
G01X1576052Y41573D02*
X1580249Y35277D01*
G01X1575354Y40545D02*
X1579498Y34328D01*
G01X1580249Y35277D02*
X1584548Y33677D01*
G01D02*
X1590220Y34878D01*
G01X1542092Y44902D02*
X1566548Y39706D01*
G01X1542092Y46078D02*
X1567245Y40734D01*
G01X1566548Y39706D02*
X1570363Y33980D01*
G01X1567245Y40734D02*
X1571114Y34928D01*
G01X1542150Y42247D02*
X1547795Y41047D01*
G01X1542150Y43423D02*
X1548500Y42073D01*
G01X1547795Y41047D02*
X1548140Y40515D01*
G01X1548500Y42073D02*
X1549365Y40742D01*
G01X1548140Y40515D02*
X1547709Y38490D01*
G01X1549365Y40742D02*
X1548934Y38718D01*
G01X1547709Y38490D02*
X1548576Y37159D01*
G01X1548934Y38718D02*
X1549281Y38185D01*
G01X1548576Y37159D02*
X1550536Y36740D01*
G01X1549281Y38185D02*
X1550309Y37965D01*
G01X1550536Y36740D02*
X1551869Y37607D01*
G01X1550309Y37965D02*
X1550842Y38312D01*
G01X1551869Y37607D02*
X1552299Y39631D01*
G01X1550842Y38312D02*
X1551273Y40336D01*
G01X1552299Y39631D02*
X1552831Y39976D01*
G01X1551273Y40336D02*
X1552604Y41201D01*
G01X1552831Y39976D02*
X1556373Y39223D01*
G01X1552604Y41201D02*
X1557009Y40264D01*
G01X1556373Y39223D02*
X1561000Y33548D01*
G01X1557009Y40264D02*
X1561695Y34517D01*
G01D02*
X1565192Y33212D01*
G01D02*
X1566155Y32852D01*
G01X1533167Y35990D02*
X1534487Y35710D01*
G01X1537079Y35159D02*
X1538400Y34879D01*
G01Y33703D02*
X1545142Y35136D01*
G01X1538400Y34879D02*
X1545142Y36312D01*
G01Y35136D02*
X1555128Y33014D01*
G01X1545142Y36312D02*
X1555451Y34122D01*
G01X1542298Y47577D02*
X1575354Y40545D01*
G01X1542298Y48753D02*
X1576052Y41573D01*
G01X1575354Y40545D02*
X1579498Y34328D01*
G01X1576052Y41573D02*
X1580249Y35277D01*
G01D02*
X1584548Y33677D01*
G01D02*
X1590220Y34878D01*
G01X1542164Y51389D02*
X1533709Y49592D01*
G01D02*
X1533708D01*
G01X1579375Y43474D02*
X1542164Y51389D01*
G01Y50213D02*
X1578668Y42448D01*
G01X1580238Y42139D02*
X1579375Y43474D01*
G01X1578668Y42448D02*
X1579013Y41914D01*
G01X1579884Y40486D02*
X1580238Y42139D01*
G01X1579013Y41914D02*
X1578659Y40259D01*
G01X1580230Y39954D02*
X1579884Y40486D01*
G01X1578659Y40259D02*
X1579524Y38928D01*
G01X1581261Y39734D02*
X1580230Y39954D01*
G01X1579524Y38928D02*
X1581488Y38509D01*
G01X1581794Y40080D02*
X1581793D01*
G01D02*
X1581261Y39734D01*
G01X1581488Y38509D02*
X1582819Y39374D01*
G01X1582095Y41490D02*
X1581794Y40080D01*
G01X1582819Y39374D02*
X1583121Y40785D01*
G01X1583320Y42288D02*
X1582095Y41490D01*
G01X1583121Y40785D02*
X1583949Y41325D01*
G01X1585683Y42131D02*
X1584218Y42444D01*
G01X1583320Y42288D02*
X1582095Y41490D01*
G01X1583949Y41325D02*
X1583971Y41321D01*
G01X1585683Y42131D02*
X1584218Y42444D01*
G01X1583971Y41321D02*
X1583978Y41320D01*
G01X1585683Y42131D02*
X1584218Y42444D01*
G01X1583978Y41320D02*
X1584977Y41105D01*
G01X1586931Y40213D02*
X1585683Y42131D01*
G01X1584977Y41105D02*
X1585706Y39986D01*
G01X1586413Y37794D02*
X1586931Y40213D01*
G01X1585706Y39986D02*
X1585188Y37567D01*
G01X1586759Y37262D02*
X1586413Y37794D01*
G01X1585188Y37567D02*
X1586053Y36236D01*
G01X1587790Y37042D02*
X1586759Y37262D01*
G01X1586053Y36236D02*
X1588017Y35817D01*
G01X1588323Y37388D02*
X1588322D01*
G01D02*
X1587790Y37042D01*
G01X1588017Y35817D02*
X1589348Y36682D01*
G01X1588944Y40290D02*
X1588323Y37388D01*
G01X1588944Y40290D02*
X1588323Y37388D01*
G01X1588017Y35817D02*
X1589348Y36682D01*
G01X1588323Y37388D02*
X1588322D01*
G01X1588017Y35817D02*
X1589348Y36682D01*
G01X1588322Y37388D02*
X1587790Y37042D01*
G01X1586053Y36236D02*
X1588017Y35817D01*
G01X1587790Y37042D02*
X1586759Y37262D01*
G01X1585188Y37567D02*
X1586053Y36236D01*
G01X1586759Y37262D02*
X1586413Y37794D01*
G01X1585706Y39986D02*
X1585188Y37567D01*
G01X1586413Y37794D02*
X1586931Y40213D01*
G01X1584977Y41105D02*
X1585706Y39986D01*
G01X1586931Y40213D02*
X1585683Y42131D01*
G01X1583949Y41325D02*
X1583971Y41321D01*
G01D02*
X1583978Y41320D01*
G01D02*
X1584977Y41105D01*
G01X1585683Y42131D02*
X1584218Y42444D01*
G01X1583121Y40785D02*
X1583949Y41325D01*
G01D02*
X1583971Y41321D01*
G01X1583320Y42288D02*
X1582095Y41490D01*
G01X1582819Y39374D02*
X1583121Y40785D01*
G01X1582095Y41490D02*
X1581794Y40080D01*
G01X1581488Y38509D02*
X1582819Y39374D01*
G01X1581794Y40080D02*
X1581793D01*
G01X1581488Y38509D02*
X1582819Y39374D01*
G01X1581793Y40080D02*
X1581261Y39734D01*
G01X1579524Y38928D02*
X1581488Y38509D01*
G01X1581261Y39734D02*
X1580230Y39954D01*
G01X1578659Y40259D02*
X1579524Y38928D01*
G01X1580230Y39954D02*
X1579884Y40486D01*
G01X1579013Y41914D02*
X1578659Y40259D01*
G01X1579884Y40486D02*
X1580238Y42139D01*
G01X1578668Y42448D02*
X1579013Y41914D01*
G01X1580238Y42139D02*
X1579375Y43474D01*
G01X1542164Y50213D02*
X1578668Y42448D01*
G01X1579375Y43474D02*
X1542164Y51389D01*
G01D02*
X1533709Y49592D01*
G01D02*
X1533708D01*
G01X1607171Y40748D02*
X1542055Y54589D01*
G01Y53413D02*
X1607171Y39572D01*
G01X1542055Y53413D02*
X1607171Y39572D01*
G01Y40748D02*
X1542055Y54589D01*
G01X1540703Y62556D02*
X1606137Y48647D01*
G01Y47471D02*
X1540703Y61380D01*
G01X1541280Y59871D02*
X1606367Y46037D01*
G01X1541280Y58695D02*
X1606363Y44860D01*
G01X1541420Y57281D02*
X1606640Y43418D01*
G01X1541420Y56105D02*
X1606640Y42242D01*
G01X1606137Y47471D02*
X1540703Y61380D01*
G01Y62556D02*
X1606137Y48647D01*
G01X1541280Y58695D02*
X1606363Y44860D01*
G01X1541280Y59871D02*
X1606367Y46037D01*
G01X1541420Y56105D02*
X1606640Y42242D01*
G01X1541420Y57281D02*
X1606640Y43418D01*
G01X1540378Y67746D02*
X1605694Y53864D01*
G01X1540378Y66570D02*
X1605694Y52688D01*
G01X1605868Y51265D02*
X1574306Y57974D01*
G01D02*
X1540396Y65181D01*
G01Y64005D02*
X1605868Y50089D01*
G01X1596596Y65305D02*
X1586049Y63161D01*
G01X1596596Y64131D02*
X1586044Y61986D01*
G01X1586049Y63161D02*
X1540231Y72900D01*
G01X1586044Y61986D02*
X1540225Y71725D01*
G01X1540362Y70310D02*
X1605549Y56453D01*
G01X1540363Y69134D02*
X1605549Y55277D01*
G01X1540378Y66570D02*
X1605694Y52688D01*
G01X1540378Y67746D02*
X1605694Y53864D01*
G01X1540396Y64005D02*
X1605868Y50089D01*
G01Y51265D02*
X1574306Y57974D01*
G01X1540396Y64005D02*
X1605868Y50089D01*
G01X1574306Y57974D02*
X1540396Y65181D01*
G01X1596596Y64131D02*
X1586044Y61986D01*
G01X1596596Y65305D02*
X1586049Y63161D01*
G01X1586044Y61986D02*
X1540225Y71725D01*
G01X1586049Y63161D02*
X1540231Y72900D01*
G01X1540363Y69134D02*
X1605549Y55277D01*
G01X1540362Y70310D02*
X1605549Y56453D01*
G01X1530165Y518431D02*
X1531119Y519386D01*
G01X1533912Y522179D02*
X1537048Y525317D01*
G01D02*
G02X1537366Y525450I319J-317D01*
G01X1536234Y526131D02*
G02X1537366Y526600I1132J-1132D01*
G01Y525450D02*
X1565063D01*
G01D02*
G02X1584470Y517411I0J-27445D01*
G01X1565063Y526600D02*
G02X1585284Y518225I1J-28595D01*
G01X1584470Y517411D02*
X1586222Y515659D01*
G01X1585284Y518225D02*
X1587036Y516473D01*
G01X1586222Y515659D02*
G03X1589004Y514507I2782J2783D01*
G01X1587036Y516473D02*
G03X1589004Y515658I1968J1969D01*
G01X1530830Y524431D02*
X1531785Y525386D01*
G01X1563389Y529300D02*
G02X1586766Y519616I-1J-33061D01*
G01X1563389Y530450D02*
G02X1587580Y520430I0J-34212D01*
G01X1586766Y519616D02*
X1587928Y518454D01*
G01X1587580Y520430D02*
X1588742Y519268D01*
G01X1587928Y518454D02*
G03X1589422Y517836I1494J1496D01*
G01X1588742Y519268D02*
G03X1589423Y518986I681J682D01*
G01X1589115Y521685D02*
X1587941Y522859D01*
G01X1589115Y521685D02*
X1587941Y522859D01*
G01Y522860D02*
X1587631Y523169D01*
G01X1589091Y523337D02*
X1588445Y523983D01*
G01X1587631Y523169D02*
G03X1563692Y533086I-23940J-23939D01*
G01X1588445Y523983D02*
G03X1563692Y534236I-24753J-24753D01*
G01X1528450Y499300D02*
Y510164D01*
G01X1529600Y499300D02*
Y510164D01*
G01X1528450D02*
G02X1529671Y513115I4173J1D01*
G01X1529600Y510164D02*
G02X1530485Y512301I3023J0D01*
G01X1529671Y513115D02*
X1538860Y522304D01*
G01X1530485Y512301D02*
X1532178Y513994D01*
G01X1529671Y513115D02*
X1538860Y522304D01*
G01X1534971Y516787D02*
X1535926Y517742D01*
G01X1529671Y513115D02*
X1538860Y522304D01*
G01X1538719Y520535D02*
X1539674Y521490D01*
G01X1538860Y522304D02*
G02X1539993Y522772I1132J-1134D01*
G01X1539674Y521490D02*
G02X1539993Y521622I319J-319D01*
G01Y522772D02*
X1565010D01*
G01X1539993Y521622D02*
X1565010D01*
G01Y522772D02*
G02X1582913Y515357I1J-25317D01*
G01X1565010Y521622D02*
G02X1582099Y514543I0J-24166D01*
G01X1582913Y515357D02*
X1586037Y512233D01*
G01X1582099Y514543D02*
X1585223Y511419D01*
G01X1586037Y512233D02*
G03X1587134Y511778I1098J1097D01*
G01X1585223Y511419D02*
G03X1587133Y510628I1910J1912D01*
G01X1587134Y511778D02*
X1602086D01*
G01X1587133Y510628D02*
X1602086D01*
G01X1530165Y518431D02*
X1531119Y519386D01*
G01X1533912Y522179D02*
X1537048Y525317D01*
G01X1536234Y526131D02*
G02X1537366Y526600I1132J-1132D01*
G01X1537048Y525317D02*
G02X1537366Y525450I319J-317D01*
G01D02*
X1565063D01*
G01Y526600D02*
G02X1585284Y518225I1J-28595D01*
G01X1565063Y525450D02*
G02X1584470Y517411I0J-27445D01*
G01X1585284Y518225D02*
X1587036Y516473D01*
G01X1584470Y517411D02*
X1586222Y515659D01*
G01X1587036Y516473D02*
G03X1589004Y515658I1968J1969D01*
G01X1586222Y515659D02*
G03X1589004Y514507I2782J2783D01*
G01X1530830Y524431D02*
X1531785Y525386D01*
G01X1563389Y530450D02*
G02X1587580Y520430I0J-34212D01*
G01X1563389Y529300D02*
G02X1586766Y519616I-1J-33061D01*
G01X1587580Y520430D02*
X1588742Y519268D01*
G01X1586766Y519616D02*
X1587928Y518454D01*
G01X1588742Y519268D02*
G03X1589423Y518986I681J682D01*
G01X1587928Y518454D02*
G03X1589422Y517836I1494J1496D01*
G01X1589091Y523337D02*
X1588445Y523983D01*
G01X1589115Y521685D02*
X1587941Y522859D01*
G01X1589091Y523337D02*
X1588445Y523983D01*
G01X1587941Y522860D02*
X1587631Y523169D01*
G01X1588445Y523983D02*
G03X1563692Y534236I-24753J-24753D01*
G01X1587631Y523169D02*
G03X1563692Y533086I-23940J-23939D01*
G01X1589280Y475417D02*
X1584991Y474426D01*
G01X1589318Y476607D02*
X1584544Y475504D01*
G01X1584991Y474426D02*
X1582024Y472572D01*
G01X1584544Y475504D02*
X1581414Y473547D01*
G01X1589318Y476607D02*
X1584544Y475504D01*
G01X1589280Y475417D02*
X1584991Y474426D01*
G01X1584544Y475504D02*
X1581414Y473547D01*
G01X1584991Y474426D02*
X1582024Y472572D01*
G01X1585643Y501592D02*
X1584292D01*
G01X1628238Y500442D02*
X1584291D01*
G01X1584292Y501592D02*
G02X1582509Y502331I1J2522D01*
G01X1584291Y500442D02*
G02X1581695Y501517I0J3673D01*
G01X1582509Y502331D02*
X1576605Y508235D01*
G01X1581695Y501517D02*
X1575791Y507421D01*
G01X1576605Y508235D02*
G03X1566549Y512400I-10055J-10054D01*
G01X1575791Y507421D02*
G03X1566550Y511250I-9242J-9239D01*
G01X1566549Y512400D02*
X1566143D01*
G01X1566550Y511250D02*
X1566143D01*
G01Y512400D02*
G03X1562187Y510763I-2J-5593D01*
G01X1566143Y511250D02*
G03X1563001Y509949I-1J-4442D01*
G01X1562187Y510763D02*
X1558070Y506644D01*
G01X1563001Y509949D02*
X1559913Y506860D01*
G01X1562187Y510763D02*
X1558070Y506644D01*
G01X1559913Y506860D02*
X1558884Y505830D01*
G01X1558070Y506644D02*
G03X1557250Y504662I1985J-1982D01*
G01X1558884Y505830D02*
G03X1558400Y504661I1171J-1169D01*
G01X1557250Y504662D02*
Y497439D01*
G01X1558400Y504661D02*
Y497438D01*
G01X1557250Y497439D02*
G02X1557118Y497121I-450J0D01*
G01X1558400Y497438D02*
G02X1557932Y496307I-1601J0D01*
G01X1557118Y497121D02*
X1556786Y496789D01*
G01X1557932Y496307D02*
X1557600Y495975D01*
G01X1616603Y507300D02*
X1585587D01*
G01X1616603Y508450D02*
X1585587D01*
G01Y507300D02*
G02X1584454Y507768I-1J1602D01*
G01X1585587Y508450D02*
G02X1585268Y508582I0J451D01*
G01X1584454Y507768D02*
X1580419Y511803D01*
G01X1585268Y508582D02*
X1581233Y512617D01*
G01X1580419Y511803D02*
G03X1564306Y518478I-16113J-16110D01*
G01X1581233Y512617D02*
G03X1564306Y519628I-16926J-16925D01*
G01Y518478D02*
X1550140D01*
G01X1546190D02*
X1544840D01*
G01X1564306Y519628D02*
X1544839D01*
G01X1544840Y518478D02*
G03X1543413Y517886I1J-2018D01*
G01X1544839Y519628D02*
G03X1542599Y518700I0J-3168D01*
G01X1543413Y517886D02*
X1539476Y513949D01*
G01X1542599Y518700D02*
X1538662Y514763D01*
G01X1539476Y513949D02*
G03X1539150Y513165I783J-785D01*
G01X1538662Y514763D02*
G03X1538000Y513165I1598J-1598D01*
G01X1539150D02*
Y503600D01*
G01X1538000Y513165D02*
Y503600D01*
G01X1529600Y499300D02*
Y510164D01*
G01X1528450Y499300D02*
Y510164D01*
G01X1529600D02*
G02X1530485Y512301I3023J0D01*
G01X1528450Y510164D02*
G02X1529671Y513115I4173J1D01*
G01X1530485Y512301D02*
X1532178Y513994D01*
G01X1534971Y516787D02*
X1535926Y517742D01*
G01X1538719Y520535D02*
X1539674Y521490D01*
G01X1529671Y513115D02*
X1538860Y522304D01*
G01X1539674Y521490D02*
G02X1539993Y521622I319J-319D01*
G01X1538860Y522304D02*
G02X1539993Y522772I1132J-1134D01*
G01Y521622D02*
X1565010D01*
G01X1539993Y522772D02*
X1565010D01*
G01Y521622D02*
G02X1582099Y514543I0J-24166D01*
G01X1565010Y522772D02*
G02X1582913Y515357I1J-25317D01*
G01X1582099Y514543D02*
X1585223Y511419D01*
G01X1582913Y515357D02*
X1586037Y512233D01*
G01X1585223Y511419D02*
G03X1587133Y510628I1910J1912D01*
G01X1586037Y512233D02*
G03X1587134Y511778I1098J1097D01*
G01X1587133Y510628D02*
X1602086D01*
G01X1587134Y511778D02*
X1602086D01*
G01X1621018Y505350D02*
X1584170D01*
G01X1621018Y504200D02*
X1584169D01*
G01X1584170Y505350D02*
G02X1583707Y505542I1J657D01*
G01X1584169Y504200D02*
G02X1582893Y504728I1J1807D01*
G01X1583707Y505542D02*
X1578979Y510270D01*
G01X1582893Y504728D02*
X1578165Y509456D01*
G01X1578979Y510270D02*
G03X1564109Y516429I-14869J-14868D01*
G01X1578165Y509456D02*
G03X1564110Y515279I-14056J-14053D01*
G01X1564109Y516429D02*
X1554091D01*
G01X1564110Y515279D02*
X1554090D01*
G01X1554091Y516429D02*
G03X1552959Y515960I0J-1600D01*
G01X1554090Y515279D02*
G03X1553773Y515146I2J-450D01*
G01X1552959Y515960D02*
X1550821Y513822D01*
G01X1553773Y515146D02*
X1551635Y513008D01*
G01X1550821Y513822D02*
G03X1550352Y512690I1131J-1132D01*
G01X1551635Y513008D02*
G03X1551503Y512690I317J-318D01*
G01X1550352D02*
Y501192D01*
G01X1551502Y512691D02*
Y501192D01*
G01X1628238Y500442D02*
X1584291D01*
G01X1628238D02*
X1584291D01*
G01X1628238D02*
X1584291D01*
G01X1628238D02*
X1584291D01*
G01X1628238D02*
X1584291D01*
G01X1628238D02*
X1584291D01*
G01X1628238D02*
X1584291D01*
G01X1628238D02*
X1584291D01*
G01X1585643Y501592D02*
X1584292D01*
G01X1584291Y500442D02*
G02X1581695Y501517I0J3673D01*
G01X1584292Y501592D02*
G02X1582509Y502331I1J2522D01*
G01X1581695Y501517D02*
X1575791Y507421D01*
G01X1582509Y502331D02*
X1576605Y508235D01*
G01X1575791Y507421D02*
G03X1566550Y511250I-9242J-9239D01*
G01X1576605Y508235D02*
G03X1566549Y512400I-10055J-10054D01*
G01X1566550Y511250D02*
X1566143D01*
G01X1566549Y512400D02*
X1566143D01*
G01Y511250D02*
G03X1563001Y509949I-1J-4442D01*
G01X1566143Y512400D02*
G03X1562187Y510763I-2J-5593D01*
G01X1563001Y509949D02*
X1559913Y506860D01*
G01D02*
X1558884Y505830D01*
G01X1562187Y510763D02*
X1558070Y506644D01*
G01X1558884Y505830D02*
G03X1558400Y504661I1171J-1169D01*
G01X1558070Y506644D02*
G03X1557250Y504662I1985J-1982D01*
G01X1558400Y504661D02*
Y497438D01*
G01X1557250Y504662D02*
Y497439D01*
G01X1558400Y497438D02*
G02X1557932Y496307I-1601J0D01*
G01X1557250Y497439D02*
G02X1557118Y497121I-450J0D01*
G01X1557932Y496307D02*
X1557600Y495975D01*
G01X1557118Y497121D02*
X1556786Y496789D01*
G01X1616603Y508450D02*
X1585587D01*
G01X1616603Y507300D02*
X1585587D01*
G01Y508450D02*
G02X1585268Y508582I0J451D01*
G01X1585587Y507300D02*
G02X1584454Y507768I-1J1602D01*
G01X1585268Y508582D02*
X1581233Y512617D01*
G01X1584454Y507768D02*
X1580419Y511803D01*
G01X1581233Y512617D02*
G03X1564306Y519628I-16926J-16925D01*
G01X1580419Y511803D02*
G03X1564306Y518478I-16113J-16110D01*
G01Y519628D02*
X1544839D01*
G01X1564306Y518478D02*
X1550140D01*
G01X1564306Y519628D02*
X1544839D01*
G01X1546190Y518478D02*
X1544840D01*
G01X1544839Y519628D02*
G03X1542599Y518700I0J-3168D01*
G01X1544840Y518478D02*
G03X1543413Y517886I1J-2018D01*
G01X1542599Y518700D02*
X1538662Y514763D01*
G01X1543413Y517886D02*
X1539476Y513949D01*
G01X1538662Y514763D02*
G03X1538000Y513165I1598J-1598D01*
G01X1539476Y513949D02*
G03X1539150Y513165I783J-785D01*
G01X1538000D02*
Y503600D01*
G01X1539150Y513165D02*
Y503600D01*
G01X1621018Y504200D02*
X1584169D01*
G01X1621018Y505350D02*
X1584170D01*
G01X1584169Y504200D02*
G02X1582893Y504728I1J1807D01*
G01X1584170Y505350D02*
G02X1583707Y505542I1J657D01*
G01X1582893Y504728D02*
X1578165Y509456D01*
G01X1583707Y505542D02*
X1578979Y510270D01*
G01X1578165Y509456D02*
G03X1564110Y515279I-14056J-14053D01*
G01X1578979Y510270D02*
G03X1564109Y516429I-14869J-14868D01*
G01X1564110Y515279D02*
X1554090D01*
G01X1564109Y516429D02*
X1554091D01*
G01X1554090Y515279D02*
G03X1553773Y515146I2J-450D01*
G01X1554091Y516429D02*
G03X1552959Y515960I0J-1600D01*
G01X1553773Y515146D02*
X1551635Y513008D01*
G01X1552959Y515960D02*
X1550821Y513822D01*
G01X1551635Y513008D02*
G03X1551503Y512690I317J-318D01*
G01X1550821Y513822D02*
G03X1550352Y512690I1131J-1132D01*
G01X1551502Y512691D02*
Y501192D01*
G01X1550352Y512690D02*
Y501192D01*
G01X1595718Y491781D02*
X1586850Y493622D01*
G01X1595744Y490601D02*
X1586923Y492432D01*
G01X1586850Y493622D02*
X1583490Y492480D01*
G01X1586923Y492432D02*
X1583488Y491264D01*
G01X1583490Y492480D02*
X1576753Y494798D01*
G01X1574248Y495661D02*
X1572971Y496100D01*
G01X1570465Y496962D02*
X1567802Y497879D01*
G01X1583488Y491264D02*
X1567745Y496682D01*
G01X1567802Y497879D02*
X1565763Y497389D01*
G01X1567745Y496682D02*
X1565615Y496170D01*
G01X1565763Y497389D02*
X1563260Y498686D01*
G01X1565615Y496170D02*
X1565192Y496389D01*
G01X1565763Y497389D02*
X1563260Y498686D01*
G01X1565192Y496389D02*
X1562246Y497916D01*
G01X1563260Y498686D02*
X1562747Y501134D01*
G01X1562246Y497916D02*
X1561596Y501016D01*
G01X1562751Y503437D02*
X1562918Y503883D01*
G01X1561601Y503645D02*
X1561963Y504615D01*
G01X1562918Y503883D02*
X1563438Y504254D01*
G01D02*
X1564075D01*
G01X1561963Y504615D02*
X1563069Y505404D01*
G01X1563438Y504254D02*
X1564075D01*
G01X1563069Y505404D02*
X1564075D01*
G01X1595744Y490601D02*
X1586923Y492432D01*
G01X1595718Y491781D02*
X1586850Y493622D01*
G01X1586923Y492432D02*
X1583488Y491264D01*
G01X1586850Y493622D02*
X1583490Y492480D01*
G01X1583488Y491264D02*
X1567745Y496682D01*
G01X1583490Y492480D02*
X1576753Y494798D01*
G01X1583488Y491264D02*
X1567745Y496682D01*
G01X1574248Y495661D02*
X1572971Y496100D01*
G01X1583488Y491264D02*
X1567745Y496682D01*
G01X1570465Y496962D02*
X1567802Y497879D01*
G01X1567745Y496682D02*
X1565615Y496170D01*
G01X1567802Y497879D02*
X1565763Y497389D01*
G01X1565615Y496170D02*
X1565192Y496389D01*
G01D02*
X1562246Y497916D01*
G01X1565763Y497389D02*
X1563260Y498686D01*
G01X1562246Y497916D02*
X1561596Y501016D01*
G01X1563260Y498686D02*
X1562747Y501134D01*
G01X1561601Y503645D02*
X1561963Y504615D01*
G01X1562751Y503437D02*
X1562918Y503883D01*
G01X1561963Y504615D02*
X1563069Y505404D01*
G01X1562918Y503883D02*
X1563438Y504254D01*
G01X1561963Y504615D02*
X1563069Y505404D01*
G01D02*
X1564075D01*
G01X1563438Y504254D02*
X1564075D01*
G01X1537366Y526600D02*
X1565063D01*
G01X1534578Y528179D02*
X1535324Y528926D01*
G01D02*
G02X1536227Y529300I903J-904D01*
G01X1534511Y529740D02*
G02X1536228Y530450I1716J-1718D01*
G01X1536227Y529300D02*
X1563389D01*
G01X1536228Y530450D02*
X1563389D01*
G01X1589351Y571925D02*
G03Y570125I0J-900D01*
G01Y573075D02*
G03Y568975I0J-2050D01*
G01Y566025D02*
G03Y564225I0J-900D01*
G01Y567175D02*
G03Y563075I0J-2050D01*
G01X1588789Y554086D02*
G03Y552699I694J-693D01*
G01X1591110Y554900D02*
G03X1587976I-1567J-1568D01*
G01X1588789Y554086D02*
G03Y552699I694J-693D01*
G01X1587976Y554900D02*
G03X1587975Y551885I1506J-1508D01*
G01X1588789Y552699D02*
X1591650Y549838D01*
G01X1587975Y551885D02*
X1590836Y549024D01*
G01X1590679Y530790D02*
X1588827Y528938D01*
G01D02*
G03Y526496I1221J-1221D01*
G01D02*
X1591376Y523947D01*
G01X1563692Y533086D02*
X1533898D01*
G01X1563692Y534236D02*
X1533899D01*
G01X1533898Y533086D02*
G03X1533581Y532953I2J-450D01*
G01X1533899Y534236D02*
G03X1532767Y533767I0J-1600D01*
G01X1533581Y532953D02*
X1531476Y530848D01*
G01X1528683Y528055D02*
X1527728Y527100D01*
G01X1532429Y536343D02*
G03X1532110Y536211I0J-451D01*
G01X1531296Y537025D02*
G02X1532429Y537493I1132J-1134D01*
G01X1561263Y536343D02*
X1532429D01*
G01Y537493D02*
X1561263D01*
G01Y540693D02*
G02Y536343I0J-2175D01*
G01Y537493D02*
G03Y539543I0J1025D01*
G01X1545143Y540693D02*
X1561263D01*
G01Y539543D02*
X1545143D01*
G01Y542743D02*
G03Y540693I0J-1025D01*
G01Y539543D02*
G02Y543893I0J2175D01*
G01X1563815Y542743D02*
X1545143D01*
G01Y543893D02*
X1563815D01*
G01X1567067Y541396D02*
G03X1563815Y542743I-3252J-3252D01*
G01Y543893D02*
G02X1567881Y542210I1J-5750D01*
G01X1570031Y538432D02*
X1567067Y541396D01*
G01X1567881Y542210D02*
X1570845Y539246D01*
G01X1575406Y535114D02*
G02X1570031Y538432I4327J13022D01*
G01X1570845Y539246D02*
G03X1575768Y536206I8889J8889D01*
G01X1580005Y533110D02*
G03X1575406Y535114I-15000J-28145D01*
G01X1575768Y536206D02*
G02X1580438Y534183I-10761J-31243D01*
G01X1587877Y534056D02*
G02X1583514Y532250I-4362J4364D01*
G01Y533400D02*
G03X1587063Y534870I0J5019D01*
G01X1589542Y538077D02*
G02X1587878Y534057I-5684J-1D01*
G01X1587064Y534871D02*
G03X1588392Y538077I-3206J3206D01*
G01D02*
Y540864D01*
G01X1588271Y543933D02*
G02X1589542Y540864I-3070J-3069D01*
G01X1588392D02*
G03X1587457Y543119I-3190J-1D01*
G01X1586385Y545820D02*
X1588271Y543933D01*
G01X1587457Y543120D02*
X1585571Y545006D01*
G01X1585351Y548316D02*
G03X1586385Y545820I3530J0D01*
G01X1585571Y545006D02*
G02X1584201Y548316I3310J3309D01*
G01X1585351Y584370D02*
Y578866D01*
G01Y574916D02*
Y563928D01*
G01Y559978D02*
Y548316D01*
G01X1584201D02*
Y589671D01*
G01X1537366Y526600D02*
X1565063D01*
G01X1534578Y528179D02*
X1535324Y528926D01*
G01X1534511Y529740D02*
G02X1536228Y530450I1716J-1718D01*
G01X1535324Y528926D02*
G02X1536227Y529300I903J-904D01*
G01X1536228Y530450D02*
X1563389D01*
G01X1536227Y529300D02*
X1563389D01*
G01X1589351Y573075D02*
G03Y568975I0J-2050D01*
G01Y571925D02*
G03Y570125I0J-900D01*
G01Y567175D02*
G03Y563075I0J-2050D01*
G01Y566025D02*
G03Y564225I0J-900D01*
G01X1591110Y554900D02*
G03X1587976I-1567J-1568D01*
G01D02*
G03X1587975Y551885I1506J-1508D01*
G01X1591110Y554900D02*
G03X1587976I-1567J-1568D01*
G01D02*
G03X1587975Y551885I1506J-1508D01*
G01X1588789Y554086D02*
G03Y552699I694J-693D01*
G01X1587975Y551885D02*
X1590836Y549024D01*
G01X1588789Y552699D02*
X1591650Y549838D01*
G01X1590679Y530790D02*
X1588827Y528938D01*
G01D02*
G03Y526496I1221J-1221D01*
G01D02*
X1591376Y523947D01*
G01X1563692Y534236D02*
X1533899D01*
G01X1563692Y533086D02*
X1533898D01*
G01X1533899Y534236D02*
G03X1532767Y533767I0J-1600D01*
G01X1533898Y533086D02*
G03X1533581Y532953I2J-450D01*
G01D02*
X1531476Y530848D01*
G01X1528683Y528055D02*
X1527728Y527100D01*
G01X1584201Y548316D02*
Y589671D01*
G01Y548316D02*
Y589671D01*
G01X1585351Y584370D02*
Y578866D01*
G01X1584201Y548316D02*
Y589671D01*
G01X1585351Y574916D02*
Y563928D01*
G01X1584201Y548316D02*
Y589671D01*
G01X1585351Y559978D02*
Y548316D01*
G01X1585571Y545006D02*
G02X1584201Y548316I3310J3309D01*
G01X1585351D02*
G03X1586385Y545820I3530J0D01*
G01X1587457Y543120D02*
X1585571Y545006D01*
G01X1586385Y545820D02*
X1588271Y543933D01*
G01X1588392Y540864D02*
G03X1587457Y543119I-3190J-1D01*
G01X1588271Y543933D02*
G02X1589542Y540864I-3070J-3069D01*
G01X1588392Y538077D02*
Y540864D01*
G01X1587064Y534871D02*
G03X1588392Y538077I-3206J3206D01*
G01X1589542D02*
G02X1587878Y534057I-5684J-1D01*
G01X1583514Y533400D02*
G03X1587063Y534870I0J5019D01*
G01X1587877Y534056D02*
G02X1583514Y532250I-4362J4364D01*
G01X1575768Y536206D02*
G02X1580438Y534183I-10761J-31243D01*
G01X1580005Y533110D02*
G03X1575406Y535114I-15000J-28145D01*
G01X1570845Y539246D02*
G03X1575768Y536206I8889J8889D01*
G01X1575406Y535114D02*
G02X1570031Y538432I4327J13022D01*
G01X1567881Y542210D02*
X1570845Y539246D01*
G01X1570031Y538432D02*
X1567067Y541396D01*
G01X1563815Y543893D02*
G02X1567881Y542210I1J-5750D01*
G01X1567067Y541396D02*
G03X1563815Y542743I-3252J-3252D01*
G01X1545143Y543893D02*
X1563815D01*
G01Y542743D02*
X1545143D01*
G01Y539543D02*
G02Y543893I0J2175D01*
G01Y542743D02*
G03Y540693I0J-1025D01*
G01X1561263Y539543D02*
X1545143D01*
G01Y540693D02*
X1561263D01*
G01Y537493D02*
G03Y539543I0J1025D01*
G01Y540693D02*
G02Y536343I0J-2175D01*
G01X1532429Y537493D02*
X1561263D01*
G01Y536343D02*
X1532429D01*
G01X1531296Y537025D02*
G02X1532429Y537493I1132J-1134D01*
G01Y536343D02*
G03X1532110Y536211I0J-451D01*
G01X1585351Y589670D02*
Y588320D01*
G01X1585483Y589988D02*
G03X1585351Y589670I318J-318D01*
G01X1584201Y589671D02*
G02X1584669Y590802I1601J0D01*
G01X1587800Y592305D02*
X1585483Y589988D01*
G01X1584669Y590802D02*
X1586986Y593119D01*
G01X1588118Y592437D02*
G03X1587800Y592305I0J-450D01*
G01X1586986Y593119D02*
G02X1588117Y593587I1131J-1133D01*
G01X1589509Y592437D02*
X1588118D01*
G01X1588117Y593587D02*
X1589508D01*
G01X1588117D02*
X1589508D01*
G01X1589509Y592437D02*
X1588118D01*
G01X1586986Y593119D02*
G02X1588117Y593587I1131J-1133D01*
G01X1588118Y592437D02*
G03X1587800Y592305I0J-450D01*
G01X1584669Y590802D02*
X1586986Y593119D01*
G01X1587800Y592305D02*
X1585483Y589988D01*
G01X1584201Y589671D02*
G02X1584669Y590802I1601J0D01*
G01X1585483Y589988D02*
G03X1585351Y589670I318J-318D01*
G01D02*
Y588320D01*
G01X1589806Y15110D02*
X1593831Y15933D01*
G01X1589713Y13917D02*
X1593834Y14759D01*
G01X1593831Y15933D02*
X1597547Y15191D01*
G01X1593834Y14759D02*
X1597547Y14018D01*
G01Y15191D02*
X1608125Y17305D01*
G01X1597547Y14018D02*
X1608118Y16130D01*
G01X1608125Y17305D02*
X1614200Y16015D01*
G01X1608118Y16130D02*
X1614200Y14839D01*
G01Y16015D02*
X1622192Y17712D01*
G01X1614200Y14839D02*
X1622192Y16536D01*
G01Y17712D02*
X1633276Y15359D01*
G01X1622192Y16536D02*
X1633276Y14183D01*
G01Y15359D02*
X1654911Y19953D01*
G01X1633276Y14183D02*
X1654911Y18777D01*
G01X1651351Y15828D02*
X1649015Y11635D01*
G01X1652235Y15051D02*
X1649897Y10855D01*
G01X1649015Y11635D02*
X1647925Y10839D01*
G01D02*
X1647017Y10980D01*
G01X1645785Y9275D02*
X1642957Y7209D01*
G01X1649897Y10855D02*
X1643798Y6398D01*
G01X1642957Y7209D02*
X1640288Y3265D01*
G01X1643798Y6398D02*
X1641036Y2318D01*
G01X1640288Y3265D02*
X1636109Y1688D01*
G01X1641036Y2318D02*
X1636169Y481D01*
G01X1636109Y1688D02*
X1631024Y3049D01*
G01X1636169Y481D02*
X1631018Y1860D01*
G01X1631024Y3049D02*
X1626340Y1845D01*
G01X1631018Y1860D02*
X1626314Y650D01*
G01X1626340Y1845D02*
X1619290Y3985D01*
G01X1626314Y650D02*
X1619288Y2783D01*
G01X1619290Y3985D02*
X1610059Y1219D01*
G01X1619288Y2783D02*
X1610054Y16D01*
G01X1610059Y1219D02*
X1607888Y1888D01*
G01Y1887D02*
X1605717Y2558D01*
G01X1610054Y16D02*
X1605218Y1508D01*
G01X1605717Y2558D02*
X1600835Y5815D01*
G01X1605218Y1508D02*
X1600319Y4776D01*
G01X1600835Y5815D02*
X1596952Y7164D01*
G01X1600319Y4776D02*
X1596870Y5974D01*
G01X1596952Y7164D02*
X1591958Y6164D01*
G01X1596870Y5974D02*
X1591959Y4991D01*
G01X1591958Y6164D02*
X1590148Y6525D01*
G01X1589713Y13917D02*
X1593834Y14759D01*
G01X1589806Y15110D02*
X1593831Y15933D01*
G01X1593834Y14759D02*
X1597547Y14018D01*
G01X1593831Y15933D02*
X1597547Y15191D01*
G01Y14018D02*
X1608118Y16130D01*
G01X1597547Y15191D02*
X1608125Y17305D01*
G01X1608118Y16130D02*
X1614200Y14839D01*
G01X1608125Y17305D02*
X1614200Y16015D01*
G01Y14839D02*
X1622192Y16536D01*
G01X1614200Y16015D02*
X1622192Y17712D01*
G01Y16536D02*
X1633276Y14183D01*
G01X1622192Y17712D02*
X1633276Y15359D01*
G01Y14183D02*
X1654911Y18777D01*
G01X1633276Y15359D02*
X1654911Y19953D01*
G01X1652235Y15051D02*
X1649897Y10855D01*
G01X1651351Y15828D02*
X1649015Y11635D01*
G01X1649897Y10855D02*
X1643798Y6398D01*
G01X1649015Y11635D02*
X1647925Y10839D01*
G01X1649897Y10855D02*
X1643798Y6398D01*
G01X1647925Y10839D02*
X1647017Y10980D01*
G01X1649897Y10855D02*
X1643798Y6398D01*
G01X1645785Y9275D02*
X1642957Y7209D01*
G01X1643798Y6398D02*
X1641036Y2318D01*
G01X1642957Y7209D02*
X1640288Y3265D01*
G01X1641036Y2318D02*
X1636169Y481D01*
G01X1640288Y3265D02*
X1636109Y1688D01*
G01X1636169Y481D02*
X1631018Y1860D01*
G01X1636109Y1688D02*
X1631024Y3049D01*
G01X1631018Y1860D02*
X1626314Y650D01*
G01X1631024Y3049D02*
X1626340Y1845D01*
G01X1626314Y650D02*
X1619288Y2783D01*
G01X1626340Y1845D02*
X1619290Y3985D01*
G01X1619288Y2783D02*
X1610054Y16D01*
G01X1619290Y3985D02*
X1610059Y1219D01*
G01X1610054Y16D02*
X1605218Y1508D01*
G01X1610059Y1219D02*
X1607888Y1888D01*
G01X1610054Y16D02*
X1605218Y1508D01*
G01X1607888Y1887D02*
X1605717Y2558D01*
G01X1605218Y1508D02*
X1600319Y4776D01*
G01X1605717Y2558D02*
X1600835Y5815D01*
G01X1600319Y4776D02*
X1596870Y5974D01*
G01X1600835Y5815D02*
X1596952Y7164D01*
G01X1596870Y5974D02*
X1591959Y4991D01*
G01X1596952Y7164D02*
X1591958Y6164D01*
G01D02*
X1590148Y6525D01*
G01X1590497Y32220D02*
X1615999Y26808D01*
G01X1590497Y31044D02*
X1615999Y25632D01*
G01Y26808D02*
X1635840Y31024D01*
G01X1615999Y25632D02*
X1635840Y29848D01*
G01Y31024D02*
X1642275Y29657D01*
G01X1635840Y29848D02*
X1642275Y28481D01*
G01Y29657D02*
X1645368Y30314D01*
G01X1642275Y28481D02*
X1645368Y29138D01*
G01Y30314D02*
X1649983Y29334D01*
G01X1645368Y29138D02*
X1649983Y28158D01*
G01Y29334D02*
X1654676Y30331D01*
G01X1649983Y28158D02*
X1654676Y29155D01*
G01X1591317Y29413D02*
X1615905Y24195D01*
G01X1591317Y28237D02*
X1615905Y23019D01*
G01Y24195D02*
X1635864Y28433D01*
G01X1615905Y23019D02*
X1635864Y27257D01*
G01Y28433D02*
X1642325Y27061D01*
G01X1635864Y27257D02*
X1642325Y25885D01*
G01Y27061D02*
X1645469Y27728D01*
G01X1642325Y25885D02*
X1645469Y26552D01*
G01Y27728D02*
X1650084Y26748D01*
G01X1645469Y26552D02*
X1650084Y25572D01*
G01Y26748D02*
X1654675Y27724D01*
G01X1650084Y25572D02*
X1654675Y26548D01*
G01X1591365Y20719D02*
X1593875Y21231D01*
G01X1591272Y19526D02*
X1593877Y20057D01*
G01X1593875Y21231D02*
X1597376Y20529D01*
G01X1593877Y20057D02*
X1597376Y19356D01*
G01Y20529D02*
X1608170Y22686D01*
G01X1597376Y19356D02*
X1608161Y21510D01*
G01X1608170Y22686D02*
X1614625Y21317D01*
G01X1608163Y21511D02*
X1614625Y20141D01*
G01Y21317D02*
X1635943Y25847D01*
G01X1614625Y20141D02*
X1635943Y24671D01*
G01Y25847D02*
X1642413Y24473D01*
G01X1635943Y24671D02*
X1642413Y23297D01*
G01Y24473D02*
X1645464Y25120D01*
G01X1642413Y23297D02*
X1645464Y23944D01*
G01Y25120D02*
X1650080Y24140D01*
G01X1645464Y23944D02*
X1650080Y22964D01*
G01Y24140D02*
X1654764Y25136D01*
G01X1650080Y22964D02*
X1654764Y23960D01*
G01X1589865Y17786D02*
X1593943Y18620D01*
G01X1589779Y16594D02*
X1593946Y17446D01*
G01X1593943Y18620D02*
X1597570Y17895D01*
G01X1593950Y17445D02*
X1597570Y16722D01*
G01Y17895D02*
X1607885Y19957D01*
G01X1597570Y16722D02*
X1607878Y18782D01*
G01X1607885Y19957D02*
X1614074Y18642D01*
G01X1607878Y18782D02*
X1614074Y17466D01*
G01Y18642D02*
X1622033Y20332D01*
G01X1614074Y17466D02*
X1622033Y19156D01*
G01Y20332D02*
X1625413Y19614D01*
G01X1628005Y19064D02*
X1628740Y18908D01*
G01D02*
X1629326Y18784D01*
G01X1622033Y19156D02*
X1628500Y17782D01*
G01X1628005Y19064D02*
X1628740Y18908D01*
G01D02*
X1629326Y18784D01*
G01X1631918Y18232D02*
X1633239Y17952D01*
G01X1628500Y17782D02*
X1633239Y16776D01*
G01Y17952D02*
X1634559Y18233D01*
G01X1637152Y18784D02*
X1638472Y19065D01*
G01X1641065Y19616D02*
X1642385Y19897D01*
G01X1644978Y20449D02*
X1646298Y20730D01*
G01X1648891Y21281D02*
X1654815Y22540D01*
G01X1633239Y16776D02*
X1654815Y21364D01*
G01X1590220Y34878D02*
X1616036Y29395D01*
G01X1590221Y33702D02*
X1616036Y28219D01*
G01Y29395D02*
X1635892Y33613D01*
G01X1616036Y28219D02*
X1635892Y32437D01*
G01Y33613D02*
X1642259Y32260D01*
G01X1635892Y32437D02*
X1642259Y31084D01*
G01Y32260D02*
X1645402Y32928D01*
G01X1642259Y31084D02*
X1645402Y31752D01*
G01Y32928D02*
X1650017Y31948D01*
G01X1645402Y31752D02*
X1650017Y30772D01*
G01Y31948D02*
X1654676Y32938D01*
G01X1650017Y30772D02*
X1654676Y31762D01*
G01X1590497Y31044D02*
X1615999Y25632D01*
G01X1590497Y32220D02*
X1615999Y26808D01*
G01Y25632D02*
X1635840Y29848D01*
G01X1615999Y26808D02*
X1635840Y31024D01*
G01Y29848D02*
X1642275Y28481D01*
G01X1635840Y31024D02*
X1642275Y29657D01*
G01Y28481D02*
X1645368Y29138D01*
G01X1642275Y29657D02*
X1645368Y30314D01*
G01Y29138D02*
X1649983Y28158D01*
G01X1645368Y30314D02*
X1649983Y29334D01*
G01Y28158D02*
X1654676Y29155D01*
G01X1649983Y29334D02*
X1654676Y30331D01*
G01X1591317Y28237D02*
X1615905Y23019D01*
G01X1591317Y29413D02*
X1615905Y24195D01*
G01Y23019D02*
X1635864Y27257D01*
G01X1615905Y24195D02*
X1635864Y28433D01*
G01Y27257D02*
X1642325Y25885D01*
G01X1635864Y28433D02*
X1642325Y27061D01*
G01Y25885D02*
X1645469Y26552D01*
G01X1642325Y27061D02*
X1645469Y27728D01*
G01Y26552D02*
X1650084Y25572D01*
G01X1645469Y27728D02*
X1650084Y26748D01*
G01Y25572D02*
X1654675Y26548D01*
G01X1650084Y26748D02*
X1654675Y27724D01*
G01X1591272Y19526D02*
X1593877Y20057D01*
G01X1591365Y20719D02*
X1593875Y21231D01*
G01X1593877Y20057D02*
X1597376Y19356D01*
G01X1593875Y21231D02*
X1597376Y20529D01*
G01Y19356D02*
X1608161Y21510D01*
G01X1597376Y20529D02*
X1608170Y22686D01*
G01X1608163Y21511D02*
X1614625Y20141D01*
G01X1608170Y22686D02*
X1614625Y21317D01*
G01Y20141D02*
X1635943Y24671D01*
G01X1614625Y21317D02*
X1635943Y25847D01*
G01Y24671D02*
X1642413Y23297D01*
G01X1635943Y25847D02*
X1642413Y24473D01*
G01Y23297D02*
X1645464Y23944D01*
G01X1642413Y24473D02*
X1645464Y25120D01*
G01Y23944D02*
X1650080Y22964D01*
G01X1645464Y25120D02*
X1650080Y24140D01*
G01Y22964D02*
X1654764Y23960D01*
G01X1650080Y24140D02*
X1654764Y25136D01*
G01X1589779Y16594D02*
X1593946Y17446D01*
G01X1589865Y17786D02*
X1593943Y18620D01*
G01X1593950Y17445D02*
X1597570Y16722D01*
G01X1593943Y18620D02*
X1597570Y17895D01*
G01Y16722D02*
X1607878Y18782D01*
G01X1597570Y17895D02*
X1607885Y19957D01*
G01X1607878Y18782D02*
X1614074Y17466D01*
G01X1607885Y19957D02*
X1614074Y18642D01*
G01Y17466D02*
X1622033Y19156D01*
G01X1614074Y18642D02*
X1622033Y20332D01*
G01Y19156D02*
X1628500Y17782D01*
G01X1622033Y20332D02*
X1625413Y19614D01*
G01X1622033Y19156D02*
X1628500Y17782D01*
G01D02*
X1633239Y16776D01*
G01X1628005Y19064D02*
X1628740Y18908D01*
G01X1622033Y19156D02*
X1628500Y17782D01*
G01D02*
X1633239Y16776D01*
G01X1628740Y18908D02*
X1629326Y18784D01*
G01X1628500Y17782D02*
X1633239Y16776D01*
G01X1631918Y18232D02*
X1633239Y17952D01*
G01Y16776D02*
X1654815Y21364D01*
G01X1633239Y17952D02*
X1634559Y18233D01*
G01X1633239Y16776D02*
X1654815Y21364D01*
G01X1637152Y18784D02*
X1638472Y19065D01*
G01X1633239Y16776D02*
X1654815Y21364D01*
G01X1641065Y19616D02*
X1642385Y19897D01*
G01X1633239Y16776D02*
X1654815Y21364D01*
G01X1644978Y20449D02*
X1646298Y20730D01*
G01X1633239Y16776D02*
X1654815Y21364D01*
G01X1648891Y21281D02*
X1654815Y22540D01*
G01X1590221Y33702D02*
X1616036Y28219D01*
G01X1590220Y34878D02*
X1616036Y29395D01*
G01Y28219D02*
X1635892Y32437D01*
G01X1616036Y29395D02*
X1635892Y33613D01*
G01Y32437D02*
X1642259Y31084D01*
G01X1635892Y33613D02*
X1642259Y32260D01*
G01Y31084D02*
X1645402Y31752D01*
G01X1642259Y32260D02*
X1645402Y32928D01*
G01Y31752D02*
X1650017Y30772D01*
G01X1645402Y32928D02*
X1650017Y31948D01*
G01Y30772D02*
X1654676Y31762D01*
G01X1650017Y31948D02*
X1654676Y32938D01*
G01X1597165Y34831D02*
X1610215Y32054D01*
G01D02*
X1611613Y32960D01*
G01X1614736Y32729D02*
X1615116Y34506D01*
G01X1613891Y34281D02*
X1613511Y32504D01*
G01X1615081Y32196D02*
X1614736Y32729D01*
G01X1613511Y32504D02*
X1614374Y31170D01*
G01X1615928Y32015D02*
X1615081Y32196D01*
G01X1614374Y31170D02*
X1615928Y30839D01*
G01X1635749Y36222D02*
X1615928Y32015D01*
G01Y30839D02*
X1635749Y35046D01*
G01X1615928Y30839D02*
X1635749Y35046D01*
G01Y36222D02*
X1615928Y32015D01*
G01X1614374Y31170D02*
X1615928Y30839D01*
G01Y32015D02*
X1615081Y32196D01*
G01X1613511Y32504D02*
X1614374Y31170D01*
G01X1615081Y32196D02*
X1614736Y32729D01*
G01X1613891Y34281D02*
X1613511Y32504D01*
G01X1614736Y32729D02*
X1615116Y34506D01*
G01X1610215Y32054D02*
X1611613Y32960D01*
G01X1597165Y34831D02*
X1610215Y32054D01*
G01X1589348Y36682D02*
X1589970Y39583D01*
G01X1590277Y41154D02*
X1588944Y40290D01*
G01X1589970Y39583D02*
X1590503Y39930D01*
G01X1594996Y40151D02*
X1590277Y41154D01*
G01X1590503Y39930D02*
X1594299Y39123D01*
G01X1597862Y35859D02*
X1594996Y40151D01*
G01X1594299Y39123D02*
X1597165Y34831D01*
G01X1609989Y33278D02*
X1597862Y35859D01*
G01X1610587Y33667D02*
X1609989Y33278D01*
G01X1610957Y35395D02*
X1610587Y33667D01*
G01X1611613Y32960D02*
X1611982Y34688D01*
G01X1612286Y36256D02*
X1610957Y35395D01*
G01X1611982Y34688D02*
X1612513Y35032D01*
G01X1614254Y35840D02*
X1612286Y36256D01*
G01X1612513Y35032D02*
X1613547Y34813D01*
G01X1615116Y34506D02*
X1614254Y35840D01*
G01X1613547Y34813D02*
X1613891Y34281D01*
G01X1642194Y34853D02*
X1635749Y36222D01*
G01Y35046D02*
X1642194Y33677D01*
G01X1645321Y35518D02*
X1642194Y34853D01*
G01Y33677D02*
X1645321Y34342D01*
G01X1649936Y34538D02*
X1645321Y35518D01*
G01Y34342D02*
X1649936Y33362D01*
G01X1654676Y35545D02*
X1649936Y34538D01*
G01Y33362D02*
X1654676Y34369D01*
G01X1649936Y33362D02*
X1654676Y34369D01*
G01Y35545D02*
X1649936Y34538D01*
G01X1645321Y34342D02*
X1649936Y33362D01*
G01Y34538D02*
X1645321Y35518D01*
G01X1642194Y33677D02*
X1645321Y34342D01*
G01Y35518D02*
X1642194Y34853D01*
G01X1635749Y35046D02*
X1642194Y33677D01*
G01Y34853D02*
X1635749Y36222D01*
G01X1613547Y34813D02*
X1613891Y34281D01*
G01X1615116Y34506D02*
X1614254Y35840D01*
G01X1612513Y35032D02*
X1613547Y34813D01*
G01X1614254Y35840D02*
X1612286Y36256D01*
G01X1611982Y34688D02*
X1612513Y35032D01*
G01X1612286Y36256D02*
X1610957Y35395D01*
G01X1611613Y32960D02*
X1611982Y34688D01*
G01X1610957Y35395D02*
X1610587Y33667D01*
G01D02*
X1609989Y33278D01*
G01D02*
X1597862Y35859D01*
G01X1594299Y39123D02*
X1597165Y34831D01*
G01X1597862Y35859D02*
X1594996Y40151D01*
G01X1590503Y39930D02*
X1594299Y39123D01*
G01X1594996Y40151D02*
X1590277Y41154D01*
G01X1589970Y39583D02*
X1590503Y39930D01*
G01X1590277Y41154D02*
X1588944Y40290D01*
G01X1589348Y36682D02*
X1589970Y39583D01*
G01X1632467Y46121D02*
X1607171Y40748D01*
G01Y39572D02*
X1632474Y44946D01*
G01X1648840Y42846D02*
X1632467Y46121D01*
G01X1632474Y44946D02*
X1648846Y41671D01*
G01X1651889Y43495D02*
X1648840Y42846D01*
G01X1648846Y41671D02*
X1651889Y42319D01*
G01X1648846Y41671D02*
X1651889Y42319D01*
G01Y43495D02*
X1648840Y42846D01*
G01X1632474Y44946D02*
X1648846Y41671D01*
G01X1648840Y42846D02*
X1632467Y46121D01*
G01X1607171Y39572D02*
X1632474Y44946D01*
G01X1632467Y46121D02*
X1607171Y40748D01*
G01X1648176Y50991D02*
X1669800Y55549D01*
G01X1669804Y54374D02*
X1648182Y49816D01*
G01X1632194Y54186D02*
X1648176Y50991D01*
G01X1648182Y49816D02*
X1639958Y51460D01*
G01X1632194Y54186D02*
X1648176Y50991D01*
G01X1639958Y51461D02*
X1632201Y53011D01*
G01X1606137Y48647D02*
X1632194Y54186D01*
G01X1632201Y53011D02*
X1606137Y47471D01*
G01X1606367Y46037D02*
X1632379Y51558D01*
G01X1606363Y44860D02*
X1632386Y50383D01*
G01X1632379Y51558D02*
X1648196Y48395D01*
G01X1632386Y50383D02*
X1648203Y47219D01*
G01X1648196Y48395D02*
X1659289Y50753D01*
G01X1648203Y47219D02*
X1659292Y49577D01*
G01X1606640Y43418D02*
X1632220Y48849D01*
G01X1606640Y42242D02*
X1632227Y47674D01*
G01X1632220Y48849D02*
X1647806Y45731D01*
G01X1632227Y47674D02*
X1647811Y44556D01*
G01X1647806Y45731D02*
X1659116Y48136D01*
G01X1647811Y44556D02*
X1659116Y46960D01*
G01X1632201Y53011D02*
X1606137Y47471D01*
G01Y48647D02*
X1632194Y54186D01*
G01X1648182Y49816D02*
X1639958Y51460D01*
G01Y51461D02*
X1632201Y53011D01*
G01X1632194Y54186D02*
X1648176Y50991D01*
G01X1669804Y54374D02*
X1648182Y49816D01*
G01X1648176Y50991D02*
X1669800Y55549D01*
G01X1606363Y44860D02*
X1632386Y50383D01*
G01X1606367Y46037D02*
X1632379Y51558D01*
G01X1632386Y50383D02*
X1648203Y47219D01*
G01X1632379Y51558D02*
X1648196Y48395D01*
G01X1648203Y47219D02*
X1659292Y49577D01*
G01X1648196Y48395D02*
X1659289Y50753D01*
G01X1606640Y42242D02*
X1632227Y47674D01*
G01X1606640Y43418D02*
X1632220Y48849D01*
G01X1632227Y47674D02*
X1647811Y44556D01*
G01X1632220Y48849D02*
X1647806Y45731D01*
G01X1647811Y44556D02*
X1659116Y46960D01*
G01X1647806Y45731D02*
X1659116Y48136D01*
G01X1605694Y53864D02*
X1631852Y59419D01*
G01X1605694Y52688D02*
X1631859Y58244D01*
G01X1631852Y59419D02*
X1646797Y56427D01*
G01X1631859Y58244D02*
X1646804Y55252D01*
G01X1646797Y56427D02*
X1669854Y61322D01*
G01X1646804Y55252D02*
X1669861Y60147D01*
G01X1631916Y56794D02*
X1605868Y51265D01*
G01Y50089D02*
X1631923Y55619D01*
G01X1647020Y53774D02*
X1631916Y56794D01*
G01X1631923Y55619D02*
X1639812Y54042D01*
G01X1647020Y53774D02*
X1631916Y56794D01*
G01X1639812Y54041D02*
X1647025Y52599D01*
G01X1669409Y58521D02*
X1647020Y53774D01*
G01X1647025Y52599D02*
X1669415Y57346D01*
G01X1686773Y70759D02*
X1645648Y62094D01*
G01X1686779Y69585D02*
X1645644Y60917D01*
G01X1645648Y62094D02*
X1632386Y64983D01*
G01X1645644Y60917D02*
X1632386Y63805D01*
G01Y64983D02*
X1605479Y59115D01*
G01X1632386Y63805D02*
X1605481Y57937D01*
G01X1605479Y59115D02*
X1603971Y59436D01*
G01X1605481Y57937D02*
X1603271Y58408D01*
G01X1603971Y59436D02*
X1600631Y64482D01*
G01X1603271Y58408D02*
X1599934Y63450D01*
G01X1600631Y64482D02*
X1596596Y65305D01*
G01X1599934Y63450D02*
X1596596Y64131D01*
G01X1605549Y56453D02*
X1632431Y62150D01*
G01X1605549Y55277D02*
X1632431Y60974D01*
G01Y62150D02*
X1645715Y59345D01*
G01X1632431Y60974D02*
X1645715Y58169D01*
G01Y59345D02*
X1687237Y68055D01*
G01X1645715Y58169D02*
X1687236Y66879D01*
G01X1605694Y52688D02*
X1631859Y58244D01*
G01X1605694Y53864D02*
X1631852Y59419D01*
G01X1631859Y58244D02*
X1646804Y55252D01*
G01X1631852Y59419D02*
X1646797Y56427D01*
G01X1646804Y55252D02*
X1669861Y60147D01*
G01X1646797Y56427D02*
X1669854Y61322D01*
G01X1647025Y52599D02*
X1669415Y57346D01*
G01X1669409Y58521D02*
X1647020Y53774D01*
G01X1631923Y55619D02*
X1639812Y54042D01*
G01Y54041D02*
X1647025Y52599D01*
G01X1647020Y53774D02*
X1631916Y56794D01*
G01X1605868Y50089D02*
X1631923Y55619D01*
G01X1631916Y56794D02*
X1605868Y51265D01*
G01X1686779Y69585D02*
X1645644Y60917D01*
G01X1686773Y70759D02*
X1645648Y62094D01*
G01X1645644Y60917D02*
X1632386Y63805D01*
G01X1645648Y62094D02*
X1632386Y64983D01*
G01Y63805D02*
X1605481Y57937D01*
G01X1632386Y64983D02*
X1605479Y59115D01*
G01X1605481Y57937D02*
X1603271Y58408D01*
G01X1605479Y59115D02*
X1603971Y59436D01*
G01X1603271Y58408D02*
X1599934Y63450D01*
G01X1603971Y59436D02*
X1600631Y64482D01*
G01X1599934Y63450D02*
X1596596Y64131D01*
G01X1600631Y64482D02*
X1596596Y65305D01*
G01X1605549Y55277D02*
X1632431Y60974D01*
G01X1605549Y56453D02*
X1632431Y62150D01*
G01Y60974D02*
X1645715Y58169D01*
G01X1632431Y62150D02*
X1645715Y59345D01*
G01Y58169D02*
X1687236Y66879D01*
G01X1645715Y59345D02*
X1687237Y68055D01*
G01X1658645Y381115D02*
X1646207Y389008D01*
G01X1658980Y382265D02*
X1647219Y389729D01*
G01X1646207Y389008D02*
X1643265Y401425D01*
G01X1647219Y389729D02*
X1644458Y401382D01*
G01X1643265Y401425D02*
X1643626Y402570D01*
G01Y402571D02*
X1643714Y402850D01*
G01X1643715Y402851D02*
X1643803Y403132D01*
G01X1644458Y401382D02*
X1645356Y404232D01*
G01X1658980Y382265D02*
X1647219Y389729D01*
G01X1658645Y381115D02*
X1646207Y389008D01*
G01X1647219Y389729D02*
X1644458Y401382D01*
G01X1646207Y389008D02*
X1643265Y401425D01*
G01X1644458Y401382D02*
X1645356Y404232D01*
G01X1643265Y401425D02*
X1643626Y402570D01*
G01X1644458Y401382D02*
X1645356Y404232D01*
G01X1643626Y402571D02*
X1643714Y402850D01*
G01X1644458Y401382D02*
X1645356Y404232D01*
G01X1643715Y402851D02*
X1643803Y403132D01*
G01X1644458Y401382D02*
X1645356Y404232D01*
G01X1644458Y401382D02*
X1645356Y404232D01*
G01X1660040Y384823D02*
X1649580Y391461D01*
G01X1650592Y392182D02*
X1648382Y401519D01*
G01X1649580Y391461D02*
X1647189Y401562D01*
G01X1648382Y401519D02*
X1649304Y404445D01*
G01X1647189Y401562D02*
X1648111Y404488D01*
G01X1660040Y384823D02*
X1649580Y391461D01*
G01D02*
X1647189Y401562D01*
G01X1650592Y392182D02*
X1648382Y401519D01*
G01X1647189Y401562D02*
X1648111Y404488D01*
G01X1648382Y401519D02*
X1649304Y404445D01*
G01X1643803Y403132D02*
X1643892Y403413D01*
G01D02*
X1644163Y404275D01*
G01D02*
X1643244Y408157D01*
G01X1645356Y404232D02*
X1644437Y408114D01*
G01X1643244Y408157D02*
X1653183Y439707D01*
G01X1644437Y408114D02*
X1654390Y439708D01*
G01X1651346Y453831D02*
X1647017Y460745D01*
G01X1652399Y454317D02*
X1647762Y461723D01*
G01X1647017Y460745D02*
X1637890Y463470D01*
G01X1647762Y461724D02*
X1637873Y464676D01*
G01X1637890Y463470D02*
X1633085Y461886D01*
G01X1637873Y464676D02*
X1633223Y463143D01*
G01X1633085Y461886D02*
X1627277Y465344D01*
G01X1633223Y463143D02*
X1628223Y466120D01*
G01X1643803Y403132D02*
X1643892Y403413D01*
G01D02*
X1644163Y404275D01*
G01X1645356Y404232D02*
X1644437Y408114D01*
G01X1644163Y404275D02*
X1643244Y408157D01*
G01X1644437Y408114D02*
X1654390Y439708D01*
G01X1643244Y408157D02*
X1653183Y439707D01*
G01X1652399Y454317D02*
X1647762Y461723D01*
G01X1651346Y453831D02*
X1647017Y460745D01*
G01X1647762Y461724D02*
X1637873Y464676D01*
G01X1647017Y460745D02*
X1637890Y463470D01*
G01X1637873Y464676D02*
X1633223Y463143D01*
G01X1637890Y463470D02*
X1633085Y461886D01*
G01X1633223Y463143D02*
X1628223Y466120D01*
G01X1633085Y461886D02*
X1627277Y465344D01*
G01X1649304Y404445D02*
X1648385Y408327D01*
G01X1648111Y404488D02*
X1647192Y408370D01*
G01X1648385Y408327D02*
X1658292Y439769D01*
G01X1647192Y408370D02*
X1657085Y439768D01*
G01X1652214Y459852D02*
X1649485Y464210D01*
G01D02*
X1637586Y467606D01*
G01X1648111Y404488D02*
X1647192Y408370D01*
G01X1649304Y404445D02*
X1648385Y408327D01*
G01X1647192Y408370D02*
X1657085Y439768D01*
G01X1648385Y408327D02*
X1658292Y439769D01*
G01X1652214Y459852D02*
X1649485Y464210D01*
G01D02*
X1637586Y467606D01*
G01X1589004Y514507D02*
X1601237D01*
G01X1589004Y515658D02*
X1601237D01*
G01Y514507D02*
G03X1612611Y525882I0J11374D01*
G01X1601237Y515658D02*
G03X1611461Y525882I0J10224D01*
G01X1612611D02*
Y526192D01*
G01X1611461Y525882D02*
Y531492D01*
G01X1589422Y517836D02*
X1601414D01*
G01X1589423Y518986D02*
X1601413D01*
G01X1601414Y517836D02*
G03X1609506Y525929I-1J8093D01*
G01X1601413Y518986D02*
G03X1608356Y525929I0J6943D01*
G01X1609506D02*
Y532553D01*
G01X1608356Y525929D02*
Y532553D01*
G01X1589641Y527310D02*
X1592190Y524761D01*
G01D02*
G02X1589115Y521685I-1538J-1538D01*
G01X1591376Y523947D02*
G02X1589928Y522499I-724J-724D01*
G01D02*
X1589091Y523336D01*
G01X1602086Y511778D02*
G03X1615554Y525246I0J13468D01*
G01X1602086Y510628D02*
G03X1616704Y525246I0J14618D01*
G01X1615554D02*
G02X1620183Y529875I4629J0D01*
G01X1616704Y525246D02*
G02X1620183Y528725I3479J0D01*
G01X1589004Y515658D02*
X1601237D01*
G01X1589004Y514507D02*
X1601237D01*
G01Y515658D02*
G03X1611461Y525882I0J10224D01*
G01X1601237Y514507D02*
G03X1612611Y525882I0J11374D01*
G01X1611461D02*
Y531492D01*
G01X1612611Y525882D02*
Y526192D01*
G01X1611461Y525882D02*
Y531492D01*
G01X1589423Y518986D02*
X1601413D01*
G01X1589422Y517836D02*
X1601414D01*
G01X1601413Y518986D02*
G03X1608356Y525929I0J6943D01*
G01X1601414Y517836D02*
G03X1609506Y525929I-1J8093D01*
G01X1608356D02*
Y532553D01*
G01X1609506Y525929D02*
Y532553D01*
G01X1589641Y527310D02*
X1592190Y524761D01*
G01X1591376Y523947D02*
G02X1589928Y522499I-724J-724D01*
G01X1592190Y524761D02*
G02X1589115Y521685I-1538J-1538D01*
G01X1589928Y522499D02*
X1589091Y523336D01*
G01X1627277Y465344D02*
X1625530Y470286D01*
G01X1628223Y466120D02*
X1626741Y470312D01*
G01X1625530Y470286D02*
X1626129Y472247D01*
G01X1626741Y470312D02*
X1627337Y472264D01*
G01X1626129Y472247D02*
X1624471Y477166D01*
G01X1627337Y472264D02*
X1625381Y478068D01*
G01X1624471Y477166D02*
X1619933Y478741D01*
G01X1625381Y478068D02*
X1619989Y479939D01*
G01X1619933Y478741D02*
X1615932Y477761D01*
G01X1619989Y479939D02*
X1615943Y478948D01*
G01X1615932Y477761D02*
X1613293Y478461D01*
G01X1615943Y478948D02*
X1613257Y479661D01*
G01X1613293Y478461D02*
X1599135Y473784D01*
G01X1613257Y479661D02*
X1611297Y479013D01*
G01X1613293Y478461D02*
X1599135Y473784D01*
G01X1608780Y478182D02*
X1607498Y477759D01*
G01X1613293Y478461D02*
X1599135Y473784D01*
G01X1604982Y476927D02*
X1603700Y476504D01*
G01X1613293Y478461D02*
X1599135Y473784D01*
G01X1601184Y475672D02*
X1599146Y474999D01*
G01X1599135Y473784D02*
X1595283Y475132D01*
G01X1599146Y474999D02*
X1595344Y476329D01*
G01X1595283Y475132D02*
X1592470Y474460D01*
G01X1595344Y476329D02*
X1592504Y475651D01*
G01X1592470Y474460D02*
X1589280Y475417D01*
G01X1592504Y475651D02*
X1589318Y476607D01*
G01X1628223Y466120D02*
X1626741Y470312D01*
G01X1627277Y465344D02*
X1625530Y470286D01*
G01X1626741Y470312D02*
X1627337Y472264D01*
G01X1625530Y470286D02*
X1626129Y472247D01*
G01X1627337Y472264D02*
X1625381Y478068D01*
G01X1626129Y472247D02*
X1624471Y477166D01*
G01X1625381Y478068D02*
X1619989Y479939D01*
G01X1624471Y477166D02*
X1619933Y478741D01*
G01X1619989Y479939D02*
X1615943Y478948D01*
G01X1619933Y478741D02*
X1615932Y477761D01*
G01X1615943Y478948D02*
X1613257Y479661D01*
G01X1615932Y477761D02*
X1613293Y478461D01*
G01X1613257Y479661D02*
X1611297Y479013D01*
G01X1608780Y478182D02*
X1607498Y477759D01*
G01X1604982Y476927D02*
X1603700Y476504D01*
G01X1601184Y475672D02*
X1599146Y474999D01*
G01X1613293Y478461D02*
X1599135Y473784D01*
G01X1599146Y474999D02*
X1595344Y476329D01*
G01X1599135Y473784D02*
X1595283Y475132D01*
G01X1595344Y476329D02*
X1592504Y475651D01*
G01X1595283Y475132D02*
X1592470Y474460D01*
G01X1592504Y475651D02*
X1589318Y476607D01*
G01X1592470Y474460D02*
X1589280Y475417D01*
G01X1640933Y539334D02*
Y526100D01*
G01X1642083Y539334D02*
Y526099D01*
G01X1640933Y526100D02*
G02X1639859Y523509I-3665J1D01*
G01X1642083Y526099D02*
G02X1640673Y522695I-4816J1D01*
G01X1639859Y523509D02*
X1633957Y517607D01*
G01X1640673Y522695D02*
X1634771Y516793D01*
G01X1633957Y517607D02*
G03X1631924Y512698I4907J-4908D01*
G01X1634771Y516793D02*
G03X1633075Y512698I4093J-4094D01*
G01X1631924D02*
Y505278D01*
G01X1633074Y512699D02*
Y505278D01*
G01X1631924D02*
G02X1628238Y501592I-3686J0D01*
G01X1633074Y505278D02*
G02X1628238Y500442I-4836J0D01*
G01Y501592D02*
X1625591D01*
G01X1621641D02*
X1620291D01*
G01X1616341D02*
X1614991D01*
G01X1611041D02*
X1609691D01*
G01X1605741D02*
X1600193D01*
G01X1596243D02*
X1594893D01*
G01X1590943D02*
X1589593D01*
G01X1628655Y527605D02*
G03X1629225Y526112I2236J-2D01*
G01D02*
X1629367Y525954D01*
G01X1630223Y526722D02*
G02X1630740Y525360I-1510J-1352D01*
G01X1629367Y525954D02*
G02X1629590Y525365I-654J-584D01*
G01X1630740Y525360D02*
X1630738Y524500D01*
G01X1629590Y525364D02*
X1629588Y524502D01*
G01X1630738Y524404D02*
G02X1630156Y523057I-1994J62D01*
G01X1629588Y524431D02*
G02X1629341Y523870I-844J37D01*
G01X1630156Y523057D02*
X1629548Y522448D01*
G01X1629341Y523870D02*
X1628734Y523261D01*
G01X1629548Y522448D02*
G02X1628345Y521950I-1201J1200D01*
G01X1628734Y523261D02*
G02X1628346Y523100I-388J387D01*
G01X1628345Y521950D02*
X1627144D01*
G01X1628346Y523100D02*
X1627143D01*
G01X1627144Y521950D02*
G03X1625448Y521247I1J-2399D01*
G01X1627143Y523100D02*
G03X1624634Y522061I0J-3550D01*
G01X1625448Y521247D02*
X1623824Y519623D01*
G01X1621031Y516830D02*
X1620076Y515875D01*
G01X1624634Y522061D02*
X1619262Y516689D01*
G01X1620076Y515875D02*
G03X1619588Y514700I1174J-1176D01*
G01X1619262Y516689D02*
G03X1618438Y514700I1989J-1989D01*
G01X1619588D02*
Y510056D01*
G01X1618438Y514700D02*
Y510056D01*
G01X1619588D02*
G02X1619120Y508923I-1602J-1D01*
G01X1618438Y510056D02*
G02X1618306Y509737I-451J0D01*
G01X1619120Y508923D02*
X1618127Y507930D01*
G01X1618306Y509737D02*
X1617313Y508744D01*
G01X1618127Y507930D02*
G02X1616603Y507300I-1523J1525D01*
G01X1617313Y508744D02*
G02X1616603Y508450I-710J710D01*
G01X1602086Y510628D02*
G03X1616704Y525246I0J14618D01*
G01X1602086Y511778D02*
G03X1615554Y525246I0J13468D01*
G01X1616704D02*
G02X1620183Y528725I3479J0D01*
G01X1615554Y525246D02*
G02X1620183Y529875I4629J0D01*
G01X1634150Y529401D02*
Y525028D01*
G01X1635300Y529401D02*
Y525027D01*
G01X1634150Y525028D02*
G02X1632150Y520201I-6828J1D01*
G01X1635300Y525027D02*
G02X1632964Y519387I-7979J1D01*
G01X1632150Y520201D02*
X1629936Y517987D01*
G01X1632964Y519387D02*
X1630750Y517173D01*
G01X1629936Y517987D02*
G02X1627493Y516975I-2443J2443D01*
G01X1630750Y517173D02*
G02X1627493Y515825I-3256J3257D01*
G01Y516975D02*
G03X1624198Y513680I0J-3295D01*
G01X1627493Y515825D02*
G03X1625349Y513680I0J-2144D01*
G01X1624203Y508692D02*
G02X1623747Y507595I-1547J0D01*
G01X1625353Y508693D02*
G02X1624559Y506779I-2697J-3D01*
G01X1623747Y507595D02*
X1621831Y505687D01*
G01D02*
X1621830D01*
G01X1624559Y506779D02*
X1622643Y504872D01*
G01X1621830Y505687D02*
G02X1621018Y505350I-813J812D01*
G01X1622643Y504872D02*
G02X1621018Y504200I-1625J1628D01*
G01X1642083Y539334D02*
Y526099D01*
G01X1640933Y539334D02*
Y526100D01*
G01X1642083Y526099D02*
G02X1640673Y522695I-4816J1D01*
G01X1640933Y526100D02*
G02X1639859Y523509I-3665J1D01*
G01X1640673Y522695D02*
X1634771Y516793D01*
G01X1639859Y523509D02*
X1633957Y517607D01*
G01X1634771Y516793D02*
G03X1633075Y512698I4093J-4094D01*
G01X1633957Y517607D02*
G03X1631924Y512698I4907J-4908D01*
G01X1633074Y512699D02*
Y505278D01*
G01X1631924Y512698D02*
Y505278D01*
G01X1633074D02*
G02X1628238Y500442I-4836J0D01*
G01X1631924Y505278D02*
G02X1628238Y501592I-3686J0D01*
G01D02*
X1625591D01*
G01X1621641D02*
X1620291D01*
G01X1616341D02*
X1614991D01*
G01X1611041D02*
X1609691D01*
G01X1605741D02*
X1600193D01*
G01X1596243D02*
X1594893D01*
G01X1590943D02*
X1589593D01*
G01X1628655Y527605D02*
G03X1629225Y526112I2236J-2D01*
G01D02*
X1629367Y525954D01*
G01D02*
G02X1629590Y525365I-654J-584D01*
G01X1630223Y526722D02*
G02X1630740Y525360I-1510J-1352D01*
G01X1629590Y525364D02*
X1629588Y524502D01*
G01X1630740Y525360D02*
X1630738Y524500D01*
G01X1629588Y524431D02*
G02X1629341Y523870I-844J37D01*
G01X1630738Y524404D02*
G02X1630156Y523057I-1994J62D01*
G01X1629341Y523870D02*
X1628734Y523261D01*
G01X1630156Y523057D02*
X1629548Y522448D01*
G01X1628734Y523261D02*
G02X1628346Y523100I-388J387D01*
G01X1629548Y522448D02*
G02X1628345Y521950I-1201J1200D01*
G01X1628346Y523100D02*
X1627143D01*
G01X1628345Y521950D02*
X1627144D01*
G01X1627143Y523100D02*
G03X1624634Y522061I0J-3550D01*
G01X1627144Y521950D02*
G03X1625448Y521247I1J-2399D01*
G01X1624634Y522061D02*
X1619262Y516689D01*
G01X1625448Y521247D02*
X1623824Y519623D01*
G01X1624634Y522061D02*
X1619262Y516689D01*
G01X1621031Y516830D02*
X1620076Y515875D01*
G01X1619262Y516689D02*
G03X1618438Y514700I1989J-1989D01*
G01X1620076Y515875D02*
G03X1619588Y514700I1174J-1176D01*
G01X1618438D02*
Y510056D01*
G01X1619588Y514700D02*
Y510056D01*
G01X1618438D02*
G02X1618306Y509737I-451J0D01*
G01X1619588Y510056D02*
G02X1619120Y508923I-1602J-1D01*
G01X1618306Y509737D02*
X1617313Y508744D01*
G01X1619120Y508923D02*
X1618127Y507930D01*
G01X1617313Y508744D02*
G02X1616603Y508450I-710J710D01*
G01X1618127Y507930D02*
G02X1616603Y507300I-1523J1525D01*
G01X1635300Y529401D02*
Y525027D01*
G01X1634150Y529401D02*
Y525028D01*
G01X1635300Y525027D02*
G02X1632964Y519387I-7979J1D01*
G01X1634150Y525028D02*
G02X1632150Y520201I-6828J1D01*
G01X1632964Y519387D02*
X1630750Y517173D01*
G01X1632150Y520201D02*
X1629936Y517987D01*
G01X1630750Y517173D02*
G02X1627493Y515825I-3256J3257D01*
G01X1629936Y517987D02*
G02X1627493Y516975I-2443J2443D01*
G01Y515825D02*
G03X1625349Y513680I0J-2144D01*
G01X1627493Y516975D02*
G03X1624198Y513680I0J-3295D01*
G01X1625353Y508693D02*
G02X1624559Y506779I-2697J-3D01*
G01X1624203Y508692D02*
G02X1623747Y507595I-1547J0D01*
G01X1624559Y506779D02*
X1622643Y504872D01*
G01X1623747Y507595D02*
X1621831Y505687D01*
G01X1624559Y506779D02*
X1622643Y504872D01*
G01X1621831Y505687D02*
X1621830D01*
G01X1622643Y504872D02*
G02X1621018Y504200I-1625J1628D01*
G01X1621830Y505687D02*
G02X1621018Y505350I-813J812D01*
G01X1655999Y455978D02*
X1650225Y465195D01*
G01X1655999Y455978D02*
X1650225Y465195D01*
G01D02*
X1637559Y468810D01*
G01D02*
X1633539Y467470D01*
G01X1637586Y467606D02*
X1633422Y466218D01*
G01X1633539Y467470D02*
X1631295Y468719D01*
G01X1633422Y466218D02*
X1630358Y467924D01*
G01X1631295Y468719D02*
X1630690Y470407D01*
G01X1630358Y467924D02*
X1629480Y470375D01*
G01X1630690Y470407D02*
X1631244Y472259D01*
G01X1629480Y470375D02*
X1630037Y472238D01*
G01X1631244Y472259D02*
X1628133Y481497D01*
G01X1627287Y484009D02*
X1626856Y485288D01*
G01X1626010Y487799D02*
X1625207Y490183D01*
G01X1630037Y472238D02*
X1624277Y489337D01*
G01X1625207Y490183D02*
X1616217Y494177D01*
G01X1624277Y489337D02*
X1616130Y492957D01*
G01X1616217Y494177D02*
X1607873Y491814D01*
G01X1616130Y492957D02*
X1607879Y490620D01*
G01X1607873Y491814D02*
X1602070Y493389D01*
G01X1607879Y490620D02*
X1602060Y492200D01*
G01X1602070Y493389D02*
X1595718Y491781D01*
G01X1602060Y492200D02*
X1595744Y490601D01*
G01X1655999Y455978D02*
X1650225Y465195D01*
G01D02*
X1637559Y468810D01*
G01X1637586Y467606D02*
X1633422Y466218D01*
G01X1637559Y468810D02*
X1633539Y467470D01*
G01X1633422Y466218D02*
X1630358Y467924D01*
G01X1633539Y467470D02*
X1631295Y468719D01*
G01X1630358Y467924D02*
X1629480Y470375D01*
G01X1631295Y468719D02*
X1630690Y470407D01*
G01X1629480Y470375D02*
X1630037Y472238D01*
G01X1630690Y470407D02*
X1631244Y472259D01*
G01X1630037Y472238D02*
X1624277Y489337D01*
G01X1631244Y472259D02*
X1628133Y481497D01*
G01X1630037Y472238D02*
X1624277Y489337D01*
G01X1627287Y484009D02*
X1626856Y485288D01*
G01X1630037Y472238D02*
X1624277Y489337D01*
G01X1626010Y487799D02*
X1625207Y490183D01*
G01X1624277Y489337D02*
X1616130Y492957D01*
G01X1625207Y490183D02*
X1616217Y494177D01*
G01X1616130Y492957D02*
X1607879Y490620D01*
G01X1616217Y494177D02*
X1607873Y491814D01*
G01X1607879Y490620D02*
X1602060Y492200D01*
G01X1607873Y491814D02*
X1602070Y493389D01*
G01X1602060Y492200D02*
X1595744Y490601D01*
G01X1602070Y493389D02*
X1595718Y491781D01*
G01X1612611Y530142D02*
Y531492D01*
G01D02*
G02X1613636Y532517I1025J0D01*
G01X1611461Y531492D02*
G02X1613636Y533667I2175J0D01*
G01Y532517D02*
X1620535D01*
G01X1613636Y533667D02*
X1620535D01*
G01Y532517D02*
G03Y536867I0J2175D01*
G01Y533667D02*
G03Y535717I0J1025D01*
G01Y536867D02*
X1613636D01*
G01X1620535Y535717D02*
X1613636D01*
G01Y536867D02*
G02Y538917I0J1025D01*
G01Y535717D02*
G02Y540067I0J2175D01*
G01Y538917D02*
X1620035D01*
G01X1613636Y540067D02*
X1620035D01*
G01Y538917D02*
G03Y543267I0J2175D01*
G01Y540067D02*
G03Y542117I0J1025D01*
G01Y543267D02*
X1619601D01*
G01X1620035Y542117D02*
X1619602D01*
G01X1619601Y543267D02*
G02X1617953Y543949I-2J2328D01*
G01X1619602Y542117D02*
G02X1617139Y543135I-4J3478D01*
G01X1617952Y543950D02*
G02X1616275Y548002I4059J4053D01*
G01X1617138Y543136D02*
G02X1615125Y548001I4873J4865D01*
G01X1616275Y548002D02*
Y552472D01*
G01X1615125Y548001D02*
Y552472D01*
G01X1616275D02*
G03X1614110Y554637I-2165J0D01*
G01X1615125Y552472D02*
G03X1614110Y553487I-1015J0D01*
G01Y554637D02*
X1607856D01*
G01X1614110Y553487D02*
X1607856D01*
G01Y554637D02*
G02X1605050Y557443I0J2806D01*
G01X1607856Y553487D02*
G02X1603900Y557443I0J3956D01*
G01X1605050D02*
Y569801D01*
G01X1603900Y557443D02*
Y569800D01*
G01X1605051D02*
G02X1605515Y570920I1583J0D01*
G01X1603900Y569800D02*
G02X1604701Y571734I2734J1D01*
G01X1605515Y570920D02*
X1608864Y574269D01*
G01X1604701Y571734D02*
X1608050Y575083D01*
G01X1608864Y574269D02*
G03X1609663Y576201I-1933J1931D01*
G01X1608050Y575083D02*
G03X1608513Y576201I-1118J1118D01*
G01X1609663Y576222D02*
G02X1611242Y577801I1579J0D01*
G01X1608513Y576222D02*
G02X1611242Y578951I2729J0D01*
G01Y577801D02*
X1614106D01*
G01X1611242Y578951D02*
X1614106D01*
G01Y577801D02*
G03Y582151I0J2175D01*
G01Y578951D02*
G03Y581001I0J1025D01*
G01Y582151D02*
X1611094D01*
G01X1614106Y581001D02*
X1611094D01*
G01Y582151D02*
G02X1609663Y583582I0J1431D01*
G01X1611094Y581001D02*
G02X1608513Y583582I0J2581D01*
G01X1609663D02*
Y586261D01*
G01X1608513Y583582D02*
Y586261D01*
G01X1609663D02*
G02X1610868Y587466I1205J0D01*
G01X1608513Y586261D02*
G02X1610868Y588616I2355J0D01*
G01Y587466D02*
X1612069D01*
G01X1609506Y532553D02*
G03X1607119Y534940I-2387J0D01*
G01X1608356Y532553D02*
G03X1607118Y533790I-1237J0D01*
G01X1607119Y534940D02*
X1605940D01*
G01X1607118Y533790D02*
X1605940D01*
G01Y534940D02*
G02X1603106Y537774I0J2834D01*
G01X1605940Y533790D02*
G02X1601956Y537774I0J3984D01*
G01X1603106D02*
Y545428D01*
G01X1601956Y537774D02*
Y545429D01*
G01X1603106Y545428D02*
G02X1605156I1025J0D01*
G01X1601956Y545429D02*
G02X1606306I2175J-1D01*
G01X1605156Y545428D02*
Y539280D01*
G01X1606306Y545429D02*
Y539280D01*
G01X1605156D02*
G03X1609506I2175J0D01*
G01X1606306D02*
G03X1608356I1025J0D01*
G01X1609506D02*
Y541341D01*
G01X1608356Y539280D02*
Y541341D01*
G01X1609506D02*
G02X1610531Y542366I1025J0D01*
G01X1608356Y541341D02*
G02X1610531Y543516I2175J0D01*
G01Y542366D02*
X1611508D01*
G01X1610531Y543516D02*
X1611508D01*
G01Y542366D02*
G03Y546716I0J2175D01*
G01Y543516D02*
G03Y545566I0J1025D01*
G01Y546716D02*
X1610531D01*
G01X1611508Y545566D02*
X1610531D01*
G01Y546716D02*
G02X1609506Y547741I0J1025D01*
G01X1610531Y545566D02*
G02X1608356Y547741I0J2175D01*
G01X1609506D02*
Y548696D01*
G01X1608356Y547741D02*
Y548696D01*
G01X1609506D02*
G03X1606886Y551316I-2620J0D01*
G01X1608356Y548696D02*
G03X1606886Y550166I-1470J0D01*
G01Y551316D02*
X1604316D01*
G01X1606886Y550166D02*
X1604316D01*
G01Y551316D02*
G02X1603399Y551696I0J1296D01*
G01X1604316Y550166D02*
G02X1602585Y550882I-1J2447D01*
G01X1603399Y551696D02*
X1602618Y552477D01*
G01X1599825Y555270D02*
X1595122Y559973D01*
G01X1602585Y550882D02*
X1594308Y559159D01*
G01X1595122Y559973D02*
G02X1594462Y561565I1592J1593D01*
G01X1594308Y559159D02*
G02X1593312Y561564I2406J2405D01*
G01X1594462Y561565D02*
Y571011D01*
G01X1593312Y561564D02*
Y571012D01*
G01X1594462Y571011D02*
G02X1595476Y573460I3464J0D01*
G01X1593312Y571012D02*
G02X1594662Y574274I4615J1D01*
G01X1595476Y573460D02*
X1596166Y574150D01*
G01X1594662Y574274D02*
X1595352Y574964D01*
G01X1596166Y574150D02*
G03X1597054Y576294I-2144J2144D01*
G01X1595352Y574964D02*
G03X1595904Y576294I-1330J1331D01*
G01X1597054D02*
Y580758D01*
G01X1595904Y576294D02*
Y580758D01*
G01X1597054D02*
G02X1597222Y581164I575J0D01*
G01X1595904Y580758D02*
G02X1596408Y581978I1725J1D01*
G01X1597222Y581164D02*
X1600690Y584632D01*
G01X1596408Y581978D02*
X1599876Y585446D01*
G01X1600690Y584632D02*
G02X1601009Y584764I319J-319D01*
G01X1599876Y585446D02*
G02X1601009Y585914I1132J-1134D01*
G01Y584764D02*
X1603552D01*
G01X1601009Y585914D02*
X1603552D01*
G01Y584764D02*
G03X1605584Y586796I0J2032D01*
G01X1603552Y585914D02*
G03X1604434Y586796I0J882D01*
G01X1605584D02*
Y588999D01*
G01X1604434Y586796D02*
Y589000D01*
G01X1598225Y590028D02*
G02X1595149Y586949I-1538J-1540D01*
G01X1597412Y589214D02*
G02X1595962Y587763I-725J-725D01*
G01X1595149Y586949D02*
X1593967Y588130D01*
G01X1595962Y587763D02*
X1594780Y588944D01*
G01X1593165Y588130D02*
X1592837Y587802D01*
G01D02*
G03X1592704Y587481I321J-321D01*
G01X1592023Y588616D02*
G03X1591554Y587481I1135J-1134D01*
G01X1592704D02*
Y586131D01*
G01Y582181D02*
Y579900D01*
G01X1591554Y587481D02*
Y579900D01*
G01X1592704D02*
G02X1591745Y577585I-3274J0D01*
G01X1591554Y579900D02*
G02X1590931Y578399I-2123J2D01*
G01X1591745Y577585D02*
G03X1591295Y576499I1086J-1086D01*
G01X1590931Y578399D02*
G03X1590145Y576500I1901J-1899D01*
G01X1591295Y576499D02*
Y573869D01*
G01X1590145Y576500D02*
Y573869D01*
G01X1591295D02*
G02X1589351Y571925I-1944J0D01*
G01X1590145Y573869D02*
G02X1589351Y573075I-794J0D01*
G01Y570125D02*
X1589873D01*
G01X1589351Y568975D02*
X1589873D01*
G01Y570125D02*
G02X1591295Y568703I0J-1422D01*
G01X1589873Y568975D02*
G02X1590145Y568703I0J-272D01*
G01X1591295D02*
Y567969D01*
G01X1590145Y568703D02*
Y567969D01*
G01X1591295D02*
G02X1589351Y566025I-1944J0D01*
G01X1590145Y567969D02*
G02X1589351Y567175I-794J0D01*
G01Y564225D02*
X1589605D01*
G01X1589351Y563075D02*
X1589605D01*
G01Y564225D02*
G02X1591295Y562535I0J-1690D01*
G01X1589605Y563075D02*
G02X1590145Y562535I0J-540D01*
G01X1591295D02*
Y560224D01*
G01X1590145Y562535D02*
Y560225D01*
G01X1591296D02*
G03X1591942Y558664I2208J0D01*
G01X1590145Y560225D02*
G03X1591128Y557850I3359J-1D01*
G01X1591942Y558664D02*
X1597979Y552627D01*
G01X1591128Y557850D02*
X1597165Y551813D01*
G01X1597979Y552627D02*
G02X1599167Y549756I-2872J-2870D01*
G01X1597165Y551813D02*
G02X1598017Y549756I-2057J-2057D01*
G01X1599167D02*
Y536869D01*
G01X1598017Y549756D02*
Y536869D01*
G01X1599167D02*
G02X1594817I-2175J0D01*
G01X1598017D02*
G02X1595967I-1025J0D01*
G01X1594817D02*
Y548476D01*
G01X1595967Y536869D02*
Y548475D01*
G01X1594817Y548476D02*
G03X1594044Y550343I-2641J0D01*
G01X1595967Y548475D02*
G03X1594859Y551156I-3791J3D01*
G01X1594817Y548476D02*
G03X1594044Y550343I-2641J0D01*
G01X1594859Y551156D02*
G03X1594783Y551230I-2683J-2679D01*
G01X1594042Y550343D02*
X1590297Y554086D01*
G01X1594764Y551248D02*
X1591110Y554900D01*
G01X1590297Y554086D02*
G03X1588789I-754J-754D01*
G01X1590297D02*
G03X1588789I-754J-754D01*
G01X1591650Y549838D02*
G02X1592767Y547138I-2701J-2699D01*
G01X1590836Y549024D02*
G02X1591617Y547138I-1887J-1886D01*
G01X1592767D02*
Y533050D01*
G01X1591617Y547138D02*
Y533050D01*
G01X1592767D02*
G02X1591580Y530068I-4344J2D01*
G01X1591617Y533050D02*
G02X1590744Y530858I-3194J2D01*
G01X1592767Y533050D02*
G02X1591580Y530068I-4344J2D01*
G01X1590744Y530858D02*
G02X1590681Y530793I-2324J2190D01*
G01X1591573Y530056D02*
X1589641Y528124D01*
G01D02*
G03Y527310I407J-407D01*
G01X1589542Y540864D02*
Y538077D01*
G01X1620183Y529875D02*
X1622433D01*
G01X1620183Y528725D02*
X1622433D01*
G01Y529875D02*
G03X1625318Y532760I0J2885D01*
G01X1622433Y528725D02*
G03X1626468Y532760I0J4035D01*
G01X1625318D02*
Y543861D01*
G01X1626468Y532760D02*
Y543861D01*
G01X1625318D02*
G02X1627493Y546036I2175J0D01*
G01X1626468Y543861D02*
G02X1627493Y544886I1025J0D01*
G01Y546036D02*
X1628548D01*
G01X1627493Y544886D02*
X1628548D01*
G01Y546036D02*
G03Y548086I0J1025D01*
G01Y544886D02*
G03Y549236I0J2175D01*
G01Y548086D02*
X1627210D01*
G01X1628548Y549236D02*
X1627210D01*
G01Y548086D02*
G02X1625318Y549978I0J1892D01*
G01X1627210Y549236D02*
G02X1626468Y549978I0J742D01*
G01X1625318D02*
Y550719D01*
G01X1626468Y549978D02*
Y550719D01*
G01X1625318D02*
G03X1623239I-1039J0D01*
G01X1626468D02*
G03X1622089I-2190J0D01*
G01X1623239D02*
Y547957D01*
G01X1622089Y550719D02*
Y547957D01*
G01X1623239D02*
G02X1618832I-2203J0D01*
G01X1622089D02*
G02X1619982I-1054J0D01*
G01X1618832D02*
Y582013D01*
G01X1619982Y547957D02*
Y554657D01*
G01X1618832Y547957D02*
Y582013D01*
G01X1619982Y558607D02*
Y559957D01*
G01X1618832Y547957D02*
Y582013D01*
G01X1619982Y563907D02*
Y582014D01*
G01X1618832Y582013D02*
G02X1621390Y588189I8733J1D01*
G01X1619983Y582013D02*
G02X1622204Y587375I7582J0D01*
G01X1621390Y588189D02*
X1622850Y589649D01*
G01X1622204Y587375D02*
X1623664Y588835D01*
G01X1621390Y588189D02*
X1622850Y589649D01*
G01X1612611Y530142D02*
Y531492D01*
G01X1611461D02*
G02X1613636Y533667I2175J0D01*
G01X1612611Y531492D02*
G02X1613636Y532517I1025J0D01*
G01Y533667D02*
X1620535D01*
G01X1613636Y532517D02*
X1620535D01*
G01Y533667D02*
G03Y535717I0J1025D01*
G01Y532517D02*
G03Y536867I0J2175D01*
G01Y535717D02*
X1613636D01*
G01X1620535Y536867D02*
X1613636D01*
G01Y535717D02*
G02Y540067I0J2175D01*
G01Y536867D02*
G02Y538917I0J1025D01*
G01Y540067D02*
X1620035D01*
G01X1613636Y538917D02*
X1620035D01*
G01Y540067D02*
G03Y542117I0J1025D01*
G01Y538917D02*
G03Y543267I0J2175D01*
G01Y542117D02*
X1619602D01*
G01X1620035Y543267D02*
X1619601D01*
G01X1619602Y542117D02*
G02X1617139Y543135I-4J3478D01*
G01X1619601Y543267D02*
G02X1617953Y543949I-2J2328D01*
G01X1617138Y543136D02*
G02X1615125Y548001I4873J4865D01*
G01X1617952Y543950D02*
G02X1616275Y548002I4059J4053D01*
G01X1615125Y548001D02*
Y552472D01*
G01X1616275Y548002D02*
Y552472D01*
G01X1615125D02*
G03X1614110Y553487I-1015J0D01*
G01X1616275Y552472D02*
G03X1614110Y554637I-2165J0D01*
G01Y553487D02*
X1607856D01*
G01X1614110Y554637D02*
X1607856D01*
G01Y553487D02*
G02X1603900Y557443I0J3956D01*
G01X1607856Y554637D02*
G02X1605050Y557443I0J2806D01*
G01X1603900D02*
Y569800D01*
G01X1605050Y557443D02*
Y569801D01*
G01X1603900Y569800D02*
G02X1604701Y571734I2734J1D01*
G01X1605051Y569800D02*
G02X1605515Y570920I1583J0D01*
G01X1604701Y571734D02*
X1608050Y575083D01*
G01X1605515Y570920D02*
X1608864Y574269D01*
G01X1608050Y575083D02*
G03X1608513Y576201I-1118J1118D01*
G01X1608864Y574269D02*
G03X1609663Y576201I-1933J1931D01*
G01X1608513Y576222D02*
G02X1611242Y578951I2729J0D01*
G01X1609663Y576222D02*
G02X1611242Y577801I1579J0D01*
G01Y578951D02*
X1614106D01*
G01X1611242Y577801D02*
X1614106D01*
G01Y578951D02*
G03Y581001I0J1025D01*
G01Y577801D02*
G03Y582151I0J2175D01*
G01Y581001D02*
X1611094D01*
G01X1614106Y582151D02*
X1611094D01*
G01Y581001D02*
G02X1608513Y583582I0J2581D01*
G01X1611094Y582151D02*
G02X1609663Y583582I0J1431D01*
G01X1608513D02*
Y586261D01*
G01X1609663Y583582D02*
Y586261D01*
G01X1608513D02*
G02X1610868Y588616I2355J0D01*
G01X1609663Y586261D02*
G02X1610868Y587466I1205J0D01*
G01D02*
X1612069D01*
G01X1608356Y532553D02*
G03X1607118Y533790I-1237J0D01*
G01X1609506Y532553D02*
G03X1607119Y534940I-2387J0D01*
G01X1607118Y533790D02*
X1605940D01*
G01X1607119Y534940D02*
X1605940D01*
G01Y533790D02*
G02X1601956Y537774I0J3984D01*
G01X1605940Y534940D02*
G02X1603106Y537774I0J2834D01*
G01X1601956D02*
Y545429D01*
G01X1603106Y537774D02*
Y545428D01*
G01X1601956Y545429D02*
G02X1606306I2175J-1D01*
G01X1603106Y545428D02*
G02X1605156I1025J0D01*
G01X1606306Y545429D02*
Y539280D01*
G01X1605156Y545428D02*
Y539280D01*
G01X1606306D02*
G03X1608356I1025J0D01*
G01X1605156D02*
G03X1609506I2175J0D01*
G01X1608356D02*
Y541341D01*
G01X1609506Y539280D02*
Y541341D01*
G01X1608356D02*
G02X1610531Y543516I2175J0D01*
G01X1609506Y541341D02*
G02X1610531Y542366I1025J0D01*
G01Y543516D02*
X1611508D01*
G01X1610531Y542366D02*
X1611508D01*
G01Y543516D02*
G03Y545566I0J1025D01*
G01Y542366D02*
G03Y546716I0J2175D01*
G01Y545566D02*
X1610531D01*
G01X1611508Y546716D02*
X1610531D01*
G01Y545566D02*
G02X1608356Y547741I0J2175D01*
G01X1610531Y546716D02*
G02X1609506Y547741I0J1025D01*
G01X1608356D02*
Y548696D01*
G01X1609506Y547741D02*
Y548696D01*
G01X1608356D02*
G03X1606886Y550166I-1470J0D01*
G01X1609506Y548696D02*
G03X1606886Y551316I-2620J0D01*
G01Y550166D02*
X1604316D01*
G01X1606886Y551316D02*
X1604316D01*
G01Y550166D02*
G02X1602585Y550882I-1J2447D01*
G01X1604316Y551316D02*
G02X1603399Y551696I0J1296D01*
G01X1602585Y550882D02*
X1594308Y559159D01*
G01X1603399Y551696D02*
X1602618Y552477D01*
G01X1602585Y550882D02*
X1594308Y559159D01*
G01X1599825Y555270D02*
X1595122Y559973D01*
G01X1594308Y559159D02*
G02X1593312Y561564I2406J2405D01*
G01X1595122Y559973D02*
G02X1594462Y561565I1592J1593D01*
G01X1593312Y561564D02*
Y571012D01*
G01X1594462Y561565D02*
Y571011D01*
G01X1593312Y571012D02*
G02X1594662Y574274I4615J1D01*
G01X1594462Y571011D02*
G02X1595476Y573460I3464J0D01*
G01X1594662Y574274D02*
X1595352Y574964D01*
G01X1595476Y573460D02*
X1596166Y574150D01*
G01X1595352Y574964D02*
G03X1595904Y576294I-1330J1331D01*
G01X1596166Y574150D02*
G03X1597054Y576294I-2144J2144D01*
G01X1595904D02*
Y580758D01*
G01X1597054Y576294D02*
Y580758D01*
G01X1595904D02*
G02X1596408Y581978I1725J1D01*
G01X1597054Y580758D02*
G02X1597222Y581164I575J0D01*
G01X1596408Y581978D02*
X1599876Y585446D01*
G01X1597222Y581164D02*
X1600690Y584632D01*
G01X1599876Y585446D02*
G02X1601009Y585914I1132J-1134D01*
G01X1600690Y584632D02*
G02X1601009Y584764I319J-319D01*
G01Y585914D02*
X1603552D01*
G01X1601009Y584764D02*
X1603552D01*
G01Y585914D02*
G03X1604434Y586796I0J882D01*
G01X1603552Y584764D02*
G03X1605584Y586796I0J2032D01*
G01X1604434D02*
Y589000D01*
G01X1605584Y586796D02*
Y588999D01*
G01X1597412Y589214D02*
G02X1595962Y587763I-725J-725D01*
G01X1598225Y590028D02*
G02X1595149Y586949I-1538J-1540D01*
G01X1595962Y587763D02*
X1594780Y588944D01*
G01X1595149Y586949D02*
X1593967Y588130D01*
G01X1593165D02*
X1592837Y587802D01*
G01X1592023Y588616D02*
G03X1591554Y587481I1135J-1134D01*
G01X1592837Y587802D02*
G03X1592704Y587481I321J-321D01*
G01X1591554D02*
Y579900D01*
G01X1592704Y587481D02*
Y586131D01*
G01X1591554Y587481D02*
Y579900D01*
G01X1592704Y582181D02*
Y579900D01*
G01X1591554D02*
G02X1590931Y578399I-2123J2D01*
G01X1592704Y579900D02*
G02X1591745Y577585I-3274J0D01*
G01X1590931Y578399D02*
G03X1590145Y576500I1901J-1899D01*
G01X1591745Y577585D02*
G03X1591295Y576499I1086J-1086D01*
G01X1590145Y576500D02*
Y573869D01*
G01X1591295Y576499D02*
Y573869D01*
G01X1590145D02*
G02X1589351Y573075I-794J0D01*
G01X1591295Y573869D02*
G02X1589351Y571925I-1944J0D01*
G01Y568975D02*
X1589873D01*
G01X1589351Y570125D02*
X1589873D01*
G01Y568975D02*
G02X1590145Y568703I0J-272D01*
G01X1589873Y570125D02*
G02X1591295Y568703I0J-1422D01*
G01X1590145D02*
Y567969D01*
G01X1591295Y568703D02*
Y567969D01*
G01X1590145D02*
G02X1589351Y567175I-794J0D01*
G01X1591295Y567969D02*
G02X1589351Y566025I-1944J0D01*
G01Y563075D02*
X1589605D01*
G01X1589351Y564225D02*
X1589605D01*
G01Y563075D02*
G02X1590145Y562535I0J-540D01*
G01X1589605Y564225D02*
G02X1591295Y562535I0J-1690D01*
G01X1590145D02*
Y560225D01*
G01X1591295Y562535D02*
Y560224D01*
G01X1590145Y560225D02*
G03X1591128Y557850I3359J-1D01*
G01X1591296Y560225D02*
G03X1591942Y558664I2208J0D01*
G01X1591128Y557850D02*
X1597165Y551813D01*
G01X1591942Y558664D02*
X1597979Y552627D01*
G01X1597165Y551813D02*
G02X1598017Y549756I-2057J-2057D01*
G01X1597979Y552627D02*
G02X1599167Y549756I-2872J-2870D01*
G01X1598017D02*
Y536869D01*
G01X1599167Y549756D02*
Y536869D01*
G01X1598017D02*
G02X1595967I-1025J0D01*
G01X1599167D02*
G02X1594817I-2175J0D01*
G01X1595967D02*
Y548475D01*
G01X1594817Y536869D02*
Y548476D01*
G01X1595967Y548475D02*
G03X1594859Y551156I-3791J3D01*
G01D02*
G03X1594783Y551230I-2683J-2679D01*
G01X1594817Y548476D02*
G03X1594044Y550343I-2641J0D01*
G01X1594764Y551248D02*
X1591110Y554900D01*
G01X1594042Y550343D02*
X1590297Y554086D01*
G01D02*
G03X1588789I-754J-754D01*
G01X1590836Y549024D02*
G02X1591617Y547138I-1887J-1886D01*
G01X1591650Y549838D02*
G02X1592767Y547138I-2701J-2699D01*
G01X1591617D02*
Y533050D01*
G01X1592767Y547138D02*
Y533050D01*
G01X1591617D02*
G02X1590744Y530858I-3194J2D01*
G01D02*
G02X1590681Y530793I-2324J2190D01*
G01X1592767Y533050D02*
G02X1591580Y530068I-4344J2D01*
G01X1591573Y530056D02*
X1589641Y528124D01*
G01D02*
G03Y527310I407J-407D01*
G01X1589542Y540864D02*
Y538077D01*
G01X1654567Y555585D02*
X1642782Y543800D01*
G01X1655381Y554771D02*
X1643596Y542986D01*
G01X1642782Y543800D02*
G03X1640933Y539334I4466J-4465D01*
G01X1643596Y542986D02*
G03X1642083Y539334I3651J-3652D01*
G01X1652162Y588986D02*
G03Y584636I0J-2175D01*
G01X1651372Y571627D02*
G03X1650257Y568931I2696J-2693D01*
G01D02*
Y562245D01*
G01X1651407Y562246D02*
G02X1650316Y559610I-3730J0D01*
G01X1650256Y562246D02*
G02X1649502Y560424I-2579J0D01*
G01X1650316Y559610D02*
X1649864Y559158D01*
G01X1649502Y560424D02*
X1649050Y559972D01*
G01X1649864Y559158D02*
G02X1646786I-1539J1539D01*
G01X1649050Y559972D02*
G02X1647600I-725J725D01*
G01X1646786Y559158D02*
X1643333Y562611D01*
G01X1647600Y559972D02*
X1644147Y563425D01*
G01X1643333Y562611D02*
G03X1641885I-724J-724D01*
G01X1641882Y562608D02*
G03Y561160I724J-724D01*
G01X1644147Y563425D02*
G03X1641071I-1538J-1538D01*
G01X1643333Y562611D02*
G03X1641885I-724J-724D01*
G01X1641882Y562608D02*
G03Y561160I724J-724D01*
G01X1641068Y563422D02*
G03Y560346I1538J-1538D01*
G01X1641882Y561160D02*
X1644300Y558742D01*
G01X1641068Y560346D02*
X1643486Y557928D01*
G01X1644300Y558742D02*
G02Y555126I-1808J-1808D01*
G01X1643486Y557928D02*
G02Y555940I-994J-994D01*
G01X1644300Y555126D02*
X1630300Y541126D01*
G01X1643486Y555940D02*
X1629486Y541940D01*
G01X1630300Y541126D02*
G03X1629805Y539931I1195J-1195D01*
G01X1629486Y541940D02*
G03X1628655Y539931I2010J-2008D01*
G01X1629805D02*
Y538206D01*
G01Y534256D02*
Y532906D01*
G01Y528956D02*
Y527606D01*
G01X1628655Y539931D02*
Y527605D01*
G01X1629805Y527606D02*
G03X1630083Y526881I1085J0D01*
G01X1630082Y526879D02*
X1630223Y526722D01*
G01X1620183Y528725D02*
X1622433D01*
G01X1620183Y529875D02*
X1622433D01*
G01Y528725D02*
G03X1626468Y532760I0J4035D01*
G01X1622433Y529875D02*
G03X1625318Y532760I0J2885D01*
G01X1626468D02*
Y543861D01*
G01X1625318Y532760D02*
Y543861D01*
G01X1626468D02*
G02X1627493Y544886I1025J0D01*
G01X1625318Y543861D02*
G02X1627493Y546036I2175J0D01*
G01Y544886D02*
X1628548D01*
G01X1627493Y546036D02*
X1628548D01*
G01Y544886D02*
G03Y549236I0J2175D01*
G01Y546036D02*
G03Y548086I0J1025D01*
G01Y549236D02*
X1627210D01*
G01X1628548Y548086D02*
X1627210D01*
G01Y549236D02*
G02X1626468Y549978I0J742D01*
G01X1627210Y548086D02*
G02X1625318Y549978I0J1892D01*
G01X1626468D02*
Y550719D01*
G01X1625318Y549978D02*
Y550719D01*
G01X1626468D02*
G03X1622089I-2190J0D01*
G01X1625318D02*
G03X1623239I-1039J0D01*
G01X1622089D02*
Y547957D01*
G01X1623239Y550719D02*
Y547957D01*
G01X1622089D02*
G02X1619982I-1054J0D01*
G01X1623239D02*
G02X1618832I-2203J0D01*
G01X1619982D02*
Y554657D01*
G01Y558607D02*
Y559957D01*
G01Y563907D02*
Y582014D01*
G01X1618832Y547957D02*
Y582013D01*
G01X1619983D02*
G02X1622204Y587375I7582J0D01*
G01X1618832Y582013D02*
G02X1621390Y588189I8733J1D01*
G01X1622204Y587375D02*
X1623664Y588835D01*
G01X1621390Y588189D02*
X1622850Y589649D01*
G01X1653891Y559372D02*
X1648656Y554138D01*
G01X1645863Y551345D02*
X1644908Y550391D01*
G01X1642115Y547598D02*
X1641160Y546644D01*
G01X1638367Y543851D02*
X1637412Y542897D01*
G01X1634619Y540104D02*
X1633664Y539150D01*
G01X1654705Y558558D02*
X1634478Y538336D01*
G01X1633664Y539150D02*
G03X1633196Y538017I1134J-1132D01*
G01X1634478Y538336D02*
G03X1634346Y538017I319J-319D01*
G01X1633196D02*
Y531915D01*
G01X1634346Y538017D02*
Y531914D01*
G01X1633196Y531915D02*
G03X1633599Y530850I1602J-2D01*
G01X1634346Y531914D02*
G03X1634460Y531614I452J0D01*
G01X1633599Y530850D02*
G02X1634150Y529401I-1634J-1450D01*
G01X1634460Y531614D02*
G02X1635300Y529401I-2495J-2213D01*
G01X1655381Y554771D02*
X1643596Y542986D01*
G01X1654567Y555585D02*
X1642782Y543800D01*
G01X1643596Y542986D02*
G03X1642083Y539334I3651J-3652D01*
G01X1642782Y543800D02*
G03X1640933Y539334I4466J-4465D01*
G01X1652162Y588986D02*
G03Y584636I0J-2175D01*
G01X1651372Y571627D02*
G03X1650257Y568931I2696J-2693D01*
G01D02*
Y562245D01*
G01X1650256Y562246D02*
G02X1649502Y560424I-2579J0D01*
G01X1651407Y562246D02*
G02X1650316Y559610I-3730J0D01*
G01X1649502Y560424D02*
X1649050Y559972D01*
G01X1650316Y559610D02*
X1649864Y559158D01*
G01X1649050Y559972D02*
G02X1647600I-725J725D01*
G01X1649864Y559158D02*
G02X1646786I-1539J1539D01*
G01X1647600Y559972D02*
X1644147Y563425D01*
G01X1646786Y559158D02*
X1643333Y562611D01*
G01X1644147Y563425D02*
G03X1641071I-1538J-1538D01*
G01X1641068Y563422D02*
G03Y560346I1538J-1538D01*
G01X1643333Y562611D02*
G03X1641885I-724J-724D01*
G01X1644147Y563425D02*
G03X1641071I-1538J-1538D01*
G01X1641068Y563422D02*
G03Y560346I1538J-1538D01*
G01X1641882Y562608D02*
G03Y561160I724J-724D01*
G01X1641068Y560346D02*
X1643486Y557928D01*
G01X1641882Y561160D02*
X1644300Y558742D01*
G01X1643486Y557928D02*
G02Y555940I-994J-994D01*
G01X1644300Y558742D02*
G02Y555126I-1808J-1808D01*
G01X1643486Y555940D02*
X1629486Y541940D01*
G01X1644300Y555126D02*
X1630300Y541126D01*
G01X1629486Y541940D02*
G03X1628655Y539931I2010J-2008D01*
G01X1630300Y541126D02*
G03X1629805Y539931I1195J-1195D01*
G01X1628655D02*
Y527605D01*
G01X1629805Y539931D02*
Y538206D01*
G01X1628655Y539931D02*
Y527605D01*
G01X1629805Y534256D02*
Y532906D01*
G01X1628655Y539931D02*
Y527605D01*
G01X1629805Y528956D02*
Y527606D01*
G01D02*
G03X1630083Y526881I1085J0D01*
G01X1630082Y526879D02*
X1630223Y526722D01*
G01X1654705Y558558D02*
X1634478Y538336D01*
G01X1653891Y559372D02*
X1648656Y554138D01*
G01X1654705Y558558D02*
X1634478Y538336D01*
G01X1645863Y551345D02*
X1644908Y550391D01*
G01X1654705Y558558D02*
X1634478Y538336D01*
G01X1642115Y547598D02*
X1641160Y546644D01*
G01X1654705Y558558D02*
X1634478Y538336D01*
G01X1638367Y543851D02*
X1637412Y542897D01*
G01X1654705Y558558D02*
X1634478Y538336D01*
G01X1634619Y540104D02*
X1633664Y539150D01*
G01X1634478Y538336D02*
G03X1634346Y538017I319J-319D01*
G01X1633664Y539150D02*
G03X1633196Y538017I1134J-1132D01*
G01X1634346D02*
Y531914D01*
G01X1633196Y538017D02*
Y531915D01*
G01X1634346Y531914D02*
G03X1634460Y531614I452J0D01*
G01X1633196Y531915D02*
G03X1633599Y530850I1602J-2D01*
G01X1634460Y531614D02*
G02X1635300Y529401I-2495J-2213D01*
G01X1633599Y530850D02*
G02X1634150Y529401I-1634J-1450D01*
G01X1610868Y588616D02*
X1611957D01*
G01X1605584Y588999D02*
G02X1605716Y589317I450J0D01*
G01X1604434Y589000D02*
G02X1604902Y590131I1601J0D01*
G01X1605716Y589317D02*
X1607377Y590978D01*
G01X1604902Y590131D02*
X1606563Y591791D01*
G01X1607377Y590978D02*
G03X1607845Y592109I-1133J1131D01*
G01X1606563Y591791D02*
G03X1606695Y592109I-318J319D01*
G01X1607845D02*
Y598067D01*
G01X1606695Y592109D02*
Y598067D01*
G01X1607845D02*
G02X1608237Y599013I1337J0D01*
G01X1606695Y598067D02*
G02X1607423Y599827I2488J1D01*
G01X1608237Y599013D02*
X1609615Y600391D01*
G01X1607423Y599827D02*
X1608801Y601205D01*
G01X1609615Y600391D02*
G02X1610300Y600675I685J-684D01*
G01X1608801Y601205D02*
G02X1610300Y601825I1498J-1499D01*
G01Y600675D02*
X1611738D01*
G01X1610300Y601825D02*
X1611738D01*
G01X1602313Y594170D02*
X1598988D01*
G01X1602303Y595320D02*
X1598987D01*
G01X1598988Y594170D02*
G03X1598670Y594038I0J-450D01*
G01X1598987Y595320D02*
G03X1597856Y594852I0J-1601D01*
G01X1598670Y594038D02*
X1597287Y592655D01*
G01X1597856Y594852D02*
X1596473Y593469D01*
G01X1597287Y592655D02*
G03X1597288Y590960I846J-847D01*
G01X1596473Y593469D02*
G03X1596476Y590144I1660J-1661D01*
G01X1597288Y590960D02*
X1598225Y590028D01*
G01X1596476Y590144D02*
X1597412Y589214D01*
G01X1593967Y588130D02*
G03X1593165I-401J-401D01*
G01X1594780Y588944D02*
G03X1592351I-1214J-1215D01*
G01D02*
X1592023Y588616D01*
G01X1590640Y592905D02*
G02X1589509Y592437I-1131J1133D01*
G01X1589508Y593587D02*
G03X1589826Y593719I0J450D01*
G01X1593165Y595430D02*
X1590640Y592905D01*
G01X1589826Y593719D02*
X1592351Y596244D01*
G01X1593634Y596562D02*
G02X1593165Y595430I-1600J0D01*
G01X1592351Y596244D02*
G03X1592483Y596562I-317J318D01*
G01X1593634Y598790D02*
Y596562D01*
G01X1592484Y596561D02*
Y598791D01*
G01X1593766Y599108D02*
G03X1593634Y598790I318J-318D01*
G01X1592484Y598791D02*
G02X1592952Y599922I1601J0D01*
G01X1600401Y605743D02*
X1599446Y604788D01*
G01X1596653Y601995D02*
X1593766Y599108D01*
G01X1592952Y599922D02*
X1599587Y606557D01*
G01X1600719Y605875D02*
G03X1600401Y605743I0J-450D01*
G01X1599587Y606557D02*
G02X1600718Y607025I1131J-1133D01*
G01X1602258Y605875D02*
X1600719D01*
G01X1600718Y607025D02*
X1602258D01*
G01X1623664Y588836D02*
X1623666Y588838D01*
G01X1622850Y589650D02*
G02X1627075Y591400I4225J-4225D01*
G01X1623666Y588838D02*
G02X1627075Y590250I3409J-3409D01*
G01Y591400D02*
X1647162D01*
G01X1627075Y590250D02*
X1647161D01*
G01X1647162Y591400D02*
G03X1647479Y591533I-2J449D01*
G01X1647161Y590250D02*
G03X1648293Y590719I0J1600D01*
G01X1647479Y591533D02*
X1649240Y593294D01*
G01X1648293Y590719D02*
X1650054Y592480D01*
G01X1649240Y593294D02*
G03X1649372Y593612I-317J318D01*
G01X1650054Y592480D02*
G03X1650523Y593611I-1131J1132D01*
G01X1649373D02*
Y594708D01*
G01D02*
G02X1651190Y596525I1817J0D01*
G01X1610868Y588616D02*
X1611957D01*
G01X1604434Y589000D02*
G02X1604902Y590131I1601J0D01*
G01X1605584Y588999D02*
G02X1605716Y589317I450J0D01*
G01X1604902Y590131D02*
X1606563Y591791D01*
G01X1605716Y589317D02*
X1607377Y590978D01*
G01X1606563Y591791D02*
G03X1606695Y592109I-318J319D01*
G01X1607377Y590978D02*
G03X1607845Y592109I-1133J1131D01*
G01X1606695D02*
Y598067D01*
G01X1607845Y592109D02*
Y598067D01*
G01X1606695D02*
G02X1607423Y599827I2488J1D01*
G01X1607845Y598067D02*
G02X1608237Y599013I1337J0D01*
G01X1607423Y599827D02*
X1608801Y601205D01*
G01X1608237Y599013D02*
X1609615Y600391D01*
G01X1608801Y601205D02*
G02X1610300Y601825I1498J-1499D01*
G01X1609615Y600391D02*
G02X1610300Y600675I685J-684D01*
G01Y601825D02*
X1611738D01*
G01X1610300Y600675D02*
X1611738D01*
G01X1602303Y595320D02*
X1598987D01*
G01X1602313Y594170D02*
X1598988D01*
G01X1598987Y595320D02*
G03X1597856Y594852I0J-1601D01*
G01X1598988Y594170D02*
G03X1598670Y594038I0J-450D01*
G01X1597856Y594852D02*
X1596473Y593469D01*
G01X1598670Y594038D02*
X1597287Y592655D01*
G01X1596473Y593469D02*
G03X1596476Y590144I1660J-1661D01*
G01X1597287Y592655D02*
G03X1597288Y590960I846J-847D01*
G01X1596476Y590144D02*
X1597412Y589214D01*
G01X1597288Y590960D02*
X1598225Y590028D01*
G01X1594780Y588944D02*
G03X1592351I-1214J-1215D01*
G01X1593967Y588130D02*
G03X1593165I-401J-401D01*
G01X1592351Y588944D02*
X1592023Y588616D01*
G01X1600718Y607025D02*
X1602258D01*
G01Y605875D02*
X1600719D01*
G01X1599587Y606557D02*
G02X1600718Y607025I1131J-1133D01*
G01X1600719Y605875D02*
G03X1600401Y605743I0J-450D01*
G01X1592952Y599922D02*
X1599587Y606557D01*
G01X1600401Y605743D02*
X1599446Y604788D01*
G01X1592952Y599922D02*
X1599587Y606557D01*
G01X1596653Y601995D02*
X1593766Y599108D01*
G01X1592484Y598791D02*
G02X1592952Y599922I1601J0D01*
G01X1593766Y599108D02*
G03X1593634Y598790I318J-318D01*
G01X1592484Y596561D02*
Y598791D01*
G01X1593634Y598790D02*
Y596562D01*
G01X1592351Y596244D02*
G03X1592483Y596562I-317J318D01*
G01X1593634D02*
G02X1593165Y595430I-1600J0D01*
G01X1589826Y593719D02*
X1592351Y596244D01*
G01X1593165Y595430D02*
X1590640Y592905D01*
G01X1589508Y593587D02*
G03X1589826Y593719I0J450D01*
G01X1590640Y592905D02*
G02X1589509Y592437I-1131J1133D01*
G01X1623664Y588836D02*
X1623666Y588838D01*
G01D02*
G02X1627075Y590250I3409J-3409D01*
G01X1622850Y589650D02*
G02X1627075Y591400I4225J-4225D01*
G01Y590250D02*
X1647161D01*
G01X1627075Y591400D02*
X1647162D01*
G01X1647161Y590250D02*
G03X1648293Y590719I0J1600D01*
G01X1647162Y591400D02*
G03X1647479Y591533I-2J449D01*
G01X1648293Y590719D02*
X1650054Y592480D01*
G01X1647479Y591533D02*
X1649240Y593294D01*
G01X1650054Y592480D02*
G03X1650523Y593611I-1131J1132D01*
G01X1649240Y593294D02*
G03X1649372Y593612I-317J318D01*
G01X1649373Y593611D02*
Y594708D01*
G01D02*
G02X1651190Y596525I1817J0D01*
G01X1654911Y19953D02*
X1659576Y18961D01*
G01X1654911Y18777D02*
X1659576Y17785D01*
G01Y18961D02*
X1664299Y19965D01*
G01X1659576Y17785D02*
X1664299Y18789D01*
G01Y19965D02*
X1668936Y18981D01*
G01X1664299Y18789D02*
X1668936Y17805D01*
G01Y18981D02*
X1673496Y19950D01*
G01X1668936Y17805D02*
X1673496Y18774D01*
G01Y19950D02*
X1678669Y18851D01*
G01X1673496Y18774D02*
X1678669Y17675D01*
G01Y18851D02*
X1683703Y19922D01*
G01X1678669Y17675D02*
X1683703Y18746D01*
G01Y19922D02*
X1687959Y19016D01*
G01X1683703Y18746D02*
X1687959Y17840D01*
G01Y19016D02*
X1692592Y20001D01*
G01X1687959Y17840D02*
X1692592Y18825D01*
G01Y20001D02*
X1698839Y18673D01*
G01X1692592Y18825D02*
X1698883Y17487D01*
G01X1698839Y18673D02*
X1702956Y19874D01*
G01X1698883Y17487D02*
X1703000Y18688D01*
G01X1702956Y19874D02*
X1707063Y19000D01*
G01X1703000Y18688D02*
X1707186Y17797D01*
G01X1707063Y19000D02*
X1731110Y29571D01*
G01X1707186Y17797D02*
X1731352Y28421D01*
G01X1730767Y26689D02*
X1707254Y16352D01*
G01X1731009Y25539D02*
X1707378Y15149D01*
G01X1707254Y16352D02*
X1703054Y17246D01*
G01X1707378Y15149D02*
X1703098Y16060D01*
G01X1703054Y17246D02*
X1698853Y16020D01*
G01X1703098Y16060D02*
X1698897Y14834D01*
G01X1698853Y16020D02*
X1692494Y17373D01*
G01X1698897Y14834D02*
X1692494Y16197D01*
G01Y17373D02*
X1687973Y16413D01*
G01X1692494Y16197D02*
X1687973Y15237D01*
G01Y16413D02*
X1683718Y17318D01*
G01X1687973Y15237D02*
X1683718Y16142D01*
G01Y17318D02*
X1678771Y16266D01*
G01X1683718Y16142D02*
X1678771Y15090D01*
G01Y16266D02*
X1673597Y17365D01*
G01X1678771Y15090D02*
X1673597Y16189D01*
G01Y17365D02*
X1669001Y16388D01*
G01X1673597Y16189D02*
X1669001Y15212D01*
G01Y16388D02*
X1664364Y17372D01*
G01X1669001Y15212D02*
X1664364Y16196D01*
G01Y17372D02*
X1659679Y16376D01*
G01X1664364Y16196D02*
X1659679Y15200D01*
G01Y16376D02*
X1655013Y17368D01*
G01X1659679Y15200D02*
X1655013Y16192D01*
G01Y17368D02*
X1652796Y16897D01*
G01X1655013Y16192D02*
X1653280Y15823D01*
G01X1652796Y16897D02*
X1651351Y15828D01*
G01X1653280Y15823D02*
X1652235Y15051D01*
G01X1654911Y18777D02*
X1659576Y17785D01*
G01X1654911Y19953D02*
X1659576Y18961D01*
G01Y17785D02*
X1664299Y18789D01*
G01X1659576Y18961D02*
X1664299Y19965D01*
G01Y18789D02*
X1668936Y17805D01*
G01X1664299Y19965D02*
X1668936Y18981D01*
G01Y17805D02*
X1673496Y18774D01*
G01X1668936Y18981D02*
X1673496Y19950D01*
G01Y18774D02*
X1678669Y17675D01*
G01X1673496Y19950D02*
X1678669Y18851D01*
G01Y17675D02*
X1683703Y18746D01*
G01X1678669Y18851D02*
X1683703Y19922D01*
G01Y18746D02*
X1687959Y17840D01*
G01X1683703Y19922D02*
X1687959Y19016D01*
G01Y17840D02*
X1692592Y18825D01*
G01X1687959Y19016D02*
X1692592Y20001D01*
G01Y18825D02*
X1698883Y17487D01*
G01X1692592Y20001D02*
X1698839Y18673D01*
G01X1698883Y17487D02*
X1703000Y18688D01*
G01X1698839Y18673D02*
X1702956Y19874D01*
G01X1703000Y18688D02*
X1707186Y17797D01*
G01X1702956Y19874D02*
X1707063Y19000D01*
G01X1707186Y17797D02*
X1731352Y28421D01*
G01X1707063Y19000D02*
X1731110Y29571D01*
G01X1731009Y25539D02*
X1707378Y15149D01*
G01X1730767Y26689D02*
X1707254Y16352D01*
G01X1707378Y15149D02*
X1703098Y16060D01*
G01X1707254Y16352D02*
X1703054Y17246D01*
G01X1703098Y16060D02*
X1698897Y14834D01*
G01X1703054Y17246D02*
X1698853Y16020D01*
G01X1698897Y14834D02*
X1692494Y16197D01*
G01X1698853Y16020D02*
X1692494Y17373D01*
G01Y16197D02*
X1687973Y15237D01*
G01X1692494Y17373D02*
X1687973Y16413D01*
G01Y15237D02*
X1683718Y16142D01*
G01X1687973Y16413D02*
X1683718Y17318D01*
G01Y16142D02*
X1678771Y15090D01*
G01X1683718Y17318D02*
X1678771Y16266D01*
G01Y15090D02*
X1673597Y16189D01*
G01X1678771Y16266D02*
X1673597Y17365D01*
G01Y16189D02*
X1669001Y15212D01*
G01X1673597Y17365D02*
X1669001Y16388D01*
G01Y15212D02*
X1664364Y16196D01*
G01X1669001Y16388D02*
X1664364Y17372D01*
G01Y16196D02*
X1659679Y15200D01*
G01X1664364Y17372D02*
X1659679Y16376D01*
G01Y15200D02*
X1655013Y16192D01*
G01X1659679Y16376D02*
X1655013Y17368D01*
G01Y16192D02*
X1653280Y15823D01*
G01X1655013Y17368D02*
X1652796Y16897D01*
G01X1653280Y15823D02*
X1652235Y15051D01*
G01X1652796Y16897D02*
X1651351Y15828D01*
G01X1654676Y30331D02*
X1659340Y29339D01*
G01X1654676Y29155D02*
X1659340Y28163D01*
G01Y29339D02*
X1664232Y30378D01*
G01X1659340Y28163D02*
X1664232Y29202D01*
G01Y30378D02*
X1668869Y29394D01*
G01X1664232Y29202D02*
X1668869Y28218D01*
G01Y29394D02*
X1673179Y30310D01*
G01X1668869Y28218D02*
X1673179Y29134D01*
G01Y30310D02*
X1678351Y29212D01*
G01X1673179Y29134D02*
X1678351Y28036D01*
G01Y29212D02*
X1683580Y30324D01*
G01X1678351Y28036D02*
X1683580Y29148D01*
G01Y30324D02*
X1687838Y29419D01*
G01X1683580Y29148D02*
X1687838Y28243D01*
G01Y29419D02*
X1692406Y30389D01*
G01X1687838Y28243D02*
X1692406Y29213D01*
G01Y30389D02*
X1698293Y29138D01*
G01X1692406Y29213D02*
X1698337Y27952D01*
G01X1698293Y29138D02*
X1702544Y30379D01*
G01X1698337Y27952D02*
X1702588Y29193D01*
G01X1702544Y30379D02*
X1706173Y29606D01*
G01X1702588Y29193D02*
X1706296Y28403D01*
G01X1706173Y29606D02*
X1716296Y34056D01*
G01X1706296Y28403D02*
X1716957Y33089D01*
G01X1654675Y27724D02*
X1659340Y26732D01*
G01X1654675Y26548D02*
X1659340Y25556D01*
G01Y26732D02*
X1664233Y27771D01*
G01X1659340Y25556D02*
X1664233Y26595D01*
G01Y27771D02*
X1668869Y26787D01*
G01X1664233Y26595D02*
X1668869Y25611D01*
G01Y26787D02*
X1673240Y27716D01*
G01X1668869Y25611D02*
X1673240Y26540D01*
G01Y27716D02*
X1678412Y26618D01*
G01X1673240Y26540D02*
X1678412Y25442D01*
G01Y26618D02*
X1683500Y27700D01*
G01X1678412Y25442D02*
X1683500Y26524D01*
G01Y27700D02*
X1687756Y26795D01*
G01X1683500Y26524D02*
X1687756Y25619D01*
G01Y26795D02*
X1692456Y27793D01*
G01X1687756Y25619D02*
X1692456Y26617D01*
G01Y27793D02*
X1698433Y26524D01*
G01X1692456Y26617D02*
X1698477Y25338D01*
G01X1698433Y26524D02*
X1702542Y27724D01*
G01X1698477Y25338D02*
X1702586Y26538D01*
G01X1702542Y27724D02*
X1706396Y26905D01*
G01X1702586Y26538D02*
X1706520Y25702D01*
G01X1706396Y26905D02*
X1727059Y35987D01*
G01X1706520Y25702D02*
X1727720Y35020D01*
G01X1654764Y25136D02*
X1659429Y24144D01*
G01X1654764Y23960D02*
X1659429Y22968D01*
G01Y24144D02*
X1664233Y25165D01*
G01X1659429Y22968D02*
X1664233Y23989D01*
G01Y25165D02*
X1668869Y24180D01*
G01X1664233Y23989D02*
X1668869Y23004D01*
G01Y24180D02*
X1673344Y25131D01*
G01X1668869Y23004D02*
X1673344Y23955D01*
G01Y25131D02*
X1678516Y24033D01*
G01X1673344Y23955D02*
X1678516Y22857D01*
G01Y24033D02*
X1683515Y25095D01*
G01X1678516Y22857D02*
X1683515Y23919D01*
G01Y25095D02*
X1687771Y24190D01*
G01X1683515Y23919D02*
X1687771Y23014D01*
G01Y24190D02*
X1692423Y25179D01*
G01X1687771Y23014D02*
X1692423Y24003D01*
G01Y25179D02*
X1698504Y23888D01*
G01X1692423Y24003D02*
X1698548Y22702D01*
G01X1698504Y23888D02*
X1702666Y25103D01*
G01X1698548Y22702D02*
X1702710Y23917D01*
G01X1702666Y25103D02*
X1706606Y24264D01*
G01X1702710Y23917D02*
X1706729Y23061D01*
G01X1706606Y24264D02*
X1730786Y34891D01*
G01X1706729Y23061D02*
X1731028Y33741D01*
G01X1654815Y22540D02*
X1659480Y21548D01*
G01X1654815Y21364D02*
X1659480Y20372D01*
G01Y21548D02*
X1664233Y22558D01*
G01X1659480Y20372D02*
X1664233Y21382D01*
G01Y22558D02*
X1668870Y21574D01*
G01X1664233Y21382D02*
X1668870Y20398D01*
G01Y21574D02*
X1673410Y22539D01*
G01X1668870Y20398D02*
X1673410Y21363D01*
G01Y22539D02*
X1678583Y21440D01*
G01X1673410Y21363D02*
X1678583Y20264D01*
G01Y21440D02*
X1683603Y22508D01*
G01X1678583Y20264D02*
X1683603Y21332D01*
G01Y22508D02*
X1687860Y21602D01*
G01X1683603Y21332D02*
X1687860Y20426D01*
G01Y21602D02*
X1692492Y22586D01*
G01X1687860Y20426D02*
X1692492Y21410D01*
G01Y22586D02*
X1698656Y21276D01*
G01X1692492Y21410D02*
X1698700Y20090D01*
G01X1698656Y21276D02*
X1702859Y22502D01*
G01X1698700Y20090D02*
X1702903Y21316D01*
G01X1702859Y22502D02*
X1706871Y21648D01*
G01X1702903Y21316D02*
X1706994Y20445D01*
G01X1706871Y21648D02*
X1730764Y32150D01*
G01X1706994Y20445D02*
X1731006Y31000D01*
G01X1654676Y32938D02*
X1659341Y31946D01*
G01X1654676Y31762D02*
X1659341Y30770D01*
G01Y31946D02*
X1664232Y32985D01*
G01X1659341Y30770D02*
X1664232Y31809D01*
G01Y32985D02*
X1668868Y32001D01*
G01X1664232Y31809D02*
X1668868Y30825D01*
G01Y32001D02*
X1673178Y32917D01*
G01X1668868Y30825D02*
X1673178Y31741D01*
G01Y32917D02*
X1678350Y31819D01*
G01X1673178Y31741D02*
X1678350Y30643D01*
G01Y31819D02*
X1683558Y32926D01*
G01X1678350Y30643D02*
X1683558Y31750D01*
G01Y32926D02*
X1687815Y32021D01*
G01X1683558Y31750D02*
X1687815Y30845D01*
G01Y32021D02*
X1692510Y33018D01*
G01X1687815Y30845D02*
X1692510Y31842D01*
G01Y33018D02*
X1698282Y31791D01*
G01X1692510Y31842D02*
X1698326Y30605D01*
G01X1698282Y31791D02*
X1702448Y33008D01*
G01X1698326Y30605D02*
X1702493Y31822D01*
G01X1702448Y33008D02*
X1703612Y32761D01*
G01X1702493Y31822D02*
X1703695Y31567D01*
G01X1703612Y32761D02*
X1708455Y34515D01*
G01X1703695Y31567D02*
X1709188Y33557D01*
G01X1654676Y29155D02*
X1659340Y28163D01*
G01X1654676Y30331D02*
X1659340Y29339D01*
G01Y28163D02*
X1664232Y29202D01*
G01X1659340Y29339D02*
X1664232Y30378D01*
G01Y29202D02*
X1668869Y28218D01*
G01X1664232Y30378D02*
X1668869Y29394D01*
G01Y28218D02*
X1673179Y29134D01*
G01X1668869Y29394D02*
X1673179Y30310D01*
G01Y29134D02*
X1678351Y28036D01*
G01X1673179Y30310D02*
X1678351Y29212D01*
G01Y28036D02*
X1683580Y29148D01*
G01X1678351Y29212D02*
X1683580Y30324D01*
G01Y29148D02*
X1687838Y28243D01*
G01X1683580Y30324D02*
X1687838Y29419D01*
G01Y28243D02*
X1692406Y29213D01*
G01X1687838Y29419D02*
X1692406Y30389D01*
G01Y29213D02*
X1698337Y27952D01*
G01X1692406Y30389D02*
X1698293Y29138D01*
G01X1698337Y27952D02*
X1702588Y29193D01*
G01X1698293Y29138D02*
X1702544Y30379D01*
G01X1702588Y29193D02*
X1706296Y28403D01*
G01X1702544Y30379D02*
X1706173Y29606D01*
G01X1706296Y28403D02*
X1716957Y33089D01*
G01X1706173Y29606D02*
X1716296Y34056D01*
G01X1654675Y26548D02*
X1659340Y25556D01*
G01X1654675Y27724D02*
X1659340Y26732D01*
G01Y25556D02*
X1664233Y26595D01*
G01X1659340Y26732D02*
X1664233Y27771D01*
G01Y26595D02*
X1668869Y25611D01*
G01X1664233Y27771D02*
X1668869Y26787D01*
G01Y25611D02*
X1673240Y26540D01*
G01X1668869Y26787D02*
X1673240Y27716D01*
G01Y26540D02*
X1678412Y25442D01*
G01X1673240Y27716D02*
X1678412Y26618D01*
G01Y25442D02*
X1683500Y26524D01*
G01X1678412Y26618D02*
X1683500Y27700D01*
G01Y26524D02*
X1687756Y25619D01*
G01X1683500Y27700D02*
X1687756Y26795D01*
G01Y25619D02*
X1692456Y26617D01*
G01X1687756Y26795D02*
X1692456Y27793D01*
G01Y26617D02*
X1698477Y25338D01*
G01X1692456Y27793D02*
X1698433Y26524D01*
G01X1698477Y25338D02*
X1702586Y26538D01*
G01X1698433Y26524D02*
X1702542Y27724D01*
G01X1702586Y26538D02*
X1706520Y25702D01*
G01X1702542Y27724D02*
X1706396Y26905D01*
G01X1706520Y25702D02*
X1727720Y35020D01*
G01X1706396Y26905D02*
X1727059Y35987D01*
G01X1654764Y23960D02*
X1659429Y22968D01*
G01X1654764Y25136D02*
X1659429Y24144D01*
G01Y22968D02*
X1664233Y23989D01*
G01X1659429Y24144D02*
X1664233Y25165D01*
G01Y23989D02*
X1668869Y23004D01*
G01X1664233Y25165D02*
X1668869Y24180D01*
G01Y23004D02*
X1673344Y23955D01*
G01X1668869Y24180D02*
X1673344Y25131D01*
G01Y23955D02*
X1678516Y22857D01*
G01X1673344Y25131D02*
X1678516Y24033D01*
G01Y22857D02*
X1683515Y23919D01*
G01X1678516Y24033D02*
X1683515Y25095D01*
G01Y23919D02*
X1687771Y23014D01*
G01X1683515Y25095D02*
X1687771Y24190D01*
G01Y23014D02*
X1692423Y24003D01*
G01X1687771Y24190D02*
X1692423Y25179D01*
G01Y24003D02*
X1698548Y22702D01*
G01X1692423Y25179D02*
X1698504Y23888D01*
G01X1698548Y22702D02*
X1702710Y23917D01*
G01X1698504Y23888D02*
X1702666Y25103D01*
G01X1702710Y23917D02*
X1706729Y23061D01*
G01X1702666Y25103D02*
X1706606Y24264D01*
G01X1706729Y23061D02*
X1731028Y33741D01*
G01X1706606Y24264D02*
X1730786Y34891D01*
G01X1654815Y21364D02*
X1659480Y20372D01*
G01X1654815Y22540D02*
X1659480Y21548D01*
G01Y20372D02*
X1664233Y21382D01*
G01X1659480Y21548D02*
X1664233Y22558D01*
G01Y21382D02*
X1668870Y20398D01*
G01X1664233Y22558D02*
X1668870Y21574D01*
G01Y20398D02*
X1673410Y21363D01*
G01X1668870Y21574D02*
X1673410Y22539D01*
G01Y21363D02*
X1678583Y20264D01*
G01X1673410Y22539D02*
X1678583Y21440D01*
G01Y20264D02*
X1683603Y21332D01*
G01X1678583Y21440D02*
X1683603Y22508D01*
G01Y21332D02*
X1687860Y20426D01*
G01X1683603Y22508D02*
X1687860Y21602D01*
G01Y20426D02*
X1692492Y21410D01*
G01X1687860Y21602D02*
X1692492Y22586D01*
G01Y21410D02*
X1698700Y20090D01*
G01X1692492Y22586D02*
X1698656Y21276D01*
G01X1698700Y20090D02*
X1702903Y21316D01*
G01X1698656Y21276D02*
X1702859Y22502D01*
G01X1702903Y21316D02*
X1706994Y20445D01*
G01X1702859Y22502D02*
X1706871Y21648D01*
G01X1706994Y20445D02*
X1731006Y31000D01*
G01X1706871Y21648D02*
X1730764Y32150D01*
G01X1654676Y31762D02*
X1659341Y30770D01*
G01X1654676Y32938D02*
X1659341Y31946D01*
G01Y30770D02*
X1664232Y31809D01*
G01X1659341Y31946D02*
X1664232Y32985D01*
G01Y31809D02*
X1668868Y30825D01*
G01X1664232Y32985D02*
X1668868Y32001D01*
G01Y30825D02*
X1673178Y31741D01*
G01X1668868Y32001D02*
X1673178Y32917D01*
G01Y31741D02*
X1678350Y30643D01*
G01X1673178Y32917D02*
X1678350Y31819D01*
G01Y30643D02*
X1683558Y31750D01*
G01X1678350Y31819D02*
X1683558Y32926D01*
G01Y31750D02*
X1687815Y30845D01*
G01X1683558Y32926D02*
X1687815Y32021D01*
G01Y30845D02*
X1692510Y31842D01*
G01X1687815Y32021D02*
X1692510Y33018D01*
G01Y31842D02*
X1698326Y30605D01*
G01X1692510Y33018D02*
X1698282Y31791D01*
G01X1698326Y30605D02*
X1702493Y31822D01*
G01X1698282Y31791D02*
X1702448Y33008D01*
G01X1702493Y31822D02*
X1703695Y31567D01*
G01X1702448Y33008D02*
X1703612Y32761D01*
G01X1703695Y31567D02*
X1709188Y33557D01*
G01X1703612Y32761D02*
X1708455Y34515D01*
G01X1696922Y10618D02*
Y8551D01*
G01X1698072Y10618D02*
Y9028D01*
G01X1696922Y8551D02*
X1705348Y125D01*
G01X1698072Y9028D02*
X1705825Y1275D01*
G01X1705348Y125D02*
X1765416D01*
G01X1705825Y1275D02*
X1765174D01*
G01X1764827Y2652D02*
X1710521D01*
G01X1764827D02*
X1710521D01*
G01X1712348Y3802D02*
X1710998D01*
G01X1710521Y2652D02*
X1706648Y6525D01*
G01X1710998Y3802D02*
X1707798Y7002D01*
G01X1706648Y6525D02*
Y10788D01*
G01X1707798Y7002D02*
Y10738D01*
G01X1698072Y10618D02*
Y9028D01*
G01X1696922Y10618D02*
Y8551D01*
G01X1698072Y9028D02*
X1705825Y1275D01*
G01X1696922Y8551D02*
X1705348Y125D01*
G01X1705825Y1275D02*
X1765174D01*
G01X1705348Y125D02*
X1765416D01*
G01X1712348Y3802D02*
X1710998D01*
G01X1764827Y2652D02*
X1710521D01*
G01X1710998Y3802D02*
X1707798Y7002D01*
G01X1710521Y2652D02*
X1706648Y6525D01*
G01X1707798Y7002D02*
Y10738D01*
G01X1706648Y6525D02*
Y10788D01*
G01X1708455Y34515D02*
X1709850Y36505D01*
G01X1709188Y33557D02*
X1711000Y36142D01*
G01X1709850Y36505D02*
Y38649D01*
G01X1711000Y36142D02*
Y38800D01*
G01X1709188Y33557D02*
X1711000Y36142D01*
G01X1708455Y34515D02*
X1709850Y36505D01*
G01X1711000Y36142D02*
Y38800D01*
G01X1709850Y36505D02*
Y38649D01*
G01X1659341Y34553D02*
X1654676Y35545D01*
G01Y34369D02*
X1659341Y33377D01*
G01X1664232Y35592D02*
X1659341Y34553D01*
G01Y33377D02*
X1664232Y34416D01*
G01X1668868Y34608D02*
X1664232Y35592D01*
G01Y34416D02*
X1668868Y33432D01*
G01X1673178Y35524D02*
X1668868Y34608D01*
G01Y33432D02*
X1673178Y34348D01*
G01X1678350Y34426D02*
X1673178Y35524D01*
G01Y34348D02*
X1678350Y33250D01*
G01X1683457Y35511D02*
X1678350Y34426D01*
G01Y33250D02*
X1683457Y34335D01*
G01X1687714Y34606D02*
X1683457Y35511D01*
G01Y34335D02*
X1687714Y33430D01*
G01X1692421Y35606D02*
X1687714Y34606D01*
G01Y33430D02*
X1692421Y34430D01*
G01X1698109Y34398D02*
X1692421Y35606D01*
G01Y34430D02*
X1698153Y33212D01*
G01X1700115Y34984D02*
X1700114D01*
G01D02*
X1698109Y34398D01*
G01X1698153Y33212D02*
X1700720Y33962D01*
G01X1700650Y35519D02*
X1700115Y34984D01*
G01X1700720Y33962D02*
X1701800Y35042D01*
G01X1700650Y38850D02*
Y35519D01*
G01X1701800Y35042D02*
Y39100D01*
G01Y35042D02*
Y39100D01*
G01X1700650Y38850D02*
Y35519D01*
G01X1700720Y33962D02*
X1701800Y35042D01*
G01X1700650Y35519D02*
X1700115Y34984D01*
G01X1698153Y33212D02*
X1700720Y33962D01*
G01X1700115Y34984D02*
X1700114D01*
G01X1698153Y33212D02*
X1700720Y33962D01*
G01X1700114Y34984D02*
X1698109Y34398D01*
G01X1692421Y34430D02*
X1698153Y33212D01*
G01X1698109Y34398D02*
X1692421Y35606D01*
G01X1687714Y33430D02*
X1692421Y34430D01*
G01Y35606D02*
X1687714Y34606D01*
G01X1683457Y34335D02*
X1687714Y33430D01*
G01Y34606D02*
X1683457Y35511D01*
G01X1678350Y33250D02*
X1683457Y34335D01*
G01Y35511D02*
X1678350Y34426D01*
G01X1673178Y34348D02*
X1678350Y33250D01*
G01Y34426D02*
X1673178Y35524D01*
G01X1668868Y33432D02*
X1673178Y34348D01*
G01Y35524D02*
X1668868Y34608D01*
G01X1664232Y34416D02*
X1668868Y33432D01*
G01Y34608D02*
X1664232Y35592D01*
G01X1659341Y33377D02*
X1664232Y34416D01*
G01Y35592D02*
X1659341Y34553D01*
G01X1654676Y34369D02*
X1659341Y33377D01*
G01Y34553D02*
X1654676Y35545D01*
G01X1657780Y42240D02*
X1651889Y43495D01*
G01Y42319D02*
X1657780Y41064D01*
G01X1666133Y44017D02*
X1657780Y42240D01*
G01Y41064D02*
X1666133Y42841D01*
G01X1672580Y42646D02*
X1666133Y44017D01*
G01Y42841D02*
X1672574Y41471D01*
G01X1674459Y43028D02*
X1674230Y42982D01*
G01Y42981D02*
X1672580Y42646D01*
G01X1672574Y41471D02*
X1674459Y41854D01*
G01X1678134Y42280D02*
X1674459Y43028D01*
G01Y41854D02*
X1677905Y41153D01*
G01X1678134Y42280D02*
X1674459Y43028D01*
G01X1677905Y41152D02*
X1678134Y41106D01*
G01X1682458Y43160D02*
X1678134Y42280D01*
G01Y41106D02*
X1682907Y42077D01*
G01X1684013Y44189D02*
X1682458Y43160D01*
G01X1682907Y42077D02*
X1684462Y43106D01*
G01X1687222Y44842D02*
X1684013Y44189D01*
G01X1684462Y43106D02*
X1687222Y43668D01*
G01X1697338Y42783D02*
X1687222Y44842D01*
G01Y43668D02*
X1697338Y41609D01*
G01X1705926Y44528D02*
X1697338Y42783D01*
G01Y41609D02*
X1705945Y43357D01*
G01X1713864Y42867D02*
X1705954Y44547D01*
G01Y43371D02*
X1713864Y41691D01*
G01X1705954Y43371D02*
X1713864Y41691D01*
G01Y42867D02*
X1705954Y44547D01*
G01X1697338Y41609D02*
X1705945Y43357D01*
G01X1705926Y44528D02*
X1697338Y42783D01*
G01X1687222Y43668D02*
X1697338Y41609D01*
G01Y42783D02*
X1687222Y44842D01*
G01X1684462Y43106D02*
X1687222Y43668D01*
G01Y44842D02*
X1684013Y44189D01*
G01X1682907Y42077D02*
X1684462Y43106D01*
G01X1684013Y44189D02*
X1682458Y43160D01*
G01X1678134Y41106D02*
X1682907Y42077D01*
G01X1682458Y43160D02*
X1678134Y42280D01*
G01X1674459Y41854D02*
X1677905Y41153D01*
G01Y41152D02*
X1678134Y41106D01*
G01Y42280D02*
X1674459Y43028D01*
G01X1672574Y41471D02*
X1674459Y41854D01*
G01Y43028D02*
X1674230Y42982D01*
G01X1672574Y41471D02*
X1674459Y41854D01*
G01X1674230Y42981D02*
X1672580Y42646D01*
G01X1666133Y42841D02*
X1672574Y41471D01*
G01X1672580Y42646D02*
X1666133Y44017D01*
G01X1657780Y41064D02*
X1666133Y42841D01*
G01Y44017D02*
X1657780Y42240D01*
G01X1651889Y42319D02*
X1657780Y41064D01*
G01Y42240D02*
X1651889Y43495D01*
G01X1692096Y54821D02*
X1729553Y62317D01*
G01X1730003Y61233D02*
X1692094Y53647D01*
G01X1688158Y55622D02*
X1692096Y54821D01*
G01X1692094Y53647D02*
X1688158Y54448D01*
G01X1682761Y54525D02*
X1688158Y55622D01*
G01Y54448D02*
X1683210Y53442D01*
G01X1680128Y52782D02*
X1682761Y54525D01*
G01X1683210Y53442D02*
X1680576Y51698D01*
G01X1679302Y52616D02*
X1680128Y52782D01*
G01X1680576Y51698D02*
X1679301Y51442D01*
G01X1675848Y53317D02*
X1679302Y52616D01*
G01X1679301Y51442D02*
X1675400Y52234D01*
G01X1673657Y54765D02*
X1675848Y53317D01*
G01X1675400Y52234D02*
X1673209Y53682D01*
G01X1669800Y55549D02*
X1673657Y54765D01*
G01X1673209Y53682D02*
X1669804Y54374D01*
G01X1659289Y50753D02*
X1672381Y48044D01*
G01X1659292Y49577D02*
X1660259Y49376D01*
G01X1659289Y50753D02*
X1672381Y48044D01*
G01X1660262Y49376D02*
X1672379Y46870D01*
G01X1672381Y48044D02*
X1673988Y48370D01*
G01X1672382Y46870D02*
X1673988Y47196D01*
G01Y48370D02*
X1674217Y48324D01*
G01Y48323D02*
X1678093Y47536D01*
G01X1673988Y47196D02*
X1678094Y46362D01*
G01X1678093Y47536D02*
X1679818Y47888D01*
G01D02*
X1679817D01*
G01X1678094Y46362D02*
X1680268Y46806D01*
G01X1679818Y47888D02*
X1679817D01*
G01Y47889D02*
X1680454Y48313D01*
G01X1680268Y46806D02*
X1681286Y47484D01*
G01X1680454Y48313D02*
X1681743Y50259D01*
G01X1681286Y47484D02*
X1682573Y49429D01*
G01X1681743Y50259D02*
X1683990Y51746D01*
G01X1682573Y49429D02*
X1684439Y50664D01*
G01X1683990Y51746D02*
X1685706Y52098D01*
G01X1684439Y50664D02*
X1685707Y50924D01*
G01X1685706Y52098D02*
X1687968Y51639D01*
G01X1685707Y50924D02*
X1687520Y50556D01*
G01X1687968Y51639D02*
X1690899Y49701D01*
G01X1687520Y50556D02*
X1690450Y48618D01*
G01X1690899Y49701D02*
X1691668Y49544D01*
G01X1690450Y48618D02*
X1691668Y48370D01*
G01Y49544D02*
X1714869Y54229D01*
G01X1691668Y48370D02*
X1715318Y53146D01*
G01X1659116Y48136D02*
X1672466Y45295D01*
G01X1659116Y46960D02*
X1672461Y44120D01*
G01X1672466Y45295D02*
X1674226Y45654D01*
G01X1672461Y44120D02*
X1674226Y44480D01*
G01Y45654D02*
X1678032Y44880D01*
G01X1674226Y44480D02*
X1678032Y43706D01*
G01Y44880D02*
X1681421Y45572D01*
G01X1678032Y43706D02*
X1681870Y44489D01*
G01X1681421Y45572D02*
X1682897Y46549D01*
G01X1681870Y44489D02*
X1683346Y45466D01*
G01X1682897Y46549D02*
X1687802Y47546D01*
G01X1683346Y45466D02*
X1687802Y46372D01*
G01Y47546D02*
X1697603Y45553D01*
G01X1687802Y46372D02*
X1697602Y44379D01*
G01X1697603Y45553D02*
X1701515Y46342D01*
G01X1697602Y44379D02*
X1701962Y45258D01*
G01X1701515Y46342D02*
X1703404Y47589D01*
G01X1701962Y45258D02*
X1703852Y46506D01*
G01X1703404Y47589D02*
X1718430Y50649D01*
G01X1703852Y46506D02*
X1718430Y49475D01*
G01X1673209Y53682D02*
X1669804Y54374D01*
G01X1669800Y55549D02*
X1673657Y54765D01*
G01X1675400Y52234D02*
X1673209Y53682D01*
G01X1673657Y54765D02*
X1675848Y53317D01*
G01X1679301Y51442D02*
X1675400Y52234D01*
G01X1675848Y53317D02*
X1679302Y52616D01*
G01X1680576Y51698D02*
X1679301Y51442D01*
G01X1679302Y52616D02*
X1680128Y52782D01*
G01X1683210Y53442D02*
X1680576Y51698D01*
G01X1680128Y52782D02*
X1682761Y54525D01*
G01X1688158Y54448D02*
X1683210Y53442D01*
G01X1682761Y54525D02*
X1688158Y55622D01*
G01X1692094Y53647D02*
X1688158Y54448D01*
G01Y55622D02*
X1692096Y54821D01*
G01X1730003Y61233D02*
X1692094Y53647D01*
G01X1692096Y54821D02*
X1729553Y62317D01*
G01X1659292Y49577D02*
X1660259Y49376D01*
G01X1660262D02*
X1672379Y46870D01*
G01X1659289Y50753D02*
X1672381Y48044D01*
G01X1672382Y46870D02*
X1673988Y47196D01*
G01X1672381Y48044D02*
X1673988Y48370D01*
G01Y47196D02*
X1678094Y46362D01*
G01X1673988Y48370D02*
X1674217Y48324D01*
G01X1673988Y47196D02*
X1678094Y46362D01*
G01X1674217Y48323D02*
X1678093Y47536D01*
G01X1678094Y46362D02*
X1680268Y46806D01*
G01X1678093Y47536D02*
X1679818Y47888D01*
G01X1678094Y46362D02*
X1680268Y46806D01*
G01D02*
X1681286Y47484D01*
G01X1679818Y47888D02*
X1679817D01*
G01X1680268Y46806D02*
X1681286Y47484D01*
G01X1679817Y47889D02*
X1680454Y48313D01*
G01X1681286Y47484D02*
X1682573Y49429D01*
G01X1680454Y48313D02*
X1681743Y50259D01*
G01X1682573Y49429D02*
X1684439Y50664D01*
G01X1681743Y50259D02*
X1683990Y51746D01*
G01X1684439Y50664D02*
X1685707Y50924D01*
G01X1683990Y51746D02*
X1685706Y52098D01*
G01X1685707Y50924D02*
X1687520Y50556D01*
G01X1685706Y52098D02*
X1687968Y51639D01*
G01X1687520Y50556D02*
X1690450Y48618D01*
G01X1687968Y51639D02*
X1690899Y49701D01*
G01X1690450Y48618D02*
X1691668Y48370D01*
G01X1690899Y49701D02*
X1691668Y49544D01*
G01Y48370D02*
X1715318Y53146D01*
G01X1691668Y49544D02*
X1714869Y54229D01*
G01X1659116Y46960D02*
X1672461Y44120D01*
G01X1659116Y48136D02*
X1672466Y45295D01*
G01X1672461Y44120D02*
X1674226Y44480D01*
G01X1672466Y45295D02*
X1674226Y45654D01*
G01Y44480D02*
X1678032Y43706D01*
G01X1674226Y45654D02*
X1678032Y44880D01*
G01Y43706D02*
X1681870Y44489D01*
G01X1678032Y44880D02*
X1681421Y45572D01*
G01X1681870Y44489D02*
X1683346Y45466D01*
G01X1681421Y45572D02*
X1682897Y46549D01*
G01X1683346Y45466D02*
X1687802Y46372D01*
G01X1682897Y46549D02*
X1687802Y47546D01*
G01Y46372D02*
X1697602Y44379D01*
G01X1687802Y47546D02*
X1697603Y45553D01*
G01X1697602Y44379D02*
X1701962Y45258D01*
G01X1697603Y45553D02*
X1701515Y46342D01*
G01X1701962Y45258D02*
X1703852Y46506D01*
G01X1701515Y46342D02*
X1703404Y47589D01*
G01X1703852Y46506D02*
X1718430Y49475D01*
G01X1703404Y47589D02*
X1718430Y50649D01*
G01X1669854Y61322D02*
X1673436Y60603D01*
G01X1669861Y60147D02*
X1673435Y59430D01*
G01X1673436Y60603D02*
X1685118Y62935D01*
G01X1673435Y59430D02*
X1685118Y61762D01*
G01Y62935D02*
X1689467Y62063D01*
G01X1685118Y61762D02*
X1689469Y60889D01*
G01X1689467Y62063D02*
X1702001Y64614D01*
G01X1689469Y60889D02*
X1702450Y63531D01*
G01X1702001Y64614D02*
X1702805Y65146D01*
G01X1702450Y63531D02*
X1703254Y64063D01*
G01X1702805Y65146D02*
X1716966Y68028D01*
G01X1703254Y64063D02*
X1716966Y66854D01*
G01X1672581Y57884D02*
X1669409Y58521D01*
G01X1669415Y57346D02*
X1672577Y56711D01*
G01X1683350Y59961D02*
X1672581Y57884D01*
G01X1672577Y56711D02*
X1683346Y58789D01*
G01X1687689Y59093D02*
X1683350Y59961D01*
G01X1683346Y58789D02*
X1687690Y57919D01*
G01X1715228Y64669D02*
X1687689Y59093D01*
G01X1687690Y57919D02*
X1703467Y61113D01*
G01X1715228Y64669D02*
X1687689Y59093D01*
G01X1706064Y61639D02*
X1707387Y61907D01*
G01X1715228Y64669D02*
X1687689Y59093D01*
G01X1709984Y62433D02*
X1711307Y62701D01*
G01X1715228Y64669D02*
X1687689Y59093D01*
G01X1742721Y83917D02*
X1710556Y75357D01*
G01X1742756Y82736D02*
X1711272Y74356D01*
G01X1742721Y83917D02*
X1710556Y75357D01*
G01X1711272Y74357D02*
X1711271D01*
G01X1710556Y75357D02*
X1709007Y73043D01*
G01X1711271Y74357D02*
X1709699Y72008D01*
G01X1709007Y73043D02*
X1700828Y71404D01*
G01X1709699Y72008D02*
X1700826Y70230D01*
G01X1700828Y71404D02*
X1699008Y71774D01*
G01X1700826Y70230D02*
X1699008Y70600D01*
G01Y71774D02*
X1690424Y70029D01*
G01X1699008Y70600D02*
X1690426Y68855D01*
G01X1690424Y70029D02*
X1686773Y70759D01*
G01X1690426Y68855D02*
X1686779Y69585D01*
G01X1687238Y68055D02*
X1690374Y67388D01*
G01X1687236Y66879D02*
X1690369Y66213D01*
G01X1690374Y67388D02*
X1698036Y68946D01*
G01X1690369Y66213D02*
X1698036Y67772D01*
G01Y68946D02*
X1702748Y67985D01*
G01X1698036Y67772D02*
X1702748Y66811D01*
G01Y67985D02*
X1710155Y69492D01*
G01X1702748Y66811D02*
X1710900Y68469D01*
G01X1710155Y69492D02*
X1712053Y72859D01*
G01X1710900Y68469D02*
X1712807Y71854D01*
G01X1712053Y72859D02*
X1715151Y73583D01*
G01X1669861Y60147D02*
X1673435Y59430D01*
G01X1669854Y61322D02*
X1673436Y60603D01*
G01X1673435Y59430D02*
X1685118Y61762D01*
G01X1673436Y60603D02*
X1685118Y62935D01*
G01Y61762D02*
X1689469Y60889D01*
G01X1685118Y62935D02*
X1689467Y62063D01*
G01X1689469Y60889D02*
X1702450Y63531D01*
G01X1689467Y62063D02*
X1702001Y64614D01*
G01X1702450Y63531D02*
X1703254Y64063D01*
G01X1702001Y64614D02*
X1702805Y65146D01*
G01X1703254Y64063D02*
X1716966Y66854D01*
G01X1702805Y65146D02*
X1716966Y68028D01*
G01X1687690Y57919D02*
X1703467Y61113D01*
G01X1706064Y61639D02*
X1707387Y61907D01*
G01X1709984Y62433D02*
X1711307Y62701D01*
G01X1715228Y64669D02*
X1687689Y59093D01*
G01X1683346Y58789D02*
X1687690Y57919D01*
G01X1687689Y59093D02*
X1683350Y59961D01*
G01X1672577Y56711D02*
X1683346Y58789D01*
G01X1683350Y59961D02*
X1672581Y57884D01*
G01X1669415Y57346D02*
X1672577Y56711D01*
G01X1672581Y57884D02*
X1669409Y58521D01*
G01X1742756Y82736D02*
X1711272Y74356D01*
G01Y74357D02*
X1711271D01*
G01X1742721Y83917D02*
X1710556Y75357D01*
G01X1711271Y74357D02*
X1709699Y72008D01*
G01X1710556Y75357D02*
X1709007Y73043D01*
G01X1709699Y72008D02*
X1700826Y70230D01*
G01X1709007Y73043D02*
X1700828Y71404D01*
G01X1700826Y70230D02*
X1699008Y70600D01*
G01X1700828Y71404D02*
X1699008Y71774D01*
G01Y70600D02*
X1690426Y68855D01*
G01X1699008Y71774D02*
X1690424Y70029D01*
G01X1690426Y68855D02*
X1686779Y69585D01*
G01X1690424Y70029D02*
X1686773Y70759D01*
G01X1687236Y66879D02*
X1690369Y66213D01*
G01X1687238Y68055D02*
X1690374Y67388D01*
G01X1690369Y66213D02*
X1698036Y67772D01*
G01X1690374Y67388D02*
X1698036Y68946D01*
G01Y67772D02*
X1702748Y66811D01*
G01X1698036Y68946D02*
X1702748Y67985D01*
G01Y66811D02*
X1710900Y68469D01*
G01X1702748Y67985D02*
X1710155Y69492D01*
G01X1710900Y68469D02*
X1712807Y71854D01*
G01X1710155Y69492D02*
X1712053Y72859D01*
G01D02*
X1715151Y73583D01*
G01X1831043Y256165D02*
X1678738D01*
G01X1831520Y257315D02*
X1679215D01*
G01X1678738Y256165D02*
X1666680Y268223D01*
G01X1679215Y257315D02*
X1667830Y268700D01*
G01X1666680Y268223D02*
Y301411D01*
G01X1667830Y268700D02*
Y301234D01*
G01X1831520Y257315D02*
X1679215D01*
G01X1831043Y256165D02*
X1678738D01*
G01X1679215Y257315D02*
X1667830Y268700D01*
G01X1678738Y256165D02*
X1666680Y268223D01*
G01X1667830Y268700D02*
Y301234D01*
G01X1666680Y268223D02*
Y301411D01*
G01X1852362Y261015D02*
X1680749D01*
G01X1851885Y259865D02*
X1680272D01*
G01X1680749Y261015D02*
X1671530Y270234D01*
G01X1680272Y259865D02*
X1670380Y269757D01*
G01X1671530Y270234D02*
Y299819D01*
G01X1670380Y269757D02*
Y299997D01*
G01X1851885Y259865D02*
X1680272D01*
G01X1852362Y261015D02*
X1680749D01*
G01X1680272Y259865D02*
X1670380Y269757D01*
G01X1680749Y261015D02*
X1671530Y270234D01*
G01X1670380Y269757D02*
Y299997D01*
G01X1671530Y270234D02*
Y299819D01*
G01X1666680Y301411D02*
X1669205Y309429D01*
G01X1667830Y301234D02*
X1670398Y309386D01*
G01X1669205Y309430D02*
X1666778Y319690D01*
G01X1670398Y309386D02*
X1667971Y319646D01*
G01X1666778Y319690D02*
X1669431Y328108D01*
G01X1667971Y319646D02*
X1670624Y328064D01*
G01X1669431Y328108D02*
X1667475Y336378D01*
G01X1670624Y328064D02*
X1668668Y336334D01*
G01X1667475Y336378D02*
X1670140Y344835D01*
G01X1668668Y336334D02*
X1671333Y344791D01*
G01X1667830Y301234D02*
X1670398Y309386D01*
G01X1666680Y301411D02*
X1669205Y309429D01*
G01X1670398Y309386D02*
X1667971Y319646D01*
G01X1669205Y309430D02*
X1666778Y319690D01*
G01X1667971Y319646D02*
X1670624Y328064D01*
G01X1666778Y319690D02*
X1669431Y328108D01*
G01X1670624Y328064D02*
X1668668Y336334D01*
G01X1669431Y328108D02*
X1667475Y336378D01*
G01X1668668Y336334D02*
X1671333Y344791D01*
G01X1667475Y336378D02*
X1670140Y344835D01*
G01X1671530Y299819D02*
X1674351Y308760D01*
G01X1670380Y299997D02*
X1673158Y308804D01*
G01X1674351Y308760D02*
X1672777Y315410D01*
G01X1673158Y308804D02*
X1671627Y315275D01*
G01X1672777Y315412D02*
X1671861Y319283D01*
G01X1671627Y315277D02*
X1670668Y319327D01*
G01X1671861Y319283D02*
X1674627Y328053D01*
G01X1670668Y319327D02*
X1673434Y328097D01*
G01X1674627Y328053D02*
X1672616Y336548D01*
G01X1673434Y328097D02*
X1671423Y336592D01*
G01X1672616Y336548D02*
X1675170Y344650D01*
G01X1671423Y336592D02*
X1673977Y344694D01*
G01X1670380Y299997D02*
X1673158Y308804D01*
G01X1671530Y299819D02*
X1674351Y308760D01*
G01X1673158Y308804D02*
X1671627Y315275D01*
G01X1674351Y308760D02*
X1672777Y315410D01*
G01X1671627Y315277D02*
X1670668Y319327D01*
G01X1672777Y315412D02*
X1671861Y319283D01*
G01X1670668Y319327D02*
X1673434Y328097D01*
G01X1671861Y319283D02*
X1674627Y328053D01*
G01X1673434Y328097D02*
X1671423Y336592D01*
G01X1674627Y328053D02*
X1672616Y336548D01*
G01X1671423Y336592D02*
X1673977Y344694D01*
G01X1672616Y336548D02*
X1675170Y344650D01*
G01X1670140Y344835D02*
X1669679Y346784D01*
G01D02*
X1669448Y347758D01*
G01D02*
X1669218Y348732D01*
G01X1669216D02*
X1668150Y353244D01*
G01X1671333Y344791D02*
X1669343Y353200D01*
G01X1668150Y353244D02*
X1671498Y363868D01*
G01X1669343Y353200D02*
X1672691Y363824D01*
G01X1671498Y363868D02*
X1667683Y379993D01*
G01X1672691Y363824D02*
X1668697Y380705D01*
G01X1667683Y379993D02*
X1665967Y381115D01*
G01X1668697Y380705D02*
X1666310Y382265D01*
G01X1665967Y381115D02*
X1658645D01*
G01X1666310Y382265D02*
X1658980D01*
G01X1671333Y344791D02*
X1669343Y353200D01*
G01X1670140Y344835D02*
X1669679Y346784D01*
G01X1671333Y344791D02*
X1669343Y353200D01*
G01X1669679Y346784D02*
X1669448Y347758D01*
G01X1671333Y344791D02*
X1669343Y353200D01*
G01X1669448Y347758D02*
X1669218Y348732D01*
G01X1671333Y344791D02*
X1669343Y353200D01*
G01X1669216Y348732D02*
X1668150Y353244D01*
G01X1669343Y353200D02*
X1672691Y363824D01*
G01X1668150Y353244D02*
X1671498Y363868D01*
G01X1672691Y363824D02*
X1668697Y380705D01*
G01X1671498Y363868D02*
X1667683Y379993D01*
G01X1668697Y380705D02*
X1666310Y382265D01*
G01X1667683Y379993D02*
X1665967Y381115D01*
G01X1666310Y382265D02*
X1658980D01*
G01X1665967Y381115D02*
X1658645D01*
G01X1675170Y344650D02*
X1673212Y352923D01*
G01X1673977Y344694D02*
X1672019Y352967D01*
G01X1673212Y352923D02*
X1676624Y363745D01*
G01X1672019Y352967D02*
X1675431Y363789D01*
G01X1676624Y363745D02*
X1672016Y383211D01*
G01X1675431Y363789D02*
X1671002Y382499D01*
G01X1672016Y383211D02*
X1667793Y385973D01*
G01X1671002Y382499D02*
X1667450Y384823D01*
G01X1667793Y385973D02*
X1660375D01*
G01X1667450Y384823D02*
X1660040D01*
G01X1660375Y385973D02*
X1650592Y392182D01*
G01X1673977Y344694D02*
X1672019Y352967D01*
G01X1675170Y344650D02*
X1673212Y352923D01*
G01X1672019Y352967D02*
X1675431Y363789D01*
G01X1673212Y352923D02*
X1676624Y363745D01*
G01X1675431Y363789D02*
X1671002Y382499D01*
G01X1676624Y363745D02*
X1672016Y383211D01*
G01X1671002Y382499D02*
X1667450Y384823D01*
G01X1672016Y383211D02*
X1667793Y385973D01*
G01X1667450Y384823D02*
X1660040D01*
G01X1667793Y385973D02*
X1660375D01*
G01D02*
X1650592Y392182D01*
G01X1653183Y439707D02*
X1651661Y444513D01*
G01X1654390Y439708D02*
X1652867Y444517D01*
G01X1651661Y444513D02*
X1652958Y448713D01*
G01X1652867Y444517D02*
X1654163Y448716D01*
G01X1652958Y448713D02*
X1651346Y453831D01*
G01X1654163Y448716D02*
X1652399Y454317D01*
G01X1654390Y439708D02*
X1652867Y444517D01*
G01X1653183Y439707D02*
X1651661Y444513D01*
G01X1652867Y444517D02*
X1654163Y448716D01*
G01X1651661Y444513D02*
X1652958Y448713D01*
G01X1654163Y448716D02*
X1652399Y454317D01*
G01X1652958Y448713D02*
X1651346Y453831D01*
G01X1658292Y439769D02*
X1656962Y443959D01*
G01X1657085Y439768D02*
X1655756Y443954D01*
G01X1656962Y443959D02*
X1658359Y448482D01*
G01X1655756Y443954D02*
X1657154Y448479D01*
G01X1658359Y448482D02*
X1655999Y455978D01*
G01X1657154Y448479D02*
X1654946Y455492D01*
G01D02*
X1652215Y459852D01*
G01X1657085Y439768D02*
X1655756Y443954D01*
G01X1658292Y439769D02*
X1656962Y443959D01*
G01X1655756Y443954D02*
X1657154Y448479D01*
G01X1656962Y443959D02*
X1658359Y448482D01*
G01X1657154Y448479D02*
X1654946Y455492D01*
G01X1658359Y448482D02*
X1655999Y455978D01*
G01X1654946Y455492D02*
X1652215Y459852D01*
G01X1662199Y588083D02*
X1663264D01*
G01D02*
G02X1663950Y587397I0J-686D01*
G01X1663264Y589233D02*
G02X1665100Y587397I0J-1836D01*
G01X1663950D02*
Y581887D01*
G01X1665100Y587397D02*
Y581886D01*
G01X1663950Y581887D02*
G03X1665336Y578537I4735J-3D01*
G01X1665100Y581886D02*
G03X1666150Y579351I3585J0D01*
G01X1665336Y578537D02*
X1668736Y575137D01*
G01X1666150Y579351D02*
X1669550Y575951D01*
G01X1668736Y575137D02*
G03X1673173Y573300I4437J4439D01*
G01X1669550Y575951D02*
G03X1673172Y574450I3624J3625D01*
G01X1673173Y573300D02*
X1689763D01*
G01X1673172Y574450D02*
X1689764D01*
G01X1689763Y573300D02*
G02X1693242Y571858I-1J-4920D01*
G01X1689764Y574450D02*
G02X1694056Y572672I0J-6070D01*
G01X1693242Y571858D02*
X1695383Y569717D01*
G01X1694056Y572672D02*
X1696197Y570531D01*
G01X1695383Y569717D02*
G02X1696300Y567503I-2215J-2214D01*
G01X1696197Y570531D02*
G02X1697450Y567504I-3030J-3027D01*
G01X1696300Y567503D02*
Y564413D01*
G01X1697450Y567504D02*
Y564413D01*
G01X1696300D02*
G02X1693687Y561800I-2613J0D01*
G01X1697450Y564413D02*
G02X1693687Y560650I-3763J0D01*
G01Y561800D02*
X1667891D01*
G01X1693687Y560650D02*
X1667891D01*
G01Y561800D02*
G03X1664937Y560577I-2J-4175D01*
G01X1667891Y560650D02*
G03X1665751Y559764I-1J-3025D01*
G01X1664937Y560577D02*
X1662447Y558088D01*
G01X1665751Y559764D02*
X1663261Y557274D01*
G01X1662447Y558088D02*
G02X1660069Y557103I-2379J2380D01*
G01X1663261Y557274D02*
G02X1660070Y555953I-3191J3194D01*
G01X1660069Y557103D02*
X1658234D01*
G01X1660070Y555953D02*
X1658234D01*
G01Y557103D02*
G03X1654567Y555585I-1J-5185D01*
G01X1658234Y555953D02*
G03X1655381Y554771I0J-4034D01*
G01X1655858Y590011D02*
G02X1653683Y587836I-2175J0D01*
G01D02*
X1652162D01*
G01D02*
G03Y585786I0J-1025D01*
G01D02*
X1653683D01*
G01X1652162Y584636D02*
X1653683D01*
G01Y585786D02*
G02X1655858Y583611I0J-2175D01*
G01X1653683Y584636D02*
G02X1654708Y583611I0J-1025D01*
G01X1655858D02*
Y576100D01*
G01X1654708Y583611D02*
Y576099D01*
G01X1655858Y576100D02*
G02X1654708Y573334I-3901J0D01*
G01X1654707Y576100D02*
G02X1653896Y574150I-2750J0D01*
G01X1654672Y573299D02*
X1652186Y570813D01*
G01X1653896Y574150D02*
X1653858Y574112D01*
G01X1654708Y573334D02*
X1654690Y573316D01*
G01X1654672Y573299D02*
X1652186Y570813D01*
G01X1653858Y574113D02*
X1651372Y571627D01*
G01X1652186Y570813D02*
G03X1651407Y568932I1881J-1881D01*
G01D02*
Y562246D01*
G01X1657808Y593710D02*
Y582136D01*
G01X1658958Y593710D02*
Y582137D01*
G01X1657808Y582136D02*
G03X1659769Y577404I6691J0D01*
G01X1658958Y582137D02*
G03X1660583Y578218I5540J1D01*
G01X1659769Y577404D02*
X1664311Y572862D01*
G01X1660583Y578218D02*
X1665125Y573676D01*
G01X1664311Y572862D02*
G02X1665000Y571201I-1662J-1663D01*
G01X1665125Y573676D02*
G02X1666150Y571202I-2476J-2475D01*
G01X1665000Y571201D02*
Y566124D01*
G01X1666150Y571202D02*
Y566123D01*
G01X1665000Y566124D02*
G02X1664435Y564763I-1924J1D01*
G01X1666150Y566123D02*
G02X1665249Y563949I-3075J1D01*
G01X1664435Y564763D02*
X1660732Y561060D01*
G01X1665248Y563949D02*
X1661546Y560247D01*
G01X1660732Y561060D02*
G02X1659713Y560637I-1020J1017D01*
G01X1661546Y560247D02*
G02X1659714Y559487I-1833J1831D01*
G01X1659713Y560637D02*
X1656947D01*
G01X1659714Y559487D02*
X1656948D01*
G01X1656947Y560637D02*
G03X1653891Y559372I0J-4323D01*
G01X1656948Y559487D02*
G03X1654705Y558558I0J-3172D01*
G01X1662199Y588083D02*
X1663264D01*
G01Y589233D02*
G02X1665100Y587397I0J-1836D01*
G01X1663264Y588083D02*
G02X1663950Y587397I0J-686D01*
G01X1665100D02*
Y581886D01*
G01X1663950Y587397D02*
Y581887D01*
G01X1665100Y581886D02*
G03X1666150Y579351I3585J0D01*
G01X1663950Y581887D02*
G03X1665336Y578537I4735J-3D01*
G01X1666150Y579351D02*
X1669550Y575951D01*
G01X1665336Y578537D02*
X1668736Y575137D01*
G01X1669550Y575951D02*
G03X1673172Y574450I3624J3625D01*
G01X1668736Y575137D02*
G03X1673173Y573300I4437J4439D01*
G01X1673172Y574450D02*
X1689764D01*
G01X1673173Y573300D02*
X1689763D01*
G01X1689764Y574450D02*
G02X1694056Y572672I0J-6070D01*
G01X1689763Y573300D02*
G02X1693242Y571858I-1J-4920D01*
G01X1694056Y572672D02*
X1696197Y570531D01*
G01X1693242Y571858D02*
X1695383Y569717D01*
G01X1696197Y570531D02*
G02X1697450Y567504I-3030J-3027D01*
G01X1695383Y569717D02*
G02X1696300Y567503I-2215J-2214D01*
G01X1697450Y567504D02*
Y564413D01*
G01X1696300Y567503D02*
Y564413D01*
G01X1697450D02*
G02X1693687Y560650I-3763J0D01*
G01X1696300Y564413D02*
G02X1693687Y561800I-2613J0D01*
G01Y560650D02*
X1667891D01*
G01X1693687Y561800D02*
X1667891D01*
G01Y560650D02*
G03X1665751Y559764I-1J-3025D01*
G01X1667891Y561800D02*
G03X1664937Y560577I-2J-4175D01*
G01X1665751Y559764D02*
X1663261Y557274D01*
G01X1664937Y560577D02*
X1662447Y558088D01*
G01X1663261Y557274D02*
G02X1660070Y555953I-3191J3194D01*
G01X1662447Y558088D02*
G02X1660069Y557103I-2379J2380D01*
G01X1660070Y555953D02*
X1658234D01*
G01X1660069Y557103D02*
X1658234D01*
G01Y555953D02*
G03X1655381Y554771I0J-4034D01*
G01X1658234Y557103D02*
G03X1654567Y555585I-1J-5185D01*
G01X1655858Y590011D02*
G02X1653683Y587836I-2175J0D01*
G01D02*
X1652162D01*
G01D02*
G03Y585786I0J-1025D01*
G01Y584636D02*
X1653683D01*
G01X1652162Y585786D02*
X1653683D01*
G01Y584636D02*
G02X1654708Y583611I0J-1025D01*
G01X1653683Y585786D02*
G02X1655858Y583611I0J-2175D01*
G01X1654708D02*
Y576099D01*
G01X1655858Y583611D02*
Y576100D01*
G01X1654707D02*
G02X1653896Y574150I-2750J0D01*
G01X1655858Y576100D02*
G02X1654708Y573334I-3901J0D01*
G01X1653858Y574113D02*
X1651372Y571627D01*
G01X1654708Y573334D02*
X1654690Y573316D01*
G01X1653896Y574150D02*
X1653858Y574112D01*
G01Y574113D02*
X1651372Y571627D01*
G01X1654672Y573299D02*
X1652186Y570813D01*
G01D02*
G03X1651407Y568932I1881J-1881D01*
G01D02*
Y562246D01*
G01X1658958Y593710D02*
Y582137D01*
G01X1657808Y593710D02*
Y582136D01*
G01X1658958Y582137D02*
G03X1660583Y578218I5540J1D01*
G01X1657808Y582136D02*
G03X1659769Y577404I6691J0D01*
G01X1660583Y578218D02*
X1665125Y573676D01*
G01X1659769Y577404D02*
X1664311Y572862D01*
G01X1665125Y573676D02*
G02X1666150Y571202I-2476J-2475D01*
G01X1664311Y572862D02*
G02X1665000Y571201I-1662J-1663D01*
G01X1666150Y571202D02*
Y566123D01*
G01X1665000Y571201D02*
Y566124D01*
G01X1666150Y566123D02*
G02X1665249Y563949I-3075J1D01*
G01X1665000Y566124D02*
G02X1664435Y564763I-1924J1D01*
G01X1665248Y563949D02*
X1661546Y560247D01*
G01X1664435Y564763D02*
X1660732Y561060D01*
G01X1661546Y560247D02*
G02X1659714Y559487I-1833J1831D01*
G01X1660732Y561060D02*
G02X1659713Y560637I-1020J1017D01*
G01X1659714Y559487D02*
X1656948D01*
G01X1659713Y560637D02*
X1656947D01*
G01X1656948Y559487D02*
G03X1654705Y558558I0J-3172D01*
G01X1656947Y560637D02*
G03X1653891Y559372I0J-4323D01*
G01X1650523Y593611D02*
Y594708D01*
G01D02*
G02X1651190Y595375I667J0D01*
G01Y596525D02*
X1652049D01*
G01X1651190Y595375D02*
X1652049D01*
G01X1662383Y589233D02*
X1663264D01*
G01X1656758Y603675D02*
X1656308D01*
G01X1656758Y604825D02*
X1656308D01*
G01Y603675D02*
G03X1655858Y603225I0J-450D01*
G01X1656308Y604825D02*
G03X1654708Y603225I0J-1600D01*
G01X1655858D02*
Y590011D01*
G01X1654708Y603225D02*
Y590011D01*
G01D02*
G02X1653683Y588986I-1025J0D01*
G01D02*
X1652162D01*
G01X1650523Y593611D02*
Y594708D01*
G01D02*
G02X1651190Y595375I667J0D01*
G01D02*
X1652049D01*
G01X1651190Y596525D02*
X1652049D01*
G01X1651319Y611175D02*
X1659804D01*
G01X1651319Y612325D02*
X1659804D01*
G01Y611175D02*
G02X1662184Y610188I-1J-3366D01*
G01X1659804Y612325D02*
G02X1662998Y611002I0J-4517D01*
G01X1662184Y610188D02*
X1662886Y609486D01*
G01X1662998Y611002D02*
X1663700Y610300D01*
G01X1662886Y609486D02*
G02X1663123Y608914I-572J-572D01*
G01X1663700Y610300D02*
G02X1664273Y608915I-1387J-1385D01*
G01X1663123Y608914D02*
Y600481D01*
G01X1664273Y608915D02*
Y600482D01*
G01X1663123Y600481D02*
G02X1662991Y600162I-452J0D01*
G01X1664273Y600482D02*
G02X1663805Y599349I-1602J-1D01*
G01X1662991Y600162D02*
X1658704Y595876D01*
G01X1663805Y599349D02*
X1659518Y595062D01*
G01X1658704Y595876D02*
G03X1657808Y593710I2167J-2165D01*
G01X1659518Y595062D02*
G03X1658958Y593710I1352J-1352D01*
G01X1662383Y589233D02*
X1663264D01*
G01X1656758Y604825D02*
X1656308D01*
G01X1656758Y603675D02*
X1656308D01*
G01Y604825D02*
G03X1654708Y603225I0J-1600D01*
G01X1656308Y603675D02*
G03X1655858Y603225I0J-450D01*
G01X1654708D02*
Y590011D01*
G01X1655858Y603225D02*
Y590011D01*
G01X1654708D02*
G02X1653683Y588986I-1025J0D01*
G01D02*
X1652162D01*
G01X1651319Y612325D02*
X1659804D01*
G01X1651319Y611175D02*
X1659804D01*
G01Y612325D02*
G02X1662998Y611002I0J-4517D01*
G01X1659804Y611175D02*
G02X1662184Y610188I-1J-3366D01*
G01X1662998Y611002D02*
X1663700Y610300D01*
G01X1662184Y610188D02*
X1662886Y609486D01*
G01X1663700Y610300D02*
G02X1664273Y608915I-1387J-1385D01*
G01X1662886Y609486D02*
G02X1663123Y608914I-572J-572D01*
G01X1664273Y608915D02*
Y600482D01*
G01X1663123Y608914D02*
Y600481D01*
G01X1664273Y600482D02*
G02X1663805Y599349I-1602J-1D01*
G01X1663123Y600481D02*
G02X1662991Y600162I-452J0D01*
G01X1663805Y599349D02*
X1659518Y595062D01*
G01X1662991Y600162D02*
X1658704Y595876D01*
G01X1659518Y595062D02*
G03X1658958Y593710I1352J-1352D01*
G01X1658704Y595876D02*
G03X1657808Y593710I2167J-2165D01*
G01X1731110Y29571D02*
X1750196D01*
G01X1731352Y28421D02*
X1750673D01*
G01X1750196Y29571D02*
X1753558Y32933D01*
G01X1750673Y28421D02*
X1754035Y31783D01*
G01D02*
X1756357D01*
G01X1760819Y35062D02*
X1758289Y28934D01*
G01X1762020Y34956D02*
X1759265Y28284D01*
G01X1758289Y28934D02*
X1756937Y27578D01*
G01X1759265Y28284D02*
X1757519Y26531D01*
G01X1756937Y27578D02*
X1753096Y26689D01*
G01X1757519Y26531D02*
X1753228Y25539D01*
G01X1753096Y26689D02*
X1730767D01*
G01X1753228Y25539D02*
X1731009D01*
G01X1731352Y28421D02*
X1750673D01*
G01X1731110Y29571D02*
X1750196D01*
G01X1750673Y28421D02*
X1754035Y31783D01*
G01X1750196Y29571D02*
X1753558Y32933D01*
G01X1754035Y31783D02*
X1756357D01*
G01X1762020Y34956D02*
X1759265Y28284D01*
G01X1760819Y35062D02*
X1758289Y28934D01*
G01X1759265Y28284D02*
X1757519Y26531D01*
G01X1758289Y28934D02*
X1756937Y27578D01*
G01X1757519Y26531D02*
X1753228Y25539D01*
G01X1756937Y27578D02*
X1753096Y26689D01*
G01X1753228Y25539D02*
X1731009D01*
G01X1753096Y26689D02*
X1730767D01*
G01X1730764Y32150D02*
X1746664D01*
G01X1731006Y31000D02*
X1747141D01*
G01X1746664Y32150D02*
X1747825Y33311D01*
G01X1747141Y31000D02*
X1748975Y32834D01*
G01X1731006Y31000D02*
X1747141D01*
G01X1730764Y32150D02*
X1746664D01*
G01X1747141Y31000D02*
X1748975Y32834D01*
G01X1746664Y32150D02*
X1747825Y33311D01*
G01X1761979Y26256D02*
X1765442Y34662D01*
G01X1764239Y34763D02*
X1761003Y26907D01*
G01X1759452Y23729D02*
X1761979Y26256D01*
G01X1761003Y26907D02*
X1758302Y24206D01*
G01X1759452Y21171D02*
Y23729D01*
G01X1758302Y24206D02*
Y21278D01*
G01Y24206D02*
Y21278D01*
G01X1759452Y21171D02*
Y23729D01*
G01X1761003Y26907D02*
X1758302Y24206D01*
G01X1759452Y23729D02*
X1761979Y26256D01*
G01X1764239Y34763D02*
X1761003Y26907D01*
G01X1761979Y26256D02*
X1765442Y34662D01*
G01X1735190Y20090D02*
Y21810D01*
G01X1736340Y21740D02*
Y20567D01*
G01X1736974Y18306D02*
X1735190Y20090D01*
G01X1736340Y20567D02*
X1737547Y19360D01*
G01X1757472Y13958D02*
X1736974Y18305D01*
G01X1737547Y19360D02*
X1757593Y15108D01*
G01X1767259Y13958D02*
X1757472D01*
G01X1757593Y15108D02*
X1767022D01*
G01X1774927Y17253D02*
X1767259Y13958D01*
G01X1767022Y15108D02*
X1773926Y18075D01*
G01X1775440Y25175D02*
X1773121Y36103D01*
G01X1771641Y36336D02*
X1773995Y25255D01*
G01X1770466Y36329D02*
X1772819Y25256D01*
G01X1773995Y25255D02*
X1772694Y19140D01*
G01X1772819Y25256D02*
X1771693Y19962D01*
G01X1772695Y19140D02*
X1766453Y16458D01*
G01X1771693Y19962D02*
X1766216Y17608D01*
G01X1766453Y16458D02*
X1757761D01*
G01X1766216Y17608D02*
X1757882D01*
G01X1757761Y16458D02*
X1747947Y18543D01*
G01X1757882Y17608D02*
X1748522Y19597D01*
G01X1747947Y18543D02*
X1745077Y21439D01*
G01X1748522Y19597D02*
X1746227Y21913D01*
G01X1745077Y21439D02*
Y22747D01*
G01X1746227Y21913D02*
Y22747D01*
G01X1768752Y34977D02*
X1765943Y28159D01*
G01X1767551Y35083D02*
X1764793Y28387D01*
G01X1765943Y28159D02*
Y25136D01*
G01X1764793Y28387D02*
Y25443D01*
G01X1775440Y25175D02*
X1773121Y36103D01*
G01X1767022Y15108D02*
X1773926Y18075D01*
G01X1774927Y17253D02*
X1767259Y13958D01*
G01X1757593Y15108D02*
X1767022D01*
G01X1767259Y13958D02*
X1757472D01*
G01X1737547Y19360D02*
X1757593Y15108D01*
G01X1757472Y13958D02*
X1736974Y18305D01*
G01X1736340Y20567D02*
X1737547Y19360D01*
G01X1736974Y18306D02*
X1735190Y20090D01*
G01X1736340Y21740D02*
Y20567D01*
G01X1735190Y20090D02*
Y21810D01*
G01X1770466Y36329D02*
X1772819Y25256D01*
G01X1771641Y36336D02*
X1773995Y25255D01*
G01X1772819Y25256D02*
X1771693Y19962D01*
G01X1773995Y25255D02*
X1772694Y19140D01*
G01X1771693Y19962D02*
X1766216Y17608D01*
G01X1772695Y19140D02*
X1766453Y16458D01*
G01X1766216Y17608D02*
X1757882D01*
G01X1766453Y16458D02*
X1757761D01*
G01X1757882Y17608D02*
X1748522Y19597D01*
G01X1757761Y16458D02*
X1747947Y18543D01*
G01X1748522Y19597D02*
X1746227Y21913D01*
G01X1747947Y18543D02*
X1745077Y21439D01*
G01X1746227Y21913D02*
Y22747D01*
G01X1745077Y21439D02*
Y22747D01*
G01X1767551Y35083D02*
X1764793Y28387D01*
G01X1768752Y34977D02*
X1765943Y28159D01*
G01X1764793Y28387D02*
Y25443D01*
G01X1765943Y28159D02*
Y25136D01*
G01X1777246Y10967D02*
X1764506Y5384D01*
G01X1776475Y11886D02*
X1764265Y6534D01*
G01X1764506Y5384D02*
X1720961D01*
G01X1764265Y6534D02*
X1721082D01*
G01X1720961Y5384D02*
X1717992Y6014D01*
G01X1721082Y6534D02*
X1718629Y7055D01*
G01X1717992Y6014D02*
X1716150Y8285D01*
G01X1718629Y7055D02*
X1717300Y8693D01*
G01X1716150Y8285D02*
Y10609D01*
G01X1717300Y8693D02*
Y10759D01*
G01X1768439Y11458D02*
X1777138Y15467D01*
G01X1776132Y16271D02*
X1768186Y12608D01*
G01X1756456Y11458D02*
X1768439D01*
G01X1768186Y12608D02*
X1756578D01*
G01X1750606Y12698D02*
X1756456Y11458D01*
G01X1756577Y12608D02*
X1750727Y13848D01*
G01X1737037Y12698D02*
X1750606D01*
G01X1750727Y13848D02*
X1736886D01*
G01X1734932Y12135D02*
X1737037Y12698D01*
G01X1736886Y13848D02*
X1734451Y13198D01*
G01X1733733Y11335D02*
X1734932Y12135D01*
G01X1734451Y13198D02*
X1733000Y12229D01*
G01X1730398Y8000D02*
X1733733Y11335D01*
G01X1733000Y12229D02*
X1729921Y9150D01*
G01X1727001Y8000D02*
X1730398D01*
G01X1729921Y9150D02*
X1727478D01*
G01X1725618Y9383D02*
X1727001Y8000D01*
G01X1727478Y9150D02*
X1726768Y9860D01*
G01X1725618Y10982D02*
Y9383D01*
G01X1726768Y9860D02*
Y10968D01*
G01X1765416Y125D02*
X1780871Y6904D01*
G01X1765174Y1275D02*
X1780100Y7822D01*
G01X1779023Y8875D02*
X1764827Y2652D01*
G01X1778252Y9794D02*
X1764584Y3802D01*
G01D02*
X1714998D01*
G01X1776475Y11886D02*
X1764265Y6534D01*
G01X1777246Y10967D02*
X1764506Y5384D01*
G01X1764265Y6534D02*
X1721082D01*
G01X1764506Y5384D02*
X1720961D01*
G01X1721082Y6534D02*
X1718629Y7055D01*
G01X1720961Y5384D02*
X1717992Y6014D01*
G01X1718629Y7055D02*
X1717300Y8693D01*
G01X1717992Y6014D02*
X1716150Y8285D01*
G01X1717300Y8693D02*
Y10759D01*
G01X1716150Y8285D02*
Y10609D01*
G01X1726768Y9860D02*
Y10968D01*
G01X1725618Y10982D02*
Y9383D01*
G01X1727478Y9150D02*
X1726768Y9860D01*
G01X1725618Y9383D02*
X1727001Y8000D01*
G01X1729921Y9150D02*
X1727478D01*
G01X1727001Y8000D02*
X1730398D01*
G01X1733000Y12229D02*
X1729921Y9150D01*
G01X1730398Y8000D02*
X1733733Y11335D01*
G01X1734451Y13198D02*
X1733000Y12229D01*
G01X1733733Y11335D02*
X1734932Y12135D01*
G01X1736886Y13848D02*
X1734451Y13198D01*
G01X1734932Y12135D02*
X1737037Y12698D01*
G01X1750727Y13848D02*
X1736886D01*
G01X1737037Y12698D02*
X1750606D01*
G01X1756577Y12608D02*
X1750727Y13848D01*
G01X1750606Y12698D02*
X1756456Y11458D01*
G01X1768186Y12608D02*
X1756578D01*
G01X1756456Y11458D02*
X1768439D01*
G01X1776132Y16271D02*
X1768186Y12608D01*
G01X1768439Y11458D02*
X1777138Y15467D01*
G01X1765174Y1275D02*
X1780100Y7822D01*
G01X1765416Y125D02*
X1780871Y6904D01*
G01X1778252Y9794D02*
X1764584Y3802D01*
G01X1779023Y8875D02*
X1764827Y2652D01*
G01X1764584Y3802D02*
X1714998D01*
G01X1753558Y32933D02*
X1756292D01*
G01X1754646Y38873D02*
X1755319Y39546D01*
G01X1753011Y38865D02*
X1754842Y40696D01*
G01X1755319Y39546D02*
X1758434D01*
G01X1754842Y40696D02*
X1758911D01*
G01X1758434Y39546D02*
X1759972Y38008D01*
G01X1758911Y40696D02*
X1760932Y38675D01*
G01X1759972Y38008D02*
X1760361Y37157D01*
G01X1760932Y38675D02*
X1761459Y37523D01*
G01X1760361Y37157D02*
X1760819Y35062D01*
G01X1761459Y37523D02*
X1762020Y34956D01*
G01X1753558Y32933D02*
X1756292D01*
G01X1753011Y38865D02*
X1754842Y40696D01*
G01X1754646Y38873D02*
X1755319Y39546D01*
G01X1754842Y40696D02*
X1758911D01*
G01X1755319Y39546D02*
X1758434D01*
G01X1758911Y40696D02*
X1760932Y38675D01*
G01X1758434Y39546D02*
X1759972Y38008D01*
G01X1760932Y38675D02*
X1761459Y37523D01*
G01X1759972Y38008D02*
X1760361Y37157D01*
G01X1761459Y37523D02*
X1762020Y34956D01*
G01X1760361Y37157D02*
X1760819Y35062D01*
G01X1716296Y34056D02*
X1719283Y37043D01*
G01X1716957Y33089D02*
X1720433Y36566D01*
G01X1719283Y37043D02*
Y39318D01*
G01X1720433Y36566D02*
Y39234D01*
G01X1727059Y35987D02*
X1728675Y37602D01*
G01X1727720Y35020D02*
X1729825Y37125D01*
G01X1728675Y37602D02*
Y39015D01*
G01X1729825Y37125D02*
Y38645D01*
G01X1730786Y34891D02*
X1737193D01*
G01X1731028Y33741D02*
X1737670D01*
G01X1737193Y34891D02*
X1738150Y35848D01*
G01X1737670Y33741D02*
X1739300Y35371D01*
G01X1738150Y35848D02*
Y38750D01*
G01X1739300Y35371D02*
Y38600D01*
G01X1747825Y33311D02*
Y35474D01*
G01X1748975Y32834D02*
Y35474D01*
G01X1716957Y33089D02*
X1720433Y36566D01*
G01X1716296Y34056D02*
X1719283Y37043D01*
G01X1720433Y36566D02*
Y39234D01*
G01X1719283Y37043D02*
Y39318D01*
G01X1727720Y35020D02*
X1729825Y37125D01*
G01X1727059Y35987D02*
X1728675Y37602D01*
G01X1729825Y37125D02*
Y38645D01*
G01X1728675Y37602D02*
Y39015D01*
G01X1731028Y33741D02*
X1737670D01*
G01X1730786Y34891D02*
X1737193D01*
G01X1737670Y33741D02*
X1739300Y35371D01*
G01X1737193Y34891D02*
X1738150Y35848D01*
G01X1739300Y35371D02*
Y38600D01*
G01X1738150Y35848D02*
Y38750D01*
G01X1748975Y32834D02*
Y35474D01*
G01X1747825Y33311D02*
Y35474D01*
G01X1726665Y45587D02*
X1713864Y42867D01*
G01Y41691D02*
X1726665Y44411D01*
G01X1735395Y43733D02*
X1726665Y45587D01*
G01Y44411D02*
X1735388Y42558D01*
G01X1739798Y44610D02*
X1735395Y43733D01*
G01X1735388Y42558D02*
X1739798Y43437D01*
G01X1748647Y42841D02*
X1739798Y44610D01*
G01Y43437D02*
X1748647Y41668D01*
G01X1756414Y44395D02*
X1748647Y42841D01*
G01Y41668D02*
X1756413Y43221D01*
G01X1760306Y43606D02*
X1756414Y44395D01*
G01X1756413Y43221D02*
X1759835Y42528D01*
G01X1762929Y41719D02*
X1760306Y43606D01*
G01X1759835Y42528D02*
X1762056Y40930D01*
G01X1764437Y39104D02*
X1762929Y41719D01*
G01X1762056Y40930D02*
X1763353Y38680D01*
G01X1765442Y34662D02*
X1764437Y39104D01*
G01X1763353Y38680D02*
X1764239Y34763D01*
G01X1763353Y38680D02*
X1764239Y34763D01*
G01X1765442Y34662D02*
X1764437Y39104D01*
G01X1762056Y40930D02*
X1763353Y38680D01*
G01X1764437Y39104D02*
X1762929Y41719D01*
G01X1759835Y42528D02*
X1762056Y40930D01*
G01X1762929Y41719D02*
X1760306Y43606D01*
G01X1756413Y43221D02*
X1759835Y42528D01*
G01X1760306Y43606D02*
X1756414Y44395D01*
G01X1748647Y41668D02*
X1756413Y43221D01*
G01X1756414Y44395D02*
X1748647Y42841D01*
G01X1739798Y43437D02*
X1748647Y41668D01*
G01Y42841D02*
X1739798Y44610D01*
G01X1735388Y42558D02*
X1739798Y43437D01*
G01Y44610D02*
X1735395Y43733D01*
G01X1726665Y44411D02*
X1735388Y42558D01*
G01X1735395Y43733D02*
X1726665Y45587D01*
G01X1713864Y41691D02*
X1726665Y44411D01*
G01Y45587D02*
X1713864Y42867D01*
G01X1773121Y36103D02*
X1773900Y39999D01*
G01D02*
X1772969Y44655D01*
G01X1748817Y62135D02*
X1774004Y45348D01*
G01X1772969Y44655D02*
X1748368Y61052D01*
G01X1735921Y64716D02*
X1748817Y62135D01*
G01X1748368Y61052D02*
X1735955Y63536D01*
G01X1731365Y63527D02*
X1735921Y64716D01*
G01X1735955Y63536D02*
X1731843Y62463D01*
G01X1729553Y62317D02*
X1731365Y63527D01*
G01X1731843Y62463D02*
X1730003Y61233D01*
G01X1714869Y54229D02*
X1717528Y56000D01*
G01X1715318Y53146D02*
X1717977Y54916D01*
G01X1717528Y56000D02*
X1720488Y56591D01*
G01X1717977Y54916D02*
X1720488Y55418D01*
G01Y56591D02*
X1729336Y54822D01*
G01X1720488Y55418D02*
X1729343Y53647D01*
G01X1729336Y54822D02*
X1743216Y57771D01*
G01X1729343Y53647D02*
X1743223Y56596D01*
G01X1743216Y57771D02*
X1753644Y55685D01*
G01X1743223Y56596D02*
X1753195Y54602D01*
G01X1753644Y55685D02*
X1771612Y43710D01*
G01X1753195Y54602D02*
X1755040Y53372D01*
G01X1753644Y55685D02*
X1771612Y43710D01*
G01X1756344Y51722D02*
X1757245Y51902D01*
G01X1753644Y55685D02*
X1771612Y43710D01*
G01X1757245Y51902D02*
X1760592Y49672D01*
G01X1753644Y55685D02*
X1771612Y43710D01*
G01X1762797Y48203D02*
X1763920Y47454D01*
G01X1753644Y55685D02*
X1771612Y43710D01*
G01X1765224Y45804D02*
X1766125Y45984D01*
G01X1753644Y55685D02*
X1771612Y43710D01*
G01X1766125Y45984D02*
X1767249Y45235D01*
G01X1753644Y55685D02*
X1771612Y43710D01*
G01X1769454Y43766D02*
X1770577Y43017D01*
G01X1771612Y43710D02*
X1772363Y39952D01*
G01X1770577Y43017D02*
X1771190Y39952D01*
G01X1772363D02*
X1771641Y36336D01*
G01X1771190Y39952D02*
X1770466Y36329D01*
G01X1718430Y50649D02*
X1722854Y49754D01*
G01X1718430Y49475D02*
X1722625Y48622D01*
G01X1718430Y50649D02*
X1722854Y49754D01*
G01X1722866Y49750D02*
X1725273Y49265D01*
G01X1722627Y48620D02*
X1722628D01*
G01X1722866Y49750D02*
X1725273Y49265D01*
G01X1722640Y48616D02*
X1725276Y48091D01*
G01X1725273Y49265D02*
X1729919Y50216D01*
G01X1725276Y48091D02*
X1729682Y48993D01*
G01X1729919Y50216D02*
X1731243Y49341D01*
G01X1729682Y48993D02*
X1729945Y48819D01*
G01X1729919Y50216D02*
X1731243Y49341D01*
G01X1729946Y48818D02*
X1730211Y48643D01*
G01X1731243Y49341D02*
X1731498Y48096D01*
G01X1730211Y48643D02*
X1730466Y47398D01*
G01X1731498Y48096D02*
X1732028Y47746D01*
G01X1730466Y47398D02*
X1731792Y46523D01*
G01X1732028Y47746D02*
X1732912Y47927D01*
G01X1731792Y46523D02*
X1733610Y46895D01*
G01X1732912Y47927D02*
X1733262Y48457D01*
G01X1733610Y46895D02*
X1734485Y48221D01*
G01X1733262Y48457D02*
X1733007Y49702D01*
G01X1734485Y48221D02*
X1734230Y49465D01*
G01X1733007Y49702D02*
X1733883Y51027D01*
G01X1734230Y49465D02*
X1734580Y49995D01*
G01X1733883Y51027D02*
X1738189Y51908D01*
G01X1734580Y49995D02*
X1738306Y50758D01*
G01X1733883Y51027D02*
X1738189Y51908D01*
G01D02*
X1738427D01*
G01D02*
X1742667Y51063D01*
G01X1738306Y50758D02*
X1738313D01*
G01X1738427Y51908D02*
X1742667Y51063D01*
G01X1738313Y50758D02*
X1742909Y49842D01*
G01X1742667Y51063D02*
X1743197Y51417D01*
G01X1742909Y49842D02*
X1744231Y50724D01*
G01X1743197Y51417D02*
X1743587Y53358D01*
G01X1744231Y50724D02*
X1744621Y52665D01*
G01X1743587Y53358D02*
X1744909Y54240D01*
G01X1744621Y52665D02*
X1745150Y53018D01*
G01X1744909Y54240D02*
X1746726Y53874D01*
G01X1745150Y53018D02*
X1746033Y52840D01*
G01X1746726Y53874D02*
X1747608Y52553D01*
G01X1746033Y52840D02*
X1746386Y52311D01*
G01X1747608Y52553D02*
X1747218Y50611D01*
G01X1746386Y52311D02*
X1745996Y50370D01*
G01X1747218Y50611D02*
X1747570Y50082D01*
G01X1745996Y50370D02*
X1746877Y49048D01*
G01X1747570Y50082D02*
X1748457Y49904D01*
G01X1746877Y49048D02*
X1748698Y48682D01*
G01X1748457Y49904D02*
X1748985Y50256D01*
G01X1748698Y48682D02*
X1750019Y49563D01*
G01X1748985Y50256D02*
X1749375Y52197D01*
G01X1750019Y49563D02*
X1750409Y51504D01*
G01X1749375Y52197D02*
X1750697Y53079D01*
G01X1750409Y51504D02*
X1750938Y51857D01*
G01X1750697Y53079D02*
X1752514Y52713D01*
G01X1750938Y51857D02*
X1751821Y51679D01*
G01X1752514Y52713D02*
X1753396Y51392D01*
G01X1751821Y51679D02*
X1752174Y51150D01*
G01X1753396Y51392D02*
X1753006Y49450D01*
G01X1752174Y51150D02*
X1751784Y49209D01*
G01X1753006Y49450D02*
X1753358Y48922D01*
G01X1751784Y49209D02*
X1752665Y47888D01*
G01X1753358Y48922D02*
X1759250Y47739D01*
G01X1752665Y47888D02*
X1758780Y46660D01*
G01X1759250Y47739D02*
X1765145Y43497D01*
G01X1758780Y46660D02*
X1764284Y42699D01*
G01X1765145Y43497D02*
X1767863Y39039D01*
G01X1764284Y42699D02*
X1766780Y38605D01*
G01X1767863Y39039D02*
X1768752Y34977D01*
G01X1766780Y38605D02*
X1767551Y35083D01*
G01X1731843Y62463D02*
X1730003Y61233D01*
G01X1729553Y62317D02*
X1731365Y63527D01*
G01X1735955Y63536D02*
X1731843Y62463D01*
G01X1731365Y63527D02*
X1735921Y64716D01*
G01X1748368Y61052D02*
X1735955Y63536D01*
G01X1735921Y64716D02*
X1748817Y62135D01*
G01X1772969Y44655D02*
X1748368Y61052D01*
G01X1748817Y62135D02*
X1774004Y45348D01*
G01X1773900Y39999D02*
X1772969Y44655D01*
G01X1773121Y36103D02*
X1773900Y39999D01*
G01X1715318Y53146D02*
X1717977Y54916D01*
G01X1714869Y54229D02*
X1717528Y56000D01*
G01X1717977Y54916D02*
X1720488Y55418D01*
G01X1717528Y56000D02*
X1720488Y56591D01*
G01Y55418D02*
X1729343Y53647D01*
G01X1720488Y56591D02*
X1729336Y54822D01*
G01X1729343Y53647D02*
X1743223Y56596D01*
G01X1729336Y54822D02*
X1743216Y57771D01*
G01X1743223Y56596D02*
X1753195Y54602D01*
G01X1743216Y57771D02*
X1753644Y55685D01*
G01X1753195Y54602D02*
X1755040Y53372D01*
G01X1756344Y51722D02*
X1757245Y51902D01*
G01D02*
X1760592Y49672D01*
G01X1762797Y48203D02*
X1763920Y47454D01*
G01X1765224Y45804D02*
X1766125Y45984D01*
G01D02*
X1767249Y45235D01*
G01X1769454Y43766D02*
X1770577Y43017D01*
G01X1753644Y55685D02*
X1771612Y43710D01*
G01X1770577Y43017D02*
X1771190Y39952D01*
G01X1771612Y43710D02*
X1772363Y39952D01*
G01X1771190D02*
X1770466Y36329D01*
G01X1772363Y39952D02*
X1771641Y36336D01*
G01X1718430Y49475D02*
X1722625Y48622D01*
G01X1722627Y48620D02*
X1722628D01*
G01X1718430Y50649D02*
X1722854Y49754D01*
G01X1722627Y48620D02*
X1722628D01*
G01X1722640Y48616D02*
X1725276Y48091D01*
G01X1722866Y49750D02*
X1725273Y49265D01*
G01X1725276Y48091D02*
X1729682Y48993D01*
G01X1725273Y49265D02*
X1729919Y50216D01*
G01X1729682Y48993D02*
X1729945Y48819D01*
G01X1729946Y48818D02*
X1730211Y48643D01*
G01X1729919Y50216D02*
X1731243Y49341D01*
G01X1730211Y48643D02*
X1730466Y47398D01*
G01X1731243Y49341D02*
X1731498Y48096D01*
G01X1730466Y47398D02*
X1731792Y46523D01*
G01X1731498Y48096D02*
X1732028Y47746D01*
G01X1731792Y46523D02*
X1733610Y46895D01*
G01X1732028Y47746D02*
X1732912Y47927D01*
G01X1733610Y46895D02*
X1734485Y48221D01*
G01X1732912Y47927D02*
X1733262Y48457D01*
G01X1734485Y48221D02*
X1734230Y49465D01*
G01X1733262Y48457D02*
X1733007Y49702D01*
G01X1734230Y49465D02*
X1734580Y49995D01*
G01X1733007Y49702D02*
X1733883Y51027D01*
G01X1734580Y49995D02*
X1738306Y50758D01*
G01D02*
X1738313D01*
G01X1733883Y51027D02*
X1738189Y51908D01*
G01X1738306Y50758D02*
X1738313D01*
G01X1738189Y51908D02*
X1738427D01*
G01X1738306Y50758D02*
X1738313D01*
G01D02*
X1742909Y49842D01*
G01X1738427Y51908D02*
X1742667Y51063D01*
G01X1742909Y49842D02*
X1744231Y50724D01*
G01X1742667Y51063D02*
X1743197Y51417D01*
G01X1744231Y50724D02*
X1744621Y52665D01*
G01X1743197Y51417D02*
X1743587Y53358D01*
G01X1744621Y52665D02*
X1745150Y53018D01*
G01X1743587Y53358D02*
X1744909Y54240D01*
G01X1745150Y53018D02*
X1746033Y52840D01*
G01X1744909Y54240D02*
X1746726Y53874D01*
G01X1746033Y52840D02*
X1746386Y52311D01*
G01X1746726Y53874D02*
X1747608Y52553D01*
G01X1746386Y52311D02*
X1745996Y50370D01*
G01X1747608Y52553D02*
X1747218Y50611D01*
G01X1745996Y50370D02*
X1746877Y49048D01*
G01X1747218Y50611D02*
X1747570Y50082D01*
G01X1746877Y49048D02*
X1748698Y48682D01*
G01X1747570Y50082D02*
X1748457Y49904D01*
G01X1748698Y48682D02*
X1750019Y49563D01*
G01X1748457Y49904D02*
X1748985Y50256D01*
G01X1750019Y49563D02*
X1750409Y51504D01*
G01X1748985Y50256D02*
X1749375Y52197D01*
G01X1750409Y51504D02*
X1750938Y51857D01*
G01X1749375Y52197D02*
X1750697Y53079D01*
G01X1750938Y51857D02*
X1751821Y51679D01*
G01X1750697Y53079D02*
X1752514Y52713D01*
G01X1751821Y51679D02*
X1752174Y51150D01*
G01X1752514Y52713D02*
X1753396Y51392D01*
G01X1752174Y51150D02*
X1751784Y49209D01*
G01X1753396Y51392D02*
X1753006Y49450D01*
G01X1751784Y49209D02*
X1752665Y47888D01*
G01X1753006Y49450D02*
X1753358Y48922D01*
G01X1752665Y47888D02*
X1758780Y46660D01*
G01X1753358Y48922D02*
X1759250Y47739D01*
G01X1758780Y46660D02*
X1764284Y42699D01*
G01X1759250Y47739D02*
X1765145Y43497D01*
G01X1764284Y42699D02*
X1766780Y38605D01*
G01X1765145Y43497D02*
X1767863Y39039D01*
G01X1766780Y38605D02*
X1767551Y35083D01*
G01X1767863Y39039D02*
X1768752Y34977D01*
G01X1716966Y68028D02*
X1723463Y66707D01*
G01D02*
X1723684D01*
G01X1716966Y66854D02*
X1723347Y65557D01*
G01X1723463Y66707D02*
X1723684D01*
G01X1723347Y65557D02*
X1723813D01*
G01X1723463Y66707D02*
X1723684D01*
G01D02*
X1725771Y67150D01*
G01X1723814Y65558D02*
X1726226Y66070D01*
G01X1725771Y67150D02*
X1727449Y68269D01*
G01X1726226Y66070D02*
X1727929Y67206D01*
G01X1727449Y68269D02*
X1735498Y70414D01*
G01X1727929Y67206D02*
X1735571Y69243D01*
G01X1735498Y70414D02*
X1744164Y69235D01*
G01X1735571Y69243D02*
X1744200Y68069D01*
G01X1744164Y69235D02*
X1753553Y71110D01*
G01X1744200Y68069D02*
X1753552Y69937D01*
G01X1753553Y71110D02*
X1763704Y69066D01*
G01X1753552Y69937D02*
X1763043Y68025D01*
G01X1753553Y71110D02*
X1763704Y69066D01*
G01X1763043Y68026D02*
X1763044D01*
G01X1763704Y69066D02*
X1766193Y65723D01*
G01X1763044Y68025D02*
X1765510Y64713D01*
G01X1766193Y65723D02*
X1769161Y64938D01*
G01X1765510Y64713D02*
X1769163Y63747D01*
G01X1769161Y64938D02*
X1772598Y65860D01*
G01X1769163Y63747D02*
X1772560Y64658D01*
G01X1772601Y65867D02*
X1775058Y64975D01*
G01X1772560Y64658D02*
X1774424Y63981D01*
G01X1713904Y63227D02*
X1715227Y63495D01*
G01X1721468Y63399D02*
X1715228Y64669D01*
G01X1715227Y63495D02*
X1721467Y62225D01*
G01X1728642Y64843D02*
X1721468Y63399D01*
G01X1721467Y62225D02*
X1729091Y63760D01*
G01X1730998Y66414D02*
X1728642Y64843D01*
G01X1729091Y63760D02*
X1731465Y65342D01*
G01X1735441Y67471D02*
X1730998Y66414D01*
G01X1731465Y65342D02*
X1735486Y66299D01*
G01X1748081Y65468D02*
X1735441Y67471D01*
G01X1735486Y66299D02*
X1747852Y64339D01*
G01X1758909Y62789D02*
X1748081Y65468D01*
G01X1747852Y64339D02*
X1758882Y61610D01*
G01X1763800Y63766D02*
X1758909Y62789D01*
G01X1758882Y61610D02*
X1763764Y62586D01*
G01X1769626Y62228D02*
X1763800Y63766D01*
G01X1763764Y62586D02*
X1765069Y62241D01*
G01X1769626Y62228D02*
X1763800Y63766D01*
G01X1767631Y61565D02*
X1769648Y61032D01*
G01X1772014Y62955D02*
X1769626Y62228D01*
G01X1769649Y61032D02*
X1771982Y61743D01*
G01X1773958Y62250D02*
X1772014Y62955D01*
G01X1771982Y61743D02*
X1773323Y61256D01*
G01X1775503Y60694D02*
X1773958Y62250D01*
G01X1773323Y61256D02*
X1774608Y59963D01*
G01X1787591Y56311D02*
X1772772Y79606D01*
G01X1786505Y55875D02*
X1772065Y78574D01*
G01X1772772Y79606D02*
X1765678Y81026D01*
G01X1772065Y78574D02*
X1765679Y79852D01*
G01X1765678Y81026D02*
X1757658Y79412D01*
G01X1765679Y79852D02*
X1757657Y78238D01*
G01X1757658Y79412D02*
X1752034Y80558D01*
G01X1757657Y78238D02*
X1751465Y79500D01*
G01X1752034Y80558D02*
X1750194Y82398D01*
G01X1751465Y79500D02*
X1749625Y81339D01*
G01X1750194Y82398D02*
X1742721Y83917D01*
G01X1749625Y81339D02*
X1742756Y82736D01*
G01X1712807Y71854D02*
X1715170Y72406D01*
G01X1715151Y73583D02*
X1717753Y73061D01*
G01X1715170Y72406D02*
X1717753Y71888D01*
G01Y73061D02*
X1721251Y73762D01*
G01X1717753Y71888D02*
X1721251Y72589D01*
G01Y73762D02*
X1727872Y72439D01*
G01X1721251Y72589D02*
X1727873Y71265D01*
G01X1727872Y72439D02*
X1753327Y77618D01*
G01X1727874Y71265D02*
X1745487Y74849D01*
G01X1727872Y72439D02*
X1753327Y77618D01*
G01X1748084Y75377D02*
X1749407Y75646D01*
G01X1727872Y72439D02*
X1753327Y77618D01*
G01X1752004Y76174D02*
X1753327Y76443D01*
G01Y77618D02*
X1770313Y74208D01*
G01X1753329Y76444D02*
X1762064Y74691D01*
G01X1753327Y77618D02*
X1770313Y74208D01*
G01X1764662Y74169D02*
X1769864Y73125D01*
G01X1770313Y74208D02*
X1774389Y71491D01*
G01X1769864Y73125D02*
X1773548Y70668D01*
G01D02*
X1774273Y69529D01*
G01X1716966Y66854D02*
X1723347Y65557D01*
G01X1716966Y68028D02*
X1723463Y66707D01*
G01X1716966Y66854D02*
X1723347Y65557D01*
G01D02*
X1723813D01*
G01X1723814Y65558D02*
X1726226Y66070D01*
G01X1723463Y66707D02*
X1723684D01*
G01X1723814Y65558D02*
X1726226Y66070D01*
G01X1723684Y66707D02*
X1725771Y67150D01*
G01X1726226Y66070D02*
X1727929Y67206D01*
G01X1725771Y67150D02*
X1727449Y68269D01*
G01X1727929Y67206D02*
X1735571Y69243D01*
G01X1727449Y68269D02*
X1735498Y70414D01*
G01X1735571Y69243D02*
X1744200Y68069D01*
G01X1735498Y70414D02*
X1744164Y69235D01*
G01X1744200Y68069D02*
X1753552Y69937D01*
G01X1744164Y69235D02*
X1753553Y71110D01*
G01X1753552Y69937D02*
X1763043Y68025D01*
G01Y68026D02*
X1763044D01*
G01X1753553Y71110D02*
X1763704Y69066D01*
G01X1763044Y68025D02*
X1765510Y64713D01*
G01X1763704Y69066D02*
X1766193Y65723D01*
G01X1765510Y64713D02*
X1769163Y63747D01*
G01X1766193Y65723D02*
X1769161Y64938D01*
G01X1769163Y63747D02*
X1772560Y64658D01*
G01X1769161Y64938D02*
X1772598Y65860D01*
G01X1772560Y64658D02*
X1774424Y63981D01*
G01X1772601Y65867D02*
X1775058Y64975D01*
G01X1773323Y61256D02*
X1774608Y59963D01*
G01X1775503Y60694D02*
X1773958Y62250D01*
G01X1771982Y61743D02*
X1773323Y61256D01*
G01X1773958Y62250D02*
X1772014Y62955D01*
G01X1769649Y61032D02*
X1771982Y61743D01*
G01X1772014Y62955D02*
X1769626Y62228D01*
G01X1763764Y62586D02*
X1765069Y62241D01*
G01X1767631Y61565D02*
X1769648Y61032D01*
G01X1769626Y62228D02*
X1763800Y63766D01*
G01X1758882Y61610D02*
X1763764Y62586D01*
G01X1763800Y63766D02*
X1758909Y62789D01*
G01X1747852Y64339D02*
X1758882Y61610D01*
G01X1758909Y62789D02*
X1748081Y65468D01*
G01X1735486Y66299D02*
X1747852Y64339D01*
G01X1748081Y65468D02*
X1735441Y67471D01*
G01X1731465Y65342D02*
X1735486Y66299D01*
G01X1735441Y67471D02*
X1730998Y66414D01*
G01X1729091Y63760D02*
X1731465Y65342D01*
G01X1730998Y66414D02*
X1728642Y64843D01*
G01X1721467Y62225D02*
X1729091Y63760D01*
G01X1728642Y64843D02*
X1721468Y63399D01*
G01X1715227Y63495D02*
X1721467Y62225D01*
G01X1721468Y63399D02*
X1715228Y64669D01*
G01X1713904Y63227D02*
X1715227Y63495D01*
G01X1786505Y55875D02*
X1772065Y78574D01*
G01X1787591Y56311D02*
X1772772Y79606D01*
G01X1772065Y78574D02*
X1765679Y79852D01*
G01X1772772Y79606D02*
X1765678Y81026D01*
G01X1765679Y79852D02*
X1757657Y78238D01*
G01X1765678Y81026D02*
X1757658Y79412D01*
G01X1757657Y78238D02*
X1751465Y79500D01*
G01X1757658Y79412D02*
X1752034Y80558D01*
G01X1751465Y79500D02*
X1749625Y81339D01*
G01X1752034Y80558D02*
X1750194Y82398D01*
G01X1749625Y81339D02*
X1742756Y82736D01*
G01X1750194Y82398D02*
X1742721Y83917D01*
G01X1712807Y71854D02*
X1715170Y72406D01*
G01D02*
X1717753Y71888D01*
G01X1715151Y73583D02*
X1717753Y73061D01*
G01Y71888D02*
X1721251Y72589D01*
G01X1717753Y73061D02*
X1721251Y73762D01*
G01Y72589D02*
X1727873Y71265D01*
G01X1721251Y73762D02*
X1727872Y72439D01*
G01X1727874Y71265D02*
X1745487Y74849D01*
G01X1748084Y75377D02*
X1749407Y75646D01*
G01X1752004Y76174D02*
X1753327Y76443D01*
G01X1727872Y72439D02*
X1753327Y77618D01*
G01X1753329Y76444D02*
X1762064Y74691D01*
G01X1764662Y74169D02*
X1769864Y73125D01*
G01X1753327Y77618D02*
X1770313Y74208D01*
G01X1769864Y73125D02*
X1773548Y70668D01*
G01X1770313Y74208D02*
X1774389Y71491D01*
G01X1773548Y70668D02*
X1774273Y69529D01*
G01X1776616Y25174D02*
X1774927Y17253D01*
G01X1773926Y18075D02*
X1775440Y25175D01*
G01X1774296Y36110D02*
X1776616Y25174D01*
G01X1774296Y36110D02*
X1776616Y25174D01*
G01X1773926Y18075D02*
X1775440Y25175D01*
G01X1776616Y25174D02*
X1774927Y17253D01*
G01X1783746Y38974D02*
X1786507Y25988D01*
G01X1782667Y38518D02*
X1785281Y26223D01*
G01X1786507Y25988D02*
X1785211Y24043D01*
G01X1785281Y26223D02*
X1784381Y24872D01*
G01X1785211Y24043D02*
X1783262Y22741D01*
G01X1784381Y24872D02*
X1782432Y23571D01*
G01X1783262Y22741D02*
X1781268Y19751D01*
G01X1782432Y23571D02*
X1780187Y20205D01*
G01X1781268Y19751D02*
X1780429Y15741D01*
G01X1780187Y20205D02*
X1779348Y16194D01*
G01X1780429Y15741D02*
X1777246Y10967D01*
G01X1779348Y16194D02*
X1778090Y14308D01*
G01X1780429Y15741D02*
X1777246Y10967D01*
G01X1778090Y14308D02*
X1776475Y11886D01*
G01X1779211Y25236D02*
X1776917Y36041D01*
G01X1775741D02*
X1778035Y25236D01*
G01X1777138Y15467D02*
X1778090Y19953D01*
G01D02*
X1779211Y25236D01*
G01X1778035D02*
X1776132Y16271D01*
G01X1780871Y6904D02*
X1785461Y13800D01*
G01X1780100Y7822D02*
X1784631Y14629D01*
G01X1785461Y13800D02*
X1793231Y18978D01*
G01X1784631Y14629D02*
X1792401Y19808D01*
G01X1793231Y18978D02*
X1803396Y34219D01*
G01X1792401Y19808D02*
X1797088Y26835D01*
G01X1793231Y18978D02*
X1803396Y34219D01*
G01X1798558Y29040D02*
X1799776Y30865D01*
G01X1793231Y18978D02*
X1803396Y34219D01*
G01X1786325Y40133D02*
X1789383Y25749D01*
G01X1785246Y39678D02*
X1788304Y25294D01*
G01X1789383Y25749D02*
X1790299Y24376D01*
G01X1788304Y25294D02*
X1789215Y23927D01*
G01X1790299Y24376D02*
X1790718Y22272D01*
G01X1789215Y23927D02*
X1789545Y22272D01*
G01X1790718D02*
X1790290Y20128D01*
G01X1789545Y22272D02*
X1789255Y20821D01*
G01X1790290Y20128D02*
X1783510Y15606D01*
G01X1789255Y20821D02*
X1782680Y16436D01*
G01X1783510Y15606D02*
X1779023Y8875D01*
G01X1782680Y16436D02*
X1778252Y9794D01*
G01X1782667Y38518D02*
X1785281Y26223D01*
G01X1783746Y38974D02*
X1786507Y25988D01*
G01X1785281Y26223D02*
X1784381Y24872D01*
G01X1786507Y25988D02*
X1785211Y24043D01*
G01X1784381Y24872D02*
X1782432Y23571D01*
G01X1785211Y24043D02*
X1783262Y22741D01*
G01X1782432Y23571D02*
X1780187Y20205D01*
G01X1783262Y22741D02*
X1781268Y19751D01*
G01X1780187Y20205D02*
X1779348Y16194D01*
G01X1781268Y19751D02*
X1780429Y15741D01*
G01X1779348Y16194D02*
X1778090Y14308D01*
G01D02*
X1776475Y11886D01*
G01X1780429Y15741D02*
X1777246Y10967D01*
G01X1778035Y25236D02*
X1776132Y16271D01*
G01X1777138Y15467D02*
X1778090Y19953D01*
G01X1778035Y25236D02*
X1776132Y16271D01*
G01X1778090Y19953D02*
X1779211Y25236D01*
G01X1775741Y36041D02*
X1778035Y25236D01*
G01X1779211D02*
X1776917Y36041D01*
G01X1780100Y7822D02*
X1784631Y14629D01*
G01X1780871Y6904D02*
X1785461Y13800D01*
G01X1784631Y14629D02*
X1792401Y19808D01*
G01X1785461Y13800D02*
X1793231Y18978D01*
G01X1792401Y19808D02*
X1797088Y26835D01*
G01X1798558Y29040D02*
X1799776Y30865D01*
G01X1793231Y18978D02*
X1803396Y34219D01*
G01X1785246Y39678D02*
X1788304Y25294D01*
G01X1786325Y40133D02*
X1789383Y25749D01*
G01X1788304Y25294D02*
X1789215Y23927D01*
G01X1789383Y25749D02*
X1790299Y24376D01*
G01X1789215Y23927D02*
X1789545Y22272D01*
G01X1790299Y24376D02*
X1790718Y22272D01*
G01X1789545D02*
X1789255Y20821D01*
G01X1790718Y22272D02*
X1790290Y20128D01*
G01X1789255Y20821D02*
X1782680Y16436D01*
G01X1790290Y20128D02*
X1783510Y15606D01*
G01X1782680Y16436D02*
X1778252Y9794D01*
G01X1783510Y15606D02*
X1779023Y8875D01*
G01X1775073Y39999D02*
X1774296Y36110D01*
G01X1774004Y45348D02*
X1775073Y39999D01*
G01X1774004Y45348D02*
X1775073Y39999D01*
G01D02*
X1774296Y36110D01*
G01X1775058Y64975D02*
X1777584Y62443D01*
G01X1774424Y63981D02*
X1776680Y61719D01*
G01X1777584Y62443D02*
X1781415Y56421D01*
G01X1776680Y61719D02*
X1780192Y56200D01*
G01X1781415Y56421D02*
X1779506Y47450D01*
G01X1780192Y56200D02*
X1778330Y47450D01*
G01X1779506D02*
X1780174Y44309D01*
G01X1778330Y47450D02*
X1779095Y43853D01*
G01X1780174Y44309D02*
X1783746Y38974D01*
G01X1779095Y43853D02*
X1782667Y38518D01*
G01X1778697Y55902D02*
X1775503Y60694D01*
G01X1774608Y59963D02*
X1777471Y55667D01*
G01X1776660Y46322D02*
X1778697Y55902D01*
G01X1777471Y55667D02*
X1776317Y50241D01*
G01X1776660Y46322D02*
X1778697Y55902D01*
G01X1775766Y47649D02*
X1775485Y46329D01*
G01X1777844Y40402D02*
X1776660Y46322D01*
G01X1775485Y46329D02*
X1776669Y40409D01*
G01X1776917Y36041D02*
X1777844Y40402D01*
G01X1776669Y40409D02*
X1775741Y36041D01*
G01X1801246Y33070D02*
X1802174Y34461D01*
G01X1803396Y34219D02*
X1802963Y36378D01*
G01X1802174Y34461D02*
X1801880Y35929D01*
G01X1802963Y36378D02*
X1800384Y40248D01*
G01X1801880Y35929D02*
X1799691Y39213D01*
G01X1800384Y40248D02*
X1794884Y41348D01*
G01X1799691Y39213D02*
X1794191Y40313D01*
G01X1794884Y41348D02*
X1788741Y50564D01*
G01X1794191Y40313D02*
X1789876Y46787D01*
G01X1794884Y41348D02*
X1788741Y50564D01*
G01X1788407Y48992D02*
X1787658Y50115D01*
G01X1788741Y50564D02*
X1787591Y56311D01*
G01X1787658Y50115D02*
X1786505Y55875D01*
G01X1774389Y71491D02*
X1777865Y66027D01*
G01X1774389Y71491D02*
X1777865Y66027D01*
G01X1775695Y67293D02*
X1776962Y65303D01*
G01X1777865Y66027D02*
X1778090Y65802D01*
G01D02*
X1779430Y64461D01*
G01X1776962Y65303D02*
X1778527Y63737D01*
G01X1779430Y64461D02*
X1784116Y57097D01*
G01X1778527Y63737D02*
X1782893Y56876D01*
G01X1784116Y57097D02*
X1782264Y48382D01*
G01X1782893Y56876D02*
X1781089Y48390D01*
G01X1782264Y48382D02*
X1782877Y45308D01*
G01X1781089Y48390D02*
X1781793Y44859D01*
G01X1782877Y45308D02*
X1786325Y40135D01*
G01X1781793Y44859D02*
X1785246Y39678D01*
G01X1774424Y63981D02*
X1776680Y61719D01*
G01X1775058Y64975D02*
X1777584Y62443D01*
G01X1776680Y61719D02*
X1780192Y56200D01*
G01X1777584Y62443D02*
X1781415Y56421D01*
G01X1780192Y56200D02*
X1778330Y47450D01*
G01X1781415Y56421D02*
X1779506Y47450D01*
G01X1778330D02*
X1779095Y43853D01*
G01X1779506Y47450D02*
X1780174Y44309D01*
G01X1779095Y43853D02*
X1782667Y38518D01*
G01X1780174Y44309D02*
X1783746Y38974D01*
G01X1776669Y40409D02*
X1775741Y36041D01*
G01X1776917D02*
X1777844Y40402D01*
G01X1775485Y46329D02*
X1776669Y40409D01*
G01X1777844Y40402D02*
X1776660Y46322D01*
G01X1777471Y55667D02*
X1776317Y50241D01*
G01X1775766Y47649D02*
X1775485Y46329D01*
G01X1776660Y46322D02*
X1778697Y55902D01*
G01X1774608Y59963D02*
X1777471Y55667D01*
G01X1778697Y55902D02*
X1775503Y60694D01*
G01X1801246Y33070D02*
X1802174Y34461D01*
G01D02*
X1801880Y35929D01*
G01X1803396Y34219D02*
X1802963Y36378D01*
G01X1801880Y35929D02*
X1799691Y39213D01*
G01X1802963Y36378D02*
X1800384Y40248D01*
G01X1799691Y39213D02*
X1794191Y40313D01*
G01X1800384Y40248D02*
X1794884Y41348D01*
G01X1794191Y40313D02*
X1789876Y46787D01*
G01X1788407Y48992D02*
X1787658Y50115D01*
G01X1794884Y41348D02*
X1788741Y50564D01*
G01X1787658Y50115D02*
X1786505Y55875D01*
G01X1788741Y50564D02*
X1787591Y56311D01*
G01X1775695Y67293D02*
X1776962Y65303D01*
G01X1774389Y71491D02*
X1777865Y66027D01*
G01X1776962Y65303D02*
X1778527Y63737D01*
G01X1777865Y66027D02*
X1778090Y65802D01*
G01X1776962Y65303D02*
X1778527Y63737D01*
G01X1778090Y65802D02*
X1779430Y64461D01*
G01X1778527Y63737D02*
X1782893Y56876D01*
G01X1779430Y64461D02*
X1784116Y57097D01*
G01X1782893Y56876D02*
X1781089Y48390D01*
G01X1784116Y57097D02*
X1782264Y48382D01*
G01X1781089Y48390D02*
X1781793Y44859D01*
G01X1782264Y48382D02*
X1782877Y45308D01*
G01X1781793Y44859D02*
X1785246Y39678D01*
G01X1782877Y45308D02*
X1786325Y40135D01*
G01X1837374Y249834D02*
X1831043Y256165D01*
G01X1837851Y250984D02*
X1831520Y257315D01*
G01X1837851Y250984D02*
X1831520Y257315D01*
G01X1837374Y249834D02*
X1831043Y256165D01*
G01X1849000Y253074D02*
Y251268D01*
G01X1847850Y253071D02*
Y251745D01*
G01X1849000Y251268D02*
X1847566Y249834D01*
G01X1847850Y251745D02*
X1847089Y250984D01*
G01X1847566Y249834D02*
X1837374D01*
G01X1847089Y250984D02*
X1837851D01*
G01X1847850Y253071D02*
Y251745D01*
G01X1849000Y253074D02*
Y251268D01*
G01X1847850Y251745D02*
X1847089Y250984D01*
G01X1849000Y251268D02*
X1847566Y249834D01*
G01X1847089Y250984D02*
X1837851D01*
G01X1847566Y249834D02*
X1837374D01*
G01X1857170Y254150D02*
Y256207D01*
G01X1856020Y253950D02*
Y255730D01*
G01X1857170Y256207D02*
X1852362Y261015D01*
G01X1856020Y255730D02*
X1851885Y259865D01*
G01X1856020Y253950D02*
Y255730D01*
G01X1857170Y254150D02*
Y256207D01*
G01X1856020Y255730D02*
X1851885Y259865D01*
G01X1857170Y256207D02*
X1852362Y261015D01*
G54D13*
G01X282036Y570211D02*
Y552200D01*
G01X283096Y564560D02*
Y563140D01*
G01X282036Y570211D02*
Y552200D01*
G01X283096Y559460D02*
Y558090D01*
G01X288420Y564800D02*
X287649Y564029D01*
G01X287419Y565300D02*
X286589Y564470D01*
G01X287649Y564029D02*
Y563138D01*
G01Y559648D02*
Y558371D01*
G01X286589Y564470D02*
Y557930D01*
G01X287649Y558371D02*
X288320Y557700D01*
G01X286589Y557930D02*
X287419Y557100D01*
G01X283096Y564560D02*
Y563140D01*
G01Y559460D02*
Y558090D01*
G01X282036Y570211D02*
Y552200D01*
G01X287419Y565300D02*
X286589Y564470D01*
G01X288420Y564800D02*
X287649Y564029D01*
G01X286589Y564470D02*
Y557930D01*
G01X287649Y564029D02*
Y563138D01*
G01X286589Y564470D02*
Y557930D01*
G01X287649Y559648D02*
Y558371D01*
G01X286589Y557930D02*
X287419Y557100D01*
G01X287649Y558371D02*
X288320Y557700D01*
G01X573151Y-46771D02*
X531716D01*
G01X572711Y-47831D02*
X531716D01*
G01X572711D02*
X531716D01*
G01X573151Y-46771D02*
X531716D01*
G01X499556Y570212D02*
Y552200D01*
G01X500616Y564560D02*
Y563140D01*
G01X499556Y570212D02*
Y552200D01*
G01X500616Y559460D02*
Y558090D01*
G01X536367Y570211D02*
Y552200D01*
G01X537427Y564560D02*
Y563140D01*
G01X536367Y570211D02*
Y552200D01*
G01X537427Y559460D02*
Y558090D01*
G01X505840Y557700D02*
X505169Y558371D01*
G01X504938Y557101D02*
X504109Y557930D01*
G01X505169Y558371D02*
Y559648D01*
G01Y563138D02*
Y564029D01*
G01X504109Y557930D02*
Y564470D01*
G01X505169Y564029D02*
X505940Y564800D01*
G01X504109Y564470D02*
X504938Y565299D01*
G01X500616Y564560D02*
Y563140D01*
G01Y559460D02*
Y558090D01*
G01X499556Y570212D02*
Y552200D01*
G01X537427Y564560D02*
Y563140D01*
G01Y559460D02*
Y558090D01*
G01X536367Y570211D02*
Y552200D01*
G01X504938Y557101D02*
X504109Y557930D01*
G01X505840Y557700D02*
X505169Y558371D01*
G01X504109Y557930D02*
Y564470D01*
G01X505169Y558371D02*
Y559648D01*
G01X504109Y557930D02*
Y564470D01*
G01X505169Y563138D02*
Y564029D01*
G01X504109Y564470D02*
X504938Y565299D01*
G01X505169Y564029D02*
X505940Y564800D01*
G01X777601Y-42660D02*
X583560D01*
G01X777601Y-43720D02*
X583560D01*
G01Y-42660D02*
G03Y-47440I0J-2390D01*
G01Y-43720D02*
G03Y-46380I0J-1330D01*
G01Y-47440D02*
X777156D01*
G01X583560Y-46380D02*
X777156D01*
G01Y-50100D02*
X576480D01*
G01X777156Y-51160D02*
X576040D01*
G01X576480Y-50100D02*
X573151Y-46771D01*
G01X576040Y-51160D02*
X572711Y-47831D01*
G01X777601Y-43720D02*
X583560D01*
G01X777601Y-42660D02*
X583560D01*
G01Y-43720D02*
G03Y-46380I0J-1330D01*
G01Y-42660D02*
G03Y-47440I0J-2390D01*
G01Y-46380D02*
X777156D01*
G01X583560Y-47440D02*
X777156D01*
G01Y-51160D02*
X576040D01*
G01X777156Y-50100D02*
X576480D01*
G01X576040Y-51160D02*
X572711Y-47831D01*
G01X576480Y-50100D02*
X573151Y-46771D01*
G01X541980Y558371D02*
X542651Y557700D01*
G01X541749Y557101D02*
X540920Y557930D01*
G01X541980Y564029D02*
Y563138D01*
G01Y559648D02*
Y558371D01*
G01X540920Y557930D02*
Y564470D01*
G01X542751Y564800D02*
X541980Y564029D01*
G01X540920Y564470D02*
X541749Y565299D01*
G01X540920Y564470D02*
X541749Y565299D01*
G01X542751Y564800D02*
X541980Y564029D01*
G01X540920Y557930D02*
Y564470D01*
G01X541980Y564029D02*
Y563138D01*
G01X540920Y557930D02*
Y564470D01*
G01X541980Y559648D02*
Y558371D01*
G01X541749Y557101D02*
X540920Y557930D01*
G01X541980Y558371D02*
X542651Y557700D01*
G01X777156Y-47440D02*
G02Y-50100I0J-1330D01*
G01Y-46380D02*
G02Y-51160I0J-2390D01*
G01Y-46380D02*
G02Y-51160I0J-2390D01*
G01Y-47440D02*
G02Y-50100I0J-1330D01*
G01X931644Y570211D02*
Y552200D01*
G01X932704Y564560D02*
Y563140D01*
G01X931644Y570211D02*
Y552200D01*
G01X932704Y559460D02*
Y558090D01*
G01X938028Y564800D02*
X937257Y564029D01*
G01X937027Y565300D02*
X936197Y564470D01*
G01X937257Y564029D02*
Y563138D01*
G01Y559648D02*
Y558371D01*
G01X936197Y564470D02*
Y557930D01*
G01X937257Y558371D02*
X937928Y557700D01*
G01X936197Y557930D02*
X937027Y557100D01*
G01X932704Y564560D02*
Y563140D01*
G01Y559460D02*
Y558090D01*
G01X931644Y570211D02*
Y552200D01*
G01X937027Y565300D02*
X936197Y564470D01*
G01X938028Y564800D02*
X937257Y564029D01*
G01X936197Y564470D02*
Y557930D01*
G01X937257Y564029D02*
Y563138D01*
G01X936197Y564470D02*
Y557930D01*
G01X937257Y559648D02*
Y558371D01*
G01X936197Y557930D02*
X937027Y557100D01*
G01X937257Y558371D02*
X937928Y557700D01*
G01X1149164Y570212D02*
Y552200D01*
G01X1150224Y564560D02*
Y563140D01*
G01X1149164Y570212D02*
Y552200D01*
G01X1150224Y559460D02*
Y558090D01*
G01X1155448Y557700D02*
X1154777Y558371D01*
G01X1154546Y557101D02*
X1153717Y557930D01*
G01X1154777Y558371D02*
Y559648D01*
G01Y563138D02*
Y564029D01*
G01X1153717Y557930D02*
Y564470D01*
G01X1154777Y564029D02*
X1155548Y564800D01*
G01X1153717Y564470D02*
X1154546Y565299D01*
G01X1150224Y564560D02*
Y563140D01*
G01Y559460D02*
Y558090D01*
G01X1149164Y570212D02*
Y552200D01*
G01X1154546Y557101D02*
X1153717Y557930D01*
G01X1155448Y557700D02*
X1154777Y558371D01*
G01X1153717Y557930D02*
Y564470D01*
G01X1154777Y558371D02*
Y559648D01*
G01X1153717Y557930D02*
Y564470D01*
G01X1154777Y563138D02*
Y564029D01*
G01X1153717Y564470D02*
X1154546Y565299D01*
G01X1154777Y564029D02*
X1155548Y564800D01*
G01X1185975Y570211D02*
Y552200D01*
G01X1187035Y564560D02*
Y563140D01*
G01X1185975Y570211D02*
Y552200D01*
G01X1187035Y559460D02*
Y558090D01*
G01X1191588Y558371D02*
X1192259Y557700D01*
G01X1191357Y557101D02*
X1190528Y557930D01*
G01X1191588Y564029D02*
Y563138D01*
G01Y559648D02*
Y558371D01*
G01X1190528Y557930D02*
Y564470D01*
G01X1192359Y564800D02*
X1191588Y564029D01*
G01X1190528Y564470D02*
X1191357Y565299D01*
G01X1187035Y564560D02*
Y563140D01*
G01Y559460D02*
Y558090D01*
G01X1185975Y570211D02*
Y552200D01*
G01X1190528Y564470D02*
X1191357Y565299D01*
G01X1192359Y564800D02*
X1191588Y564029D01*
G01X1190528Y557930D02*
Y564470D01*
G01X1191588Y564029D02*
Y563138D01*
G01X1190528Y557930D02*
Y564470D01*
G01X1191588Y559648D02*
Y558371D01*
G01X1191357Y557101D02*
X1190528Y557930D01*
G01X1191588Y558371D02*
X1192259Y557700D01*
G54D14*
G01X57936Y14510D02*
X42600Y29846D01*
G01X59587Y15194D02*
X44251Y30530D01*
G01X42600Y29846D02*
Y82865D01*
G01X44251Y30530D02*
Y83549D01*
G01X59587Y15194D02*
X44251Y30530D01*
G01X57936Y14510D02*
X42600Y29846D01*
G01X44251Y30530D02*
Y83549D01*
G01X42600Y29846D02*
Y82865D01*
G01D02*
X39837Y85628D01*
G01X44251Y83549D02*
X41488Y86312D01*
G01X39837Y85628D02*
Y91462D01*
G01X41488Y86312D02*
Y92146D01*
G01X39837Y91462D02*
X36458Y94841D01*
G01X41488Y92146D02*
X38109Y95525D01*
G01X44251Y83549D02*
X41488Y86312D01*
G01X42600Y82865D02*
X39837Y85628D01*
G01X41488Y86312D02*
Y92146D01*
G01X39837Y85628D02*
Y91462D01*
G01X41488Y92146D02*
X38109Y95525D01*
G01X39837Y91462D02*
X36458Y94841D01*
G01X48051Y85749D02*
X45735Y88065D01*
G01X46400Y85065D02*
X44084Y87381D01*
G01X45735Y88065D02*
Y93505D01*
G01X44084Y87381D02*
Y92821D01*
G01X45735Y93505D02*
X42259Y96981D01*
G01X44084Y92821D02*
X40608Y96297D01*
G01X46400Y85065D02*
X44084Y87381D01*
G01X48051Y85749D02*
X45735Y88065D01*
G01X44084Y87381D02*
Y92821D01*
G01X45735Y88065D02*
Y93505D01*
G01X44084Y92821D02*
X40608Y96297D01*
G01X45735Y93505D02*
X42259Y96981D01*
G01X36458Y94841D02*
Y118944D01*
G01X38109Y95525D02*
Y119628D01*
G01X36458Y118944D02*
X35559Y119843D01*
G01X38109Y119628D02*
X36243Y121494D01*
G01X35559Y119843D02*
X-11604D01*
G01X36243Y121494D02*
X-10920D01*
G01X-11604Y119843D02*
X-13424Y121663D01*
G01X-10920Y121494D02*
X-11773Y122347D01*
G01X-13424Y121663D02*
Y122914D01*
G01X-11773Y122347D02*
Y122913D01*
G01X38109Y95525D02*
Y119628D01*
G01X36458Y94841D02*
Y118944D01*
G01X38109Y119628D02*
X36243Y121494D01*
G01X36458Y118944D02*
X35559Y119843D01*
G01X36243Y121494D02*
X-10920D01*
G01X35559Y119843D02*
X-11604D01*
G01X-10920Y121494D02*
X-11773Y122347D01*
G01X-11604Y119843D02*
X-13424Y121663D01*
G01X-11773Y122347D02*
Y122913D01*
G01X-13424Y121663D02*
Y122914D01*
G01X42259Y96981D02*
Y121556D01*
G01X40608Y96297D02*
Y120872D01*
G01X42259Y121556D02*
X34426Y129389D01*
G01X40608Y120872D02*
X33742Y127738D01*
G01X34426Y129389D02*
X4477D01*
G01X33742Y127738D02*
X5161D01*
G01X4477Y129389D02*
X3111Y128023D01*
G01X5161Y127738D02*
X4762Y127339D01*
G01X3111Y128023D02*
Y126772D01*
G01X4762Y127339D02*
Y126774D01*
G01X40608Y96297D02*
Y120872D01*
G01X42259Y96981D02*
Y121556D01*
G01X40608Y120872D02*
X33742Y127738D01*
G01X42259Y121556D02*
X34426Y129389D01*
G01X33742Y127738D02*
X5161D01*
G01X34426Y129389D02*
X4477D01*
G01X5161Y127738D02*
X4762Y127339D01*
G01X4477Y129389D02*
X3111Y128023D01*
G01X4762Y127339D02*
Y126774D01*
G01X3111Y128023D02*
Y126772D01*
G01X113532Y10933D02*
X105241D01*
G01X114216Y12584D02*
X104557D01*
G01X105241Y10933D02*
X98285Y3977D01*
G01X104557Y12584D02*
X97601Y5628D01*
G01X98285Y3977D02*
X66597D01*
G01X97601Y5628D02*
X67281D01*
G01X66597Y3977D02*
X57936Y12638D01*
G01X67281Y5628D02*
X59587Y13322D01*
G01X57936Y12638D02*
Y14510D01*
G01X59587Y13322D02*
Y15194D01*
G01X114216Y12584D02*
X104557D01*
G01X113532Y10933D02*
X105241D01*
G01X104557Y12584D02*
X97601Y5628D01*
G01X105241Y10933D02*
X98285Y3977D01*
G01X97601Y5628D02*
X67281D01*
G01X98285Y3977D02*
X66597D01*
G01X67281Y5628D02*
X59587Y13322D01*
G01X66597Y3977D02*
X57936Y12638D01*
G01X59587Y13322D02*
Y15194D01*
G01X57936Y12638D02*
Y14510D01*
G01X108569Y23535D02*
X56819D01*
G01X109253Y21884D02*
X56135D01*
G01X56819Y23535D02*
X48051Y32303D01*
G01X56135Y21884D02*
X46400Y31619D01*
G01X48051Y32303D02*
Y85749D01*
G01X46400Y31619D02*
Y85065D01*
G01X109253Y21884D02*
X56135D01*
G01X108569Y23535D02*
X56819D01*
G01X56135Y21884D02*
X46400Y31619D01*
G01X56819Y23535D02*
X48051Y32303D01*
G01X46400Y31619D02*
Y85065D01*
G01X48051Y32303D02*
Y85749D01*
G01X370336Y4500D02*
X119965D01*
G01X369652Y6151D02*
X120649D01*
G01X119965Y4500D02*
X113532Y10933D01*
G01X120649Y6151D02*
X114216Y12584D01*
G01X369652Y6151D02*
X120649D01*
G01X370336Y4500D02*
X119965D01*
G01X120649Y6151D02*
X114216Y12584D01*
G01X119965Y4500D02*
X113532Y10933D01*
G01X375905Y25486D02*
X110520D01*
G01X375221Y23835D02*
X111204D01*
G01X110520Y25486D02*
X108569Y23535D01*
G01X111204Y23835D02*
X109253Y21884D01*
G01X375221Y23835D02*
X111204D01*
G01X375905Y25486D02*
X110520D01*
G01X111204Y23835D02*
X109253Y21884D01*
G01X110520Y25486D02*
X108569Y23535D01*
G01X616915Y4229D02*
X384709D01*
G01X616231Y5880D02*
X385393D01*
G01X384709Y4229D02*
X379979Y8959D01*
G01X385393Y5880D02*
X380663Y10610D01*
G01X379979Y8959D02*
X374795D01*
G01X380663Y10610D02*
X374111D01*
G01X374795Y8959D02*
X370336Y4500D01*
G01X374111Y10610D02*
X369652Y6151D01*
G01X616231Y5880D02*
X385393D01*
G01X616915Y4229D02*
X384709D01*
G01X385393Y5880D02*
X380663Y10610D01*
G01X384709Y4229D02*
X379979Y8959D01*
G01X380663Y10610D02*
X374111D01*
G01X379979Y8959D02*
X374795D01*
G01X374111Y10610D02*
X369652Y6151D01*
G01X374795Y8959D02*
X370336Y4500D01*
G01X613888Y22844D02*
X392656D01*
G01X614572Y21193D02*
X391972D01*
G01X392656Y22844D02*
X391876Y23624D01*
G01X391972Y21193D02*
X391192Y21973D01*
G01X391876Y23624D02*
X383880D01*
G01X391192Y21973D02*
X384564D01*
G01X383880Y23624D02*
X383089Y22833D01*
G01X384564Y21973D02*
X383773Y21182D01*
G01X383089Y22833D02*
X378558D01*
G01X383773Y21182D02*
X377874D01*
G01X378558Y22833D02*
X375905Y25486D01*
G01X377874Y21182D02*
X375221Y23835D01*
G01X614572Y21193D02*
X391972D01*
G01X613888Y22844D02*
X392656D01*
G01X391972Y21193D02*
X391192Y21973D01*
G01X392656Y22844D02*
X391876Y23624D01*
G01X391192Y21973D02*
X384564D01*
G01X391876Y23624D02*
X383880D01*
G01X384564Y21973D02*
X383773Y21182D01*
G01X383880Y23624D02*
X383089Y22833D01*
G01X383773Y21182D02*
X377874D01*
G01X383089Y22833D02*
X378558D01*
G01X377874Y21182D02*
X375221Y23835D01*
G01X378558Y22833D02*
X375905Y25486D01*
G01X667019Y33523D02*
X660878Y27382D01*
G01X665368Y34207D02*
X660194Y29033D01*
G01X660878Y27382D02*
X645526D01*
G01X660194Y29033D02*
X644842D01*
G01X645526Y27382D02*
X640359Y22215D01*
G01X644842Y29033D02*
X639675Y23866D01*
G01X640359Y22215D02*
X634901D01*
G01X639675Y23866D02*
X634217D01*
G01X634901Y22215D02*
X616915Y4229D01*
G01X634217Y23866D02*
X616231Y5880D01*
G01X665368Y34207D02*
X660194Y29033D01*
G01X667019Y33523D02*
X660878Y27382D01*
G01X660194Y29033D02*
X644842D01*
G01X660878Y27382D02*
X645526D01*
G01X644842Y29033D02*
X639675Y23866D01*
G01X645526Y27382D02*
X640359Y22215D01*
G01X639675Y23866D02*
X634217D01*
G01X640359Y22215D02*
X634901D01*
G01X634217Y23866D02*
X616231Y5880D01*
G01X634901Y22215D02*
X616915Y4229D01*
G01X626605Y35561D02*
X613888Y22844D01*
G01X628256Y34877D02*
X614572Y21193D01*
G01X628256Y34877D02*
X614572Y21193D01*
G01X626605Y35561D02*
X613888Y22844D01*
G01X675920Y41511D02*
X654034D01*
G01X675236Y39860D02*
X653350D01*
G01X654034Y41511D02*
X652237Y43308D01*
G01X653350Y39860D02*
X651553Y41657D01*
G01X652237Y43308D02*
X633457D01*
G01X651553Y41657D02*
X634141D01*
G01X633457Y43308D02*
X626605Y36456D01*
G01X634141Y41657D02*
X628256Y35772D01*
G01X675236Y39860D02*
X653350D01*
G01X675920Y41511D02*
X654034D01*
G01X653350Y39860D02*
X651553Y41657D01*
G01X654034Y41511D02*
X652237Y43308D01*
G01X651553Y41657D02*
X634141D01*
G01X652237Y43308D02*
X633457D01*
G01X634141Y41657D02*
X628256Y35772D01*
G01X633457Y43308D02*
X626605Y36456D01*
G01X747687Y19791D02*
X708310D01*
G01X748371Y21442D02*
X708994D01*
G01X708310Y19791D02*
X705252Y22849D01*
G01X708994Y21442D02*
X705936Y24500D01*
G01X705252Y22849D02*
X694762D01*
G01X705936Y24500D02*
X695446D01*
G01X694762Y22849D02*
X687662Y29949D01*
G01X695446Y24500D02*
X688346Y31600D01*
G01X687662Y29949D02*
X677140D01*
G01X688346Y31600D02*
X677824D01*
G01X677140Y29949D02*
X671060Y36029D01*
G01X677824Y31600D02*
X671744Y37680D01*
G01X748371Y21442D02*
X708994D01*
G01X747687Y19791D02*
X708310D01*
G01X708994Y21442D02*
X705936Y24500D01*
G01X708310Y19791D02*
X705252Y22849D01*
G01X705936Y24500D02*
X695446D01*
G01X705252Y22849D02*
X694762D01*
G01X695446Y24500D02*
X688346Y31600D01*
G01X694762Y22849D02*
X687662Y29949D01*
G01X688346Y31600D02*
X677824D01*
G01X687662Y29949D02*
X677140D01*
G01X677824Y31600D02*
X671744Y37680D01*
G01X677140Y29949D02*
X671060Y36029D01*
G01X726036Y32184D02*
X698283D01*
G01X725352Y30533D02*
X697599D01*
G01X698283Y32184D02*
X694667Y35800D01*
G01X697599Y30533D02*
X693983Y34149D01*
G01X725352Y30533D02*
X697599D01*
G01X726036Y32184D02*
X698283D01*
G01X697599Y30533D02*
X693983Y34149D01*
G01X698283Y32184D02*
X694667Y35800D01*
G01X671060Y36029D02*
X668035D01*
G01X671744Y37680D02*
X667351D01*
G01X668035Y36029D02*
X667019Y35013D01*
G01X667351Y37680D02*
X665368Y35697D01*
G01X667019Y35013D02*
Y33523D01*
G01X665368Y35697D02*
Y34207D01*
G01X671744Y37680D02*
X667351D01*
G01X671060Y36029D02*
X668035D01*
G01X667351Y37680D02*
X665368Y35697D01*
G01X668035Y36029D02*
X667019Y35013D01*
G01X665368Y35697D02*
Y34207D01*
G01X667019Y35013D02*
Y33523D01*
G01X694667Y35800D02*
X681631D01*
G01X693983Y34149D02*
X680947D01*
G01X681631Y35800D02*
X675920Y41511D01*
G01X680947Y34149D02*
X675236Y39860D01*
G01X693983Y34149D02*
X680947D01*
G01X694667Y35800D02*
X681631D01*
G01X680947Y34149D02*
X675236Y39860D01*
G01X681631Y35800D02*
X675920Y41511D01*
G01X1019092Y5300D02*
X767051D01*
G01X1018408Y6951D02*
X767735D01*
G01X767051Y5300D02*
X759973Y12378D01*
G01X767735Y6951D02*
X760657Y14029D01*
G01X759973Y12378D02*
X755100D01*
G01X760657Y14029D02*
X755784D01*
G01X755100Y12378D02*
X747687Y19791D01*
G01X755784Y14029D02*
X748371Y21442D01*
G01X1018408Y6951D02*
X767735D01*
G01X1019092Y5300D02*
X767051D01*
G01X767735Y6951D02*
X760657Y14029D01*
G01X767051Y5300D02*
X759973Y12378D01*
G01X760657Y14029D02*
X755784D01*
G01X759973Y12378D02*
X755100D01*
G01X755784Y14029D02*
X748371Y21442D01*
G01X755100Y12378D02*
X747687Y19791D01*
G01X1020148Y21030D02*
X763628D01*
G01X1020832Y19379D02*
X762944D01*
G01X763628Y21030D02*
X757212Y27446D01*
G01X762944Y19379D02*
X756528Y25795D01*
G01X757212Y27446D02*
X751599D01*
G01X756528Y25795D02*
X752283D01*
G01X751599Y27446D02*
X749406Y25253D01*
G01X752283Y25795D02*
X750090Y23602D01*
G01X749406Y25253D02*
X732967D01*
G01X750090Y23602D02*
X732283D01*
G01X732967Y25253D02*
X726036Y32184D01*
G01X732283Y23602D02*
X725352Y30533D01*
G01X1020832Y19379D02*
X762944D01*
G01X1020148Y21030D02*
X763628D01*
G01X762944Y19379D02*
X756528Y25795D01*
G01X763628Y21030D02*
X757212Y27446D01*
G01X756528Y25795D02*
X752283D01*
G01X757212Y27446D02*
X751599D01*
G01X752283Y25795D02*
X750090Y23602D01*
G01X751599Y27446D02*
X749406Y25253D01*
G01X750090Y23602D02*
X732283D01*
G01X749406Y25253D02*
X732967D01*
G01X732283Y23602D02*
X725352Y30533D01*
G01X732967Y25253D02*
X726036Y32184D01*
G01X1041732Y21705D02*
X1033162D01*
G01X1033846Y20054D02*
X1019092Y5300D01*
G01X1033162Y21705D02*
X1018408Y6951D01*
G01X1041732Y21705D02*
X1033162D01*
G01D02*
X1018408Y6951D01*
G01X1033846Y20054D02*
X1019092Y5300D01*
G01X1034823Y23677D02*
X1032200Y26300D01*
G01D02*
Y27245D01*
G01X1033851Y27929D02*
X1032179Y29601D01*
G01X1032200Y27245D02*
X1031495Y27950D01*
G01X1032179Y29601D02*
X1028719D01*
G01D02*
X1020148Y21030D01*
G01X1031495Y27950D02*
X1029403D01*
G01X1028719Y29601D02*
X1020148Y21030D01*
G01X1029403Y27950D02*
X1020832Y19379D01*
G01X1034823Y23677D02*
X1032200Y26300D01*
G01D02*
Y27245D01*
G01D02*
X1031495Y27950D01*
G01X1033851Y27929D02*
X1032179Y29601D01*
G01X1031495Y27950D02*
X1029403D01*
G01X1032179Y29601D02*
X1028719D01*
G01X1031495Y27950D02*
X1029403D01*
G01D02*
X1020832Y19379D01*
G01X1028719Y29601D02*
X1020148Y21030D01*
G01X1273485Y19408D02*
X1041694D01*
G01X1272801Y21059D02*
X1042378D01*
G01X1041048Y20054D02*
X1033846D01*
G01X1272801Y21059D02*
X1042378D01*
G01X1273485Y19408D02*
X1041694D01*
G01X1041048Y20054D02*
X1033846D01*
G01X1270638Y25328D02*
X1035507D01*
G01X1271322Y23677D02*
X1034823D01*
G01X1035507Y25328D02*
X1033851Y26984D01*
G01D02*
Y27929D01*
G01X1271322Y23677D02*
X1034823D01*
G01X1270638Y25328D02*
X1035507D01*
G01D02*
X1033851Y26984D01*
G01D02*
Y27929D01*
G01X1278993Y35461D02*
Y27251D01*
G01X1280644Y26567D02*
X1273485Y19408D01*
G01X1278993Y27251D02*
X1272801Y21059D01*
G01X1278993Y35461D02*
Y27251D01*
G01D02*
X1272801Y21059D01*
G01X1280644Y26567D02*
X1273485Y19408D01*
G01X1274843Y37391D02*
Y29533D01*
G01X1276494Y36707D02*
Y28849D01*
G01X1274843Y29533D02*
X1270638Y25328D01*
G01X1276494Y28849D02*
X1271322Y23677D01*
G01X1276494Y36707D02*
Y28849D01*
G01X1274843Y37391D02*
Y29533D01*
G01X1276494Y28849D02*
X1271322Y23677D01*
G01X1274843Y29533D02*
X1270638Y25328D01*
G01X1284062Y40530D02*
X1278993Y35461D01*
G01X1284062Y40530D02*
X1278993Y35461D01*
G01X1281570Y44118D02*
X1274843Y37391D01*
G01X1282254Y42467D02*
X1276494Y36707D01*
G01X1282254Y42467D02*
X1276494Y36707D01*
G01X1281570Y44118D02*
X1274843Y37391D01*
G01X1280644Y34777D02*
Y26567D01*
G01Y34777D02*
Y26567D01*
G01X1315027Y129762D02*
Y60027D01*
G01X1313376Y130446D02*
Y60711D01*
G01X1315027Y60027D02*
X1306901Y51901D01*
G01X1313376Y60711D02*
X1305250Y52585D01*
G01X1306901Y51901D02*
Y47723D01*
G01X1305250Y52585D02*
Y48407D01*
G01X1306901Y47723D02*
X1299728Y40550D01*
G01X1305250Y48407D02*
X1299044Y42201D01*
G01X1299728Y40550D02*
X1295154D01*
G01X1299044Y42201D02*
X1294470D01*
G01X1295154Y40550D02*
X1293483Y38879D01*
G01X1294470Y42201D02*
X1292799Y40530D01*
G01X1293483Y38879D02*
X1284746D01*
G01X1292799Y40530D02*
X1284062D01*
G01X1284746Y38879D02*
X1280644Y34777D01*
G01X1313376Y130446D02*
Y60711D01*
G01X1315027Y129762D02*
Y60027D01*
G01X1313376Y60711D02*
X1305250Y52585D01*
G01X1315027Y60027D02*
X1306901Y51901D01*
G01X1305250Y52585D02*
Y48407D01*
G01X1306901Y51901D02*
Y47723D01*
G01X1305250Y48407D02*
X1299044Y42201D01*
G01X1306901Y47723D02*
X1299728Y40550D01*
G01X1299044Y42201D02*
X1294470D01*
G01X1299728Y40550D02*
X1295154D01*
G01X1294470Y42201D02*
X1292799Y40530D01*
G01X1295154Y40550D02*
X1293483Y38879D01*
G01X1292799Y40530D02*
X1284062D01*
G01X1293483Y38879D02*
X1284746D01*
G01D02*
X1280644Y34777D01*
G01X1304746Y97481D02*
Y84245D01*
G01X1306397Y96797D02*
Y83561D01*
G01X1304746Y84245D02*
X1300876Y80375D01*
G01X1306397Y83561D02*
X1302527Y79691D01*
G01X1300876Y80375D02*
Y67979D01*
G01X1302527Y79691D02*
Y68663D01*
G01X1300876Y67979D02*
X1306316Y62539D01*
G01X1302527Y68663D02*
X1307967Y63223D01*
G01X1306316Y62539D02*
Y59816D01*
G01X1307967Y63223D02*
Y59132D01*
G01X1306316Y59816D02*
X1301100Y54600D01*
G01X1307967Y59132D02*
X1302751Y53916D01*
G01X1301100Y54600D02*
Y50127D01*
G01X1302751Y53916D02*
Y49443D01*
G01X1301100Y50127D02*
X1297324Y46351D01*
G01X1302751Y49443D02*
X1298008Y44700D01*
G01X1297324Y46351D02*
X1292661D01*
G01X1298008Y44700D02*
X1293345D01*
G01X1292661Y46351D02*
X1290428Y44118D01*
G01X1293345Y44700D02*
X1291112Y42467D01*
G01X1290428Y44118D02*
X1281570D01*
G01X1291112Y42467D02*
X1282254D01*
G01X1306397Y96797D02*
Y83561D01*
G01X1304746Y97481D02*
Y84245D01*
G01X1306397Y83561D02*
X1302527Y79691D01*
G01X1304746Y84245D02*
X1300876Y80375D01*
G01X1302527Y79691D02*
Y68663D01*
G01X1300876Y80375D02*
Y67979D01*
G01X1302527Y68663D02*
X1307967Y63223D01*
G01X1300876Y67979D02*
X1306316Y62539D01*
G01X1307967Y63223D02*
Y59132D01*
G01X1306316Y62539D02*
Y59816D01*
G01X1307967Y59132D02*
X1302751Y53916D01*
G01X1306316Y59816D02*
X1301100Y54600D01*
G01X1302751Y53916D02*
Y49443D01*
G01X1301100Y54600D02*
Y50127D01*
G01X1302751Y49443D02*
X1298008Y44700D01*
G01X1301100Y50127D02*
X1297324Y46351D01*
G01X1298008Y44700D02*
X1293345D01*
G01X1297324Y46351D02*
X1292661D01*
G01X1293345Y44700D02*
X1291112Y42467D01*
G01X1292661Y46351D02*
X1290428Y44118D01*
G01X1291112Y42467D02*
X1282254D01*
G01X1290428Y44118D02*
X1281570D01*
G01X1398516Y135349D02*
X1320614D01*
G01X1399200Y137000D02*
X1319930D01*
G01X1320614Y135349D02*
X1315027Y129762D01*
G01X1319930Y137000D02*
X1313376Y130446D01*
G01X1399200Y137000D02*
X1319930D01*
G01X1398516Y135349D02*
X1320614D01*
G01X1319930Y137000D02*
X1313376Y130446D01*
G01X1320614Y135349D02*
X1315027Y129762D01*
G01X1401500Y141000D02*
X1317861D01*
G01X1400816Y139349D02*
X1318545D01*
G01X1317861Y141000D02*
X1309017Y132156D01*
G01X1318545Y139349D02*
X1310668Y131472D01*
G01X1309017Y132156D02*
Y101752D01*
G01X1310668Y131472D02*
Y101068D01*
G01X1309017Y101752D02*
X1304746Y97481D01*
G01X1310668Y101068D02*
X1306397Y96797D01*
G01X1400816Y139349D02*
X1318545D01*
G01X1401500Y141000D02*
X1317861D01*
G01X1318545Y139349D02*
X1310668Y131472D01*
G01X1317861Y141000D02*
X1309017Y132156D01*
G01X1310668Y131472D02*
Y101068D01*
G01X1309017Y132156D02*
Y101752D01*
G01X1310668Y101068D02*
X1306397Y96797D01*
G01X1309017Y101752D02*
X1304746Y97481D01*
G01X1403882Y129983D02*
X1398516Y135349D01*
G01X1405533Y130667D02*
X1399200Y137000D01*
G01X1405533Y130667D02*
X1399200Y137000D01*
G01X1403882Y129983D02*
X1398516Y135349D01*
G01X1409800Y132700D02*
X1401500Y141000D01*
G01X1408149Y132016D02*
X1400816Y139349D01*
G01X1408149Y132016D02*
X1400816Y139349D01*
G01X1409800Y132700D02*
X1401500Y141000D01*
G01X1489027Y22638D02*
X1447162D01*
G01X1489711Y24289D02*
X1447846D01*
G01X1447162Y22638D02*
X1438132Y31668D01*
G01X1447846Y24289D02*
X1439783Y32352D01*
G01X1438132Y31668D02*
Y42013D01*
G01X1439783Y32352D02*
Y42697D01*
G01X1489711Y24289D02*
X1447846D01*
G01X1489027Y22638D02*
X1447162D01*
G01X1447846Y24289D02*
X1439783Y32352D01*
G01X1447162Y22638D02*
X1438132Y31668D01*
G01X1439783Y32352D02*
Y42697D01*
G01X1438132Y31668D02*
Y42013D01*
G01X1492230Y28106D02*
X1449565D01*
G01X1491546Y26455D02*
X1448881D01*
G01X1449565Y28106D02*
X1446708Y30963D01*
G01X1448881Y26455D02*
X1445057Y30279D01*
G01X1446708Y30963D02*
Y35372D01*
G01X1445057Y30279D02*
Y34688D01*
G01X1491546Y26455D02*
X1448881D01*
G01X1492230Y28106D02*
X1449565D01*
G01X1448881Y26455D02*
X1445057Y30279D01*
G01X1449565Y28106D02*
X1446708Y30963D01*
G01X1445057Y30279D02*
Y34688D01*
G01X1446708Y30963D02*
Y35372D01*
G01X1438132Y42013D02*
X1427290Y52855D01*
G01X1439783Y42697D02*
X1428941Y53539D01*
G01X1427290Y52855D02*
Y74254D01*
G01X1428941Y53539D02*
Y74938D01*
G01X1427290Y74254D02*
X1423283Y78261D01*
G01X1428941Y74938D02*
X1424934Y78945D01*
G01X1423283Y78261D02*
Y87711D01*
G01X1424934Y78945D02*
Y88395D01*
G01X1423283Y87711D02*
X1413038Y97956D01*
G01X1424934Y88395D02*
X1414689Y98640D01*
G01X1439783Y42697D02*
X1428941Y53539D01*
G01X1438132Y42013D02*
X1427290Y52855D01*
G01X1428941Y53539D02*
Y74938D01*
G01X1427290Y52855D02*
Y74254D01*
G01X1428941Y74938D02*
X1424934Y78945D01*
G01X1427290Y74254D02*
X1423283Y78261D01*
G01X1424934Y78945D02*
Y88395D01*
G01X1423283Y78261D02*
Y87711D01*
G01X1424934Y88395D02*
X1414689Y98640D01*
G01X1423283Y87711D02*
X1413038Y97956D01*
G01X1446708Y35372D02*
X1443651Y38429D01*
G01X1445057Y34688D02*
X1442967Y36778D01*
G01X1446708Y35372D02*
X1443651Y38429D01*
G01X1442966Y36779D02*
X1442000Y37745D01*
G01X1443651Y38429D02*
Y44699D01*
G01X1442000Y37745D02*
Y44015D01*
G01X1443651Y44699D02*
X1433091Y55259D01*
G01X1442000Y44015D02*
X1431440Y54575D01*
G01X1433091Y55259D02*
Y76182D01*
G01X1431440Y54575D02*
Y75498D01*
G01X1433091Y76182D02*
X1429084Y80189D01*
G01X1431440Y75498D02*
X1427433Y79505D01*
G01X1429084Y80189D02*
Y90115D01*
G01X1427433Y79505D02*
Y89431D01*
G01X1429084Y90115D02*
X1418839Y100360D01*
G01X1427433Y89431D02*
X1417188Y99676D01*
G01X1445057Y34688D02*
X1442967Y36778D01*
G01X1442966Y36779D02*
X1442000Y37745D01*
G01X1446708Y35372D02*
X1443651Y38429D01*
G01X1442000Y37745D02*
Y44015D01*
G01X1443651Y38429D02*
Y44699D01*
G01X1442000Y44015D02*
X1431440Y54575D01*
G01X1443651Y44699D02*
X1433091Y55259D01*
G01X1431440Y54575D02*
Y75498D01*
G01X1433091Y55259D02*
Y76182D01*
G01X1431440Y75498D02*
X1427433Y79505D01*
G01X1433091Y76182D02*
X1429084Y80189D01*
G01X1427433Y79505D02*
Y89431D01*
G01X1429084Y80189D02*
Y90115D01*
G01X1427433Y89431D02*
X1417188Y99676D01*
G01X1429084Y90115D02*
X1418839Y100360D01*
G01X1413038Y97956D02*
Y119198D01*
G01X1414689Y98640D02*
Y119882D01*
G01X1413038Y119198D02*
X1403882Y128354D01*
G01X1414689Y119882D02*
X1405533Y129038D01*
G01X1403882Y128354D02*
Y129983D01*
G01X1405533Y129038D02*
Y130667D01*
G01X1414689Y98640D02*
Y119882D01*
G01X1413038Y97956D02*
Y119198D01*
G01X1414689Y119882D02*
X1405533Y129038D01*
G01X1413038Y119198D02*
X1403882Y128354D01*
G01X1405533Y129038D02*
Y130667D01*
G01X1403882Y128354D02*
Y129983D01*
G01X1418839Y100360D02*
Y121872D01*
G01X1417188Y99676D02*
Y121188D01*
G01X1418839Y121872D02*
X1409800Y130911D01*
G01X1417188Y121188D02*
X1408149Y130227D01*
G01X1409800Y130911D02*
Y132700D01*
G01X1408149Y130227D02*
Y132016D01*
G01X1417188Y99676D02*
Y121188D01*
G01X1418839Y100360D02*
Y121872D01*
G01X1417188Y121188D02*
X1408149Y130227D01*
G01X1418839Y121872D02*
X1409800Y130911D01*
G01X1408149Y130227D02*
Y132016D01*
G01X1409800Y130911D02*
Y132700D01*
G01X1591264Y-5000D02*
X1523363D01*
G01X1591948Y-3349D02*
X1524047D01*
G01X1523263Y-4900D02*
X1521937D01*
G01X1523947Y-3249D02*
X1521253D01*
G01X1521837Y-5000D02*
X1505022D01*
G01X1521153Y-3349D02*
X1505706D01*
G01X1505022Y-5000D02*
X1499823Y199D01*
G01X1505706Y-3349D02*
X1501474Y883D01*
G01X1499823Y199D02*
Y11842D01*
G01X1501474Y883D02*
Y12526D01*
G01X1499823Y11842D02*
X1489027Y22638D01*
G01X1501474Y12526D02*
X1489711Y24289D01*
G01X1591948Y-3349D02*
X1524047D01*
G01X1591264Y-5000D02*
X1523363D01*
G01X1523947Y-3249D02*
X1521253D01*
G01X1523263Y-4900D02*
X1521937D01*
G01X1521153Y-3349D02*
X1505706D01*
G01X1521837Y-5000D02*
X1505022D01*
G01X1505706Y-3349D02*
X1501474Y883D01*
G01X1505022Y-5000D02*
X1499823Y199D01*
G01X1501474Y883D02*
Y12526D01*
G01X1499823Y199D02*
Y11842D01*
G01X1501474Y12526D02*
X1489711Y24289D01*
G01X1499823Y11842D02*
X1489027Y22638D01*
G01X1568852Y951D02*
X1506767D01*
G01X1569536Y-700D02*
X1506083D01*
G01X1506767Y951D02*
X1505301Y2417D01*
G01X1506083Y-700D02*
X1503650Y1733D01*
G01X1505301Y2417D02*
Y2836D01*
G01X1505300Y2837D02*
Y4163D01*
G01X1503649Y2153D02*
Y4847D01*
G01X1505301Y4164D02*
Y15035D01*
G01X1503650Y4848D02*
Y14351D01*
G01X1505301Y15035D02*
X1492230Y28106D01*
G01X1503650Y14351D02*
X1491546Y26455D01*
G01X1569536Y-700D02*
X1506083D01*
G01X1568852Y951D02*
X1506767D01*
G01X1506083Y-700D02*
X1503650Y1733D01*
G01X1506767Y951D02*
X1505301Y2417D01*
G01X1503649Y2153D02*
Y4847D01*
G01X1505301Y2417D02*
Y2836D01*
G01X1503649Y2153D02*
Y4847D01*
G01X1505300Y2837D02*
Y4163D01*
G01X1503650Y4848D02*
Y14351D01*
G01X1505301Y4164D02*
Y15035D01*
G01X1503650Y14351D02*
X1491546Y26455D01*
G01X1505301Y15035D02*
X1492230Y28106D01*
G01X1591048Y2951D02*
X1570852D01*
G01X1590364Y1300D02*
X1571536D01*
G01X1570852Y2951D02*
X1568852Y951D01*
G01X1571536Y1300D02*
X1569536Y-700D01*
G01X1590364Y1300D02*
X1571536D01*
G01X1591048Y2951D02*
X1570852D01*
G01X1571536Y1300D02*
X1569536Y-700D01*
G01X1570852Y2951D02*
X1568852Y951D01*
G01X1575188Y399988D02*
X1581153Y394023D01*
G01X1574020Y398821D02*
X1580469Y392372D01*
G01X1581153Y394023D02*
X1582574D01*
G01X1580469Y392372D02*
X1581890D01*
G01X1582574Y394023D02*
X1585513Y391084D01*
G01X1588059Y388538D02*
X1588797Y387800D01*
G01X1581890Y392372D02*
X1588030Y386231D01*
G01D02*
X1592263Y381999D01*
G01X1574020Y398821D02*
X1580469Y392372D01*
G01X1575188Y399988D02*
X1581153Y394023D01*
G01X1580469Y392372D02*
X1581890D01*
G01X1581153Y394023D02*
X1582574D01*
G01X1581890Y392372D02*
X1588030Y386231D01*
G01X1582574Y394023D02*
X1585513Y391084D01*
G01X1581890Y392372D02*
X1588030Y386231D01*
G01X1588059Y388538D02*
X1588797Y387800D01*
G01X1588030Y386231D02*
X1592263Y381999D01*
G01X1580164Y401565D02*
X1576296Y405433D01*
G01X1575129Y404265D02*
X1579480Y399914D01*
G01X1588576Y401565D02*
X1580164D01*
G01X1579480Y399914D02*
X1587892D01*
G01X1591352Y398789D02*
X1588576Y401565D01*
G01X1587892Y399914D02*
X1593722Y394084D01*
G01X1587892Y399914D02*
X1593722Y394084D01*
G01X1587892Y399914D02*
X1593722Y394084D01*
G01X1591352Y398789D02*
X1588576Y401565D01*
G01X1579480Y399914D02*
X1587892D01*
G01X1588576Y401565D02*
X1580164D01*
G01X1575129Y404265D02*
X1579480Y399914D01*
G01X1580164Y401565D02*
X1576296Y405433D01*
G01X1575553Y415297D02*
X1576118D01*
G01X1575836Y416948D02*
X1576802D01*
G01X1576118Y415297D02*
X1585441Y405974D01*
G01X1576802Y416948D02*
X1586125Y407625D01*
G01X1585441Y405974D02*
X1592874D01*
G01X1586125Y407625D02*
X1592190D01*
G01X1575836Y416948D02*
X1576802D01*
G01X1575553Y415297D02*
X1576118D01*
G01X1576802Y416948D02*
X1586125Y407625D01*
G01X1576118Y415297D02*
X1585441Y405974D01*
G01X1586125Y407625D02*
X1592190D01*
G01X1585441Y405974D02*
X1592874D01*
G01X1612669Y417720D02*
X1584494D01*
G01X1612669D02*
X1584494D01*
G01X1592221Y419371D02*
X1585178D01*
G01X1584494Y417720D02*
X1580187Y422027D01*
G01X1585178Y419371D02*
X1580871Y423678D01*
G01X1580187Y422027D02*
X1575133D01*
G01X1580871Y423678D02*
X1575133D01*
G01X1592221Y419371D02*
X1585178D01*
G01X1612669Y417720D02*
X1584494D01*
G01X1585178Y419371D02*
X1580871Y423678D01*
G01X1584494Y417720D02*
X1580187Y422027D01*
G01X1580871Y423678D02*
X1575133D01*
G01X1580187Y422027D02*
X1575133D01*
G01X1662699Y-10500D02*
X1619136D01*
G01X1662015Y-8849D02*
X1618452D01*
G01X1619136Y-10500D02*
X1618085Y-11551D01*
G01X1618452Y-8849D02*
X1617401Y-9900D01*
G01X1618085Y-11551D02*
X1597815D01*
G01X1617401Y-9900D02*
X1598499D01*
G01X1597815Y-11551D02*
X1591264Y-5000D01*
G01X1598499Y-9900D02*
X1591948Y-3349D01*
G01X1662015Y-8849D02*
X1618452D01*
G01X1662699Y-10500D02*
X1619136D01*
G01X1618452Y-8849D02*
X1617401Y-9900D01*
G01X1619136Y-10500D02*
X1618085Y-11551D01*
G01X1617401Y-9900D02*
X1598499D01*
G01X1618085Y-11551D02*
X1597815D01*
G01X1598499Y-9900D02*
X1591948Y-3349D01*
G01X1597815Y-11551D02*
X1591264Y-5000D01*
G01X1660800Y-4194D02*
X1617471D01*
G01X1661484Y-5845D02*
X1618155D01*
G01X1617471Y-4194D02*
X1616065Y-5600D01*
G01X1618155Y-5845D02*
X1616749Y-7251D01*
G01X1616065Y-5600D02*
X1599599D01*
G01X1616749Y-7251D02*
X1598915D01*
G01X1599599Y-5600D02*
X1591048Y2951D01*
G01X1598915Y-7251D02*
X1590364Y1300D01*
G01X1661484Y-5845D02*
X1618155D01*
G01X1660800Y-4194D02*
X1617471D01*
G01X1618155Y-5845D02*
X1616749Y-7251D01*
G01X1617471Y-4194D02*
X1616065Y-5600D01*
G01X1616749Y-7251D02*
X1598915D01*
G01X1616065Y-5600D02*
X1599599D01*
G01X1598915Y-7251D02*
X1590364Y1300D01*
G01X1599599Y-5600D02*
X1591048Y2951D01*
G01X1645061Y251694D02*
Y312007D01*
G01X1643410Y311323D02*
Y251010D01*
G01X1647249Y249506D02*
X1645061Y251694D01*
G01X1643410Y251010D02*
X1645598Y248822D01*
G01X1647249Y240653D02*
Y249506D01*
G01X1645598Y248822D02*
Y239969D01*
G01X1661487Y226415D02*
X1647249Y240653D01*
G01X1645598Y239969D02*
X1660803Y224764D01*
G01X1645598Y239969D02*
X1660803Y224764D01*
G01X1661487Y226415D02*
X1647249Y240653D01*
G01X1645598Y248822D02*
Y239969D01*
G01X1647249Y240653D02*
Y249506D01*
G01X1643410Y251010D02*
X1645598Y248822D01*
G01X1647249Y249506D02*
X1645061Y251694D01*
G01X1643410Y311323D02*
Y251010D01*
G01X1645061Y251694D02*
Y312007D01*
G01X1647560Y313089D02*
Y252934D01*
G01X1649211Y313773D02*
Y253618D01*
G01X1647560Y252934D02*
X1649853Y250641D01*
G01X1649211Y253618D02*
X1651504Y251325D01*
G01X1649853Y250641D02*
Y241634D01*
G01D02*
X1662537Y228950D01*
G01X1649211Y313773D02*
Y253618D01*
G01X1647560Y313089D02*
Y252934D01*
G01X1649211Y253618D02*
X1651504Y251325D01*
G01X1647560Y252934D02*
X1649853Y250641D01*
G01D02*
Y241634D01*
G01D02*
X1662537Y228950D01*
G01X1640911Y306039D02*
Y248206D01*
G01X1639260Y305355D02*
Y247522D01*
G01X1640911Y248206D02*
X1641667Y247450D01*
G01X1639260Y247522D02*
X1640016Y246766D01*
G01X1641667Y247450D02*
Y240273D01*
G01X1640016Y246766D02*
Y239589D01*
G01X1641667Y240273D02*
X1659698Y222242D01*
G01X1640016Y239589D02*
X1659014Y220591D01*
G01X1639260Y305355D02*
Y247522D01*
G01X1640911Y306039D02*
Y248206D01*
G01X1639260Y247522D02*
X1640016Y246766D01*
G01X1640911Y248206D02*
X1641667Y247450D01*
G01X1640016Y246766D02*
Y239589D01*
G01X1641667Y247450D02*
Y240273D01*
G01X1640016Y239589D02*
X1659014Y220591D01*
G01X1641667Y240273D02*
X1659698Y222242D01*
G01X1627703Y339285D02*
Y344546D01*
G01X1626052Y343862D02*
Y338601D01*
G01X1628647Y338341D02*
X1627703Y339285D01*
G01X1626052Y338601D02*
X1627963Y336690D01*
G01X1633546Y338341D02*
X1628647D01*
G01X1627963Y336690D02*
X1632862D01*
G01X1642841Y329046D02*
X1633546Y338341D01*
G01X1632862Y336690D02*
X1641190Y328362D01*
G01X1642841Y314227D02*
Y329046D01*
G01X1641190Y328362D02*
Y313543D01*
G01X1645061Y312007D02*
X1642841Y314227D01*
G01X1641190Y313543D02*
X1643410Y311323D01*
G01X1641190Y313543D02*
X1643410Y311323D01*
G01X1645061Y312007D02*
X1642841Y314227D01*
G01X1641190Y328362D02*
Y313543D01*
G01X1642841Y314227D02*
Y329046D01*
G01X1632862Y336690D02*
X1641190Y328362D01*
G01X1642841Y329046D02*
X1633546Y338341D01*
G01X1627963Y336690D02*
X1632862D01*
G01X1633546Y338341D02*
X1628647D01*
G01X1626052Y338601D02*
X1627963Y336690D01*
G01X1628647Y338341D02*
X1627703Y339285D01*
G01X1626052Y343862D02*
Y338601D01*
G01X1627703Y339285D02*
Y344546D01*
G01X1638064Y346396D02*
Y338444D01*
G01X1639715Y347080D02*
Y339128D01*
G01X1638064Y338444D02*
X1645340Y331164D01*
G01X1639715Y339128D02*
X1646991Y331848D01*
G01X1645340Y331164D02*
Y315309D01*
G01X1646991Y331848D02*
Y315993D01*
G01X1645340Y315309D02*
X1647560Y313089D01*
G01X1646991Y315993D02*
X1649211Y313773D01*
G01X1639715Y347080D02*
Y339128D01*
G01X1638064Y346396D02*
Y338444D01*
G01X1639715Y339128D02*
X1646991Y331848D01*
G01X1638064Y338444D02*
X1645340Y331164D01*
G01X1646991Y331848D02*
Y315993D01*
G01X1645340Y331164D02*
Y315309D01*
G01X1646991Y315993D02*
X1649211Y313773D01*
G01X1645340Y315309D02*
X1647560Y313089D01*
G01X1623478Y342473D02*
Y337084D01*
G01X1621827Y341789D02*
Y336400D01*
G01X1623478Y337084D02*
X1626381Y334181D01*
G01X1621827Y336400D02*
X1625697Y332530D01*
G01X1626381Y334181D02*
X1630132D01*
G01X1625697Y332530D02*
X1629448D01*
G01X1630132Y334181D02*
X1634466Y329847D01*
G01X1629448Y332530D02*
X1632815Y329163D01*
G01X1634466Y329847D02*
Y326032D01*
G01X1632815Y329163D02*
Y326716D01*
G01X1634466Y326032D02*
X1633505Y325071D01*
G01X1632815Y326716D02*
X1631854Y325755D01*
G01X1633505Y325071D02*
Y318145D01*
G01X1631854Y325755D02*
Y317461D01*
G01X1633505Y318145D02*
X1636300Y315350D01*
G01X1631854Y317461D02*
X1634649Y314666D01*
G01X1636300Y315350D02*
Y310650D01*
G01X1634649Y314666D02*
Y309966D01*
G01X1636300Y310650D02*
X1640911Y306039D01*
G01X1634649Y309966D02*
X1639260Y305355D01*
G01X1621827Y341789D02*
Y336400D01*
G01X1623478Y342473D02*
Y337084D01*
G01X1621827Y336400D02*
X1625697Y332530D01*
G01X1623478Y337084D02*
X1626381Y334181D01*
G01X1625697Y332530D02*
X1629448D01*
G01X1626381Y334181D02*
X1630132D01*
G01X1629448Y332530D02*
X1632815Y329163D01*
G01X1630132Y334181D02*
X1634466Y329847D01*
G01X1632815Y329163D02*
Y326716D01*
G01X1634466Y329847D02*
Y326032D01*
G01X1632815Y326716D02*
X1631854Y325755D01*
G01X1634466Y326032D02*
X1633505Y325071D01*
G01X1631854Y325755D02*
Y317461D01*
G01X1633505Y325071D02*
Y318145D01*
G01X1631854Y317461D02*
X1634649Y314666D01*
G01X1633505Y318145D02*
X1636300Y315350D01*
G01X1634649Y314666D02*
Y309966D01*
G01X1636300Y315350D02*
Y310650D01*
G01X1634649Y309966D02*
X1639260Y305355D01*
G01X1636300Y310650D02*
X1640911Y306039D01*
G01X1651710Y314816D02*
X1649490Y317036D01*
G01D02*
Y348757D01*
G01X1651710Y314816D02*
X1649490Y317036D01*
G01D02*
Y348757D01*
G01Y317036D02*
Y348757D01*
G01Y317036D02*
Y348757D01*
G01Y317036D02*
Y348757D01*
G01X1590900Y385697D02*
X1593914Y382683D01*
G01D02*
Y380858D01*
G01X1592263Y381999D02*
Y380174D01*
G01X1593914Y380858D02*
X1595539Y379233D01*
G01X1592263Y380174D02*
X1594855Y377582D01*
G01X1595539Y379233D02*
X1597767D01*
G01X1594855Y377582D02*
X1597642D01*
G01X1590900Y385697D02*
X1593914Y382683D01*
G01X1592263Y381999D02*
Y380174D01*
G01X1593914Y382683D02*
Y380858D01*
G01X1592263Y380174D02*
X1594855Y377582D01*
G01X1593914Y380858D02*
X1595539Y379233D01*
G01X1594855Y377582D02*
X1597642D01*
G01X1595539Y379233D02*
X1597767D01*
G01X1595373Y394768D02*
X1593899Y396242D01*
G01X1595373Y387094D02*
Y394768D01*
G01X1593722Y394084D02*
Y386410D01*
G01X1597458Y385009D02*
X1595373Y387094D01*
G01X1593722Y386410D02*
X1596774Y383358D01*
G01X1612087Y385009D02*
X1597458D01*
G01X1596774Y383358D02*
X1611403D01*
G01X1618647Y378449D02*
X1612087Y385009D01*
G01X1611403Y383358D02*
X1616996Y377765D01*
G01X1618647Y359089D02*
Y378449D01*
G01X1616996Y377765D02*
Y358405D01*
G01X1623628Y354108D02*
X1618647Y359089D01*
G01X1616996Y358405D02*
X1621977Y353424D01*
G01X1623628Y348621D02*
Y354108D01*
G01X1621977Y353424D02*
Y347937D01*
G01X1627703Y344546D02*
X1623628Y348621D01*
G01X1621977Y347937D02*
X1626052Y343862D01*
G01X1621977Y347937D02*
X1626052Y343862D01*
G01X1627703Y344546D02*
X1623628Y348621D01*
G01X1621977Y353424D02*
Y347937D01*
G01X1623628Y348621D02*
Y354108D01*
G01X1616996Y358405D02*
X1621977Y353424D01*
G01X1623628Y354108D02*
X1618647Y359089D01*
G01X1616996Y377765D02*
Y358405D01*
G01X1618647Y359089D02*
Y378449D01*
G01X1611403Y383358D02*
X1616996Y377765D01*
G01X1618647Y378449D02*
X1612087Y385009D01*
G01X1596774Y383358D02*
X1611403D01*
G01X1612087Y385009D02*
X1597458D01*
G01X1593722Y386410D02*
X1596774Y383358D01*
G01X1597458Y385009D02*
X1595373Y387094D01*
G01X1593722Y394084D02*
Y386410D01*
G01X1595373Y387094D02*
Y394768D01*
G01D02*
X1593899Y396242D01*
G01X1609164Y403095D02*
X1610690Y401569D01*
G01X1604494Y410100D02*
X1611857Y402737D01*
G01X1611536Y399023D02*
X1613236D01*
G01D02*
X1614082Y398177D01*
G01X1614929Y395630D02*
X1616629D01*
G01D02*
X1617475Y394784D01*
G01X1611857Y402736D02*
X1619126Y395468D01*
G01X1617475Y394784D02*
Y393690D01*
G01X1619126Y395468D02*
Y394374D01*
G01X1617475Y393690D02*
X1624549Y386616D01*
G01X1619126Y394374D02*
X1626200Y387300D01*
G01X1624549Y386616D02*
Y380584D01*
G01X1626200Y387300D02*
Y379900D01*
G01X1624549Y380584D02*
X1622400Y378435D01*
G01X1626200Y379900D02*
X1624051Y377751D01*
G01X1622400Y378435D02*
Y367560D01*
G01Y364361D02*
Y360100D01*
G01X1624051Y377751D02*
Y360784D01*
G01X1622400Y360100D02*
X1626375Y356125D01*
G01X1624051Y360784D02*
X1628026Y356809D01*
G01X1626375Y356125D02*
Y354109D01*
G01X1628026Y356809D02*
Y354793D01*
G01X1626375Y354109D02*
X1630584Y349900D01*
G01X1628026Y354793D02*
X1631268Y351551D01*
G01X1630584Y349900D02*
X1634560D01*
G01X1631268Y351551D02*
X1635244D01*
G01X1634560Y349900D02*
X1638064Y346396D01*
G01X1635244Y351551D02*
X1639715Y347080D01*
G01X1604494Y410100D02*
X1611857Y402737D01*
G01X1604494Y410100D02*
X1611857Y402737D01*
G01X1609164Y403095D02*
X1610690Y401569D01*
G01X1611857Y402736D02*
X1619126Y395468D01*
G01X1611536Y399023D02*
X1613236D01*
G01X1611857Y402736D02*
X1619126Y395468D01*
G01X1613236Y399023D02*
X1614082Y398177D01*
G01X1611857Y402736D02*
X1619126Y395468D01*
G01X1614929Y395630D02*
X1616629D01*
G01X1611857Y402736D02*
X1619126Y395468D01*
G01X1616629Y395630D02*
X1617475Y394784D01*
G01X1619126Y395468D02*
Y394374D01*
G01X1617475Y394784D02*
Y393690D01*
G01X1619126Y394374D02*
X1626200Y387300D01*
G01X1617475Y393690D02*
X1624549Y386616D01*
G01X1626200Y387300D02*
Y379900D01*
G01X1624549Y386616D02*
Y380584D01*
G01X1626200Y379900D02*
X1624051Y377751D01*
G01X1624549Y380584D02*
X1622400Y378435D01*
G01X1624051Y377751D02*
Y360784D01*
G01X1622400Y378435D02*
Y367560D01*
G01X1624051Y377751D02*
Y360784D01*
G01X1622400Y364361D02*
Y360100D01*
G01X1624051Y360784D02*
X1628026Y356809D01*
G01X1622400Y360100D02*
X1626375Y356125D01*
G01X1628026Y356809D02*
Y354793D01*
G01X1626375Y356125D02*
Y354109D01*
G01X1628026Y354793D02*
X1631268Y351551D01*
G01X1626375Y354109D02*
X1630584Y349900D01*
G01X1631268Y351551D02*
X1635244D01*
G01X1630584Y349900D02*
X1634560D01*
G01X1635244Y351551D02*
X1639715Y347080D01*
G01X1634560Y349900D02*
X1638064Y346396D01*
G01X1639867Y361968D02*
X1636841D01*
G01X1639867Y363619D02*
X1637525D01*
G01X1636841Y361968D02*
X1634973Y363836D01*
G01X1637525Y363619D02*
X1636624Y364520D01*
G01X1634973Y363836D02*
Y377902D01*
G01X1636624Y364520D02*
Y378586D01*
G01X1634973Y377902D02*
X1632049Y380826D01*
G01X1636624Y378586D02*
X1633700Y381510D01*
G01X1632049Y380826D02*
Y385216D01*
G01X1633700Y381510D02*
Y385900D01*
G01X1632049Y385216D02*
X1626391Y390874D01*
G01X1633700Y385900D02*
X1628042Y391558D01*
G01X1626391Y390874D02*
Y403998D01*
G01X1628042Y391558D02*
Y404682D01*
G01X1639867Y363619D02*
X1637525D01*
G01X1639867Y361968D02*
X1636841D01*
G01X1637525Y363619D02*
X1636624Y364520D01*
G01X1636841Y361968D02*
X1634973Y363836D01*
G01X1636624Y364520D02*
Y378586D01*
G01X1634973Y363836D02*
Y377902D01*
G01X1636624Y378586D02*
X1633700Y381510D01*
G01X1634973Y377902D02*
X1632049Y380826D01*
G01X1633700Y381510D02*
Y385900D01*
G01X1632049Y380826D02*
Y385216D01*
G01X1633700Y385900D02*
X1628042Y391558D01*
G01X1632049Y385216D02*
X1626391Y390874D01*
G01X1628042Y391558D02*
Y404682D01*
G01X1626391Y390874D02*
Y403998D01*
G01X1609715Y378753D02*
X1611981D01*
G01X1609077Y377102D02*
X1611297D01*
G01X1611981Y378753D02*
X1614497Y376237D01*
G01X1611297Y377102D02*
X1612846Y375553D01*
G01X1614497Y376237D02*
Y348455D01*
G01X1612846Y375553D02*
Y347771D01*
G01X1614497Y348455D02*
X1618262Y344690D01*
G01X1612846Y347771D02*
X1617578Y343039D01*
G01X1618262Y344690D02*
X1621261D01*
G01X1617578Y343039D02*
X1620577D01*
G01X1621261Y344690D02*
X1623478Y342473D01*
G01X1620577Y343039D02*
X1621827Y341789D01*
G01X1609077Y377102D02*
X1611297D01*
G01X1609715Y378753D02*
X1611981D01*
G01X1611297Y377102D02*
X1612846Y375553D01*
G01X1611981Y378753D02*
X1614497Y376237D01*
G01X1612846Y375553D02*
Y347771D01*
G01X1614497Y376237D02*
Y348455D01*
G01X1612846Y347771D02*
X1617578Y343039D01*
G01X1614497Y348455D02*
X1618262Y344690D01*
G01X1617578Y343039D02*
X1620577D01*
G01X1618262Y344690D02*
X1621261D01*
G01X1620577Y343039D02*
X1621827Y341789D01*
G01X1621261Y344690D02*
X1623478Y342473D01*
G01X1651141Y349441D02*
X1648577Y352005D01*
G01X1649490Y348757D02*
X1646926Y351321D01*
G01X1648577Y352005D02*
Y360758D01*
G01X1646926Y351321D02*
Y361442D01*
G01X1648577Y360758D02*
X1650093Y362274D01*
G01X1646926Y361442D02*
X1649409Y363925D01*
G01X1650093Y362274D02*
X1651787D01*
G01X1649409Y363925D02*
X1651737D01*
G01X1649490Y348757D02*
X1646926Y351321D01*
G01X1651141Y349441D02*
X1648577Y352005D01*
G01X1646926Y351321D02*
Y361442D01*
G01X1648577Y352005D02*
Y360758D01*
G01X1646926Y361442D02*
X1649409Y363925D01*
G01X1648577Y360758D02*
X1650093Y362274D01*
G01X1649409Y363925D02*
X1651737D01*
G01X1650093Y362274D02*
X1651787D01*
G01X1592874Y405974D02*
X1595349Y408449D01*
G01X1592190Y407625D02*
X1594665Y410100D01*
G01X1595349Y408449D02*
X1603810D01*
G01X1594665Y410100D02*
X1604494D01*
G01X1603810Y408449D02*
X1606518Y405741D01*
G01X1592190Y407625D02*
X1594665Y410100D01*
G01X1592874Y405974D02*
X1595349Y408449D01*
G01X1594665Y410100D02*
X1604494D01*
G01X1595349Y408449D02*
X1603810D01*
G01D02*
X1606518Y405741D01*
G01X1626391Y403998D02*
X1612669Y417720D01*
G01X1628042Y404682D02*
X1613353Y419371D01*
G01D02*
X1595822D01*
G01X1628042Y404682D02*
X1613353Y419371D01*
G01X1626391Y403998D02*
X1612669Y417720D01*
G01X1613353Y419371D02*
X1595822D01*
G01X1830561Y-21622D02*
X1691982D01*
G01X1829877Y-19971D02*
X1692666D01*
G01X1691982Y-21622D02*
X1677412Y-7052D01*
G01X1692666Y-19971D02*
X1678096Y-5401D01*
G01X1677412Y-7052D02*
X1666147D01*
G01X1678096Y-5401D02*
X1665463D01*
G01X1666147Y-7052D02*
X1662699Y-10500D01*
G01X1665463Y-5401D02*
X1662015Y-8849D01*
G01X1829877Y-19971D02*
X1692666D01*
G01X1830561Y-21622D02*
X1691982D01*
G01X1692666Y-19971D02*
X1678096Y-5401D01*
G01X1691982Y-21622D02*
X1677412Y-7052D01*
G01X1678096Y-5401D02*
X1665463D01*
G01X1677412Y-7052D02*
X1666147D01*
G01X1665463Y-5401D02*
X1662015Y-8849D01*
G01X1666147Y-7052D02*
X1662699Y-10500D01*
G01X1821773Y-9227D02*
X1687792D01*
G01X1822457Y-10878D02*
X1687108D01*
G01X1687792Y-9227D02*
X1679316Y-751D01*
G01X1687108Y-10878D02*
X1678632Y-2402D01*
G01X1679316Y-751D02*
X1664243D01*
G01X1678632Y-2402D02*
X1664927D01*
G01X1664243Y-751D02*
X1660800Y-4194D01*
G01X1664927Y-2402D02*
X1661484Y-5845D01*
G01X1822457Y-10878D02*
X1687108D01*
G01X1821773Y-9227D02*
X1687792D01*
G01X1687108Y-10878D02*
X1678632Y-2402D01*
G01X1687792Y-9227D02*
X1679316Y-751D01*
G01X1678632Y-2402D02*
X1664927D01*
G01X1679316Y-751D02*
X1664243D01*
G01X1664927Y-2402D02*
X1661484Y-5845D01*
G01X1664243Y-751D02*
X1660800Y-4194D01*
G01X1691071Y215430D02*
X1684031Y222470D01*
G01X1683347Y220819D02*
X1690387Y213779D01*
G01X1712374Y215430D02*
X1691071D01*
G01X1690387Y213779D02*
X1713058D01*
G01X1690387D02*
X1713058D01*
G01X1712374Y215430D02*
X1691071D01*
G01X1683347Y220819D02*
X1690387Y213779D01*
G01X1691071Y215430D02*
X1684031Y222470D01*
G01X1669707Y220591D02*
X1673739Y216559D01*
G01D02*
X1679646D01*
G01X1680330Y218210D02*
X1687536Y211004D01*
G01X1679646Y216559D02*
X1686852Y209353D01*
G01X1687536Y211004D02*
X1714425D01*
G01X1686852Y209353D02*
X1715109D01*
G01X1669707Y220591D02*
X1673739Y216559D01*
G01D02*
X1679646D01*
G01D02*
X1686852Y209353D01*
G01X1680330Y218210D02*
X1687536Y211004D01*
G01X1686852Y209353D02*
X1715109D01*
G01X1687536Y211004D02*
X1714425D01*
G01X1672279Y226415D02*
X1661487D01*
G01X1660803Y224764D02*
X1671595D01*
G01X1676224Y222470D02*
X1672279Y226415D01*
G01X1671595Y224764D02*
X1675540Y220819D01*
G01X1684031Y222470D02*
X1676224D01*
G01X1675540Y220819D02*
X1683347D01*
G01X1675540D02*
X1683347D01*
G01X1684031Y222470D02*
X1676224D01*
G01X1671595Y224764D02*
X1675540Y220819D01*
G01X1676224Y222470D02*
X1672279Y226415D01*
G01X1660803Y224764D02*
X1671595D01*
G01X1672279Y226415D02*
X1661487D01*
G01X1651504Y251325D02*
Y242318D01*
G01D02*
X1663221Y230601D01*
G01X1662537Y228950D02*
X1674640D01*
G01X1663221Y230601D02*
X1675324D01*
G01X1674640Y228950D02*
X1678621Y224969D01*
G01X1675324Y230601D02*
X1679305Y226620D01*
G01X1678621Y224969D02*
X1685288D01*
G01X1679305Y226620D02*
X1685972D01*
G01X1685288Y224969D02*
X1692266Y217992D01*
G01X1685972Y226620D02*
X1692950Y219643D01*
G01X1692266Y217992D02*
X1711400D01*
G01X1692950Y219643D02*
X1710716D01*
G01X1711400Y217992D02*
X1717445Y224037D01*
G01X1710716Y219643D02*
X1716761Y225688D01*
G01X1651504Y251325D02*
Y242318D01*
G01D02*
X1663221Y230601D01*
G01D02*
X1675324D01*
G01X1662537Y228950D02*
X1674640D01*
G01X1675324Y230601D02*
X1679305Y226620D01*
G01X1674640Y228950D02*
X1678621Y224969D01*
G01X1679305Y226620D02*
X1685972D01*
G01X1678621Y224969D02*
X1685288D01*
G01X1685972Y226620D02*
X1692950Y219643D01*
G01X1685288Y224969D02*
X1692266Y217992D01*
G01X1692950Y219643D02*
X1710716D01*
G01X1692266Y217992D02*
X1711400D01*
G01X1710716Y219643D02*
X1716761Y225688D01*
G01X1711400Y217992D02*
X1717445Y224037D01*
G01X1659698Y222242D02*
X1670391D01*
G01X1659014Y220591D02*
X1669707D01*
G01X1670391Y222242D02*
X1674423Y218210D01*
G01D02*
X1680330D01*
G01X1659014Y220591D02*
X1669707D01*
G01X1659698Y222242D02*
X1670391D01*
G01D02*
X1674423Y218210D01*
G01D02*
X1680330D01*
G01X1714986Y241074D02*
X1710952Y237040D01*
G01D02*
Y225873D01*
G01D02*
X1708880Y223801D01*
G01X1712603Y225189D02*
X1709564Y222150D01*
G01X1708880Y223801D02*
X1694662D01*
G01X1709564Y222150D02*
X1693978D01*
G01X1694662Y223801D02*
X1687693Y230770D01*
G01X1693978Y222150D02*
X1687009Y229119D01*
G01X1687693Y230770D02*
X1681025D01*
G01X1687009Y229119D02*
X1680341D01*
G01X1681025Y230770D02*
X1677025Y234770D01*
G01X1680341Y229119D02*
X1676341Y233119D01*
G01X1677025Y234770D02*
X1664971D01*
G01X1676341Y233119D02*
X1664287D01*
G01X1664971Y234770D02*
X1655720Y244021D01*
G01X1664287Y233119D02*
X1654069Y243337D01*
G01X1655720Y244021D02*
Y251745D01*
G01X1655721Y251746D02*
Y253112D01*
G01X1654069Y243337D02*
Y252429D01*
G01X1655721Y253112D02*
X1653361Y255472D01*
G01X1654069Y252429D02*
X1651710Y254788D01*
G01X1653361Y255472D02*
Y315500D01*
G01X1651710Y254788D02*
Y314816D01*
G01X1714986Y241074D02*
X1710952Y237040D01*
G01D02*
Y225873D01*
G01X1712603Y225189D02*
X1709564Y222150D01*
G01X1710952Y225873D02*
X1708880Y223801D01*
G01X1709564Y222150D02*
X1693978D01*
G01X1708880Y223801D02*
X1694662D01*
G01X1693978Y222150D02*
X1687009Y229119D01*
G01X1694662Y223801D02*
X1687693Y230770D01*
G01X1687009Y229119D02*
X1680341D01*
G01X1687693Y230770D02*
X1681025D01*
G01X1680341Y229119D02*
X1676341Y233119D01*
G01X1681025Y230770D02*
X1677025Y234770D01*
G01X1676341Y233119D02*
X1664287D01*
G01X1677025Y234770D02*
X1664971D01*
G01X1664287Y233119D02*
X1654069Y243337D01*
G01X1664971Y234770D02*
X1655720Y244021D01*
G01X1654069Y243337D02*
Y252429D01*
G01X1655720Y244021D02*
Y251745D01*
G01X1654069Y243337D02*
Y252429D01*
G01X1655721Y251746D02*
Y253112D01*
G01X1654069Y252429D02*
X1651710Y254788D01*
G01X1655721Y253112D02*
X1653361Y255472D01*
G01X1651710Y254788D02*
Y314816D01*
G01X1653361Y255472D02*
Y315500D01*
G01D02*
X1651141Y317720D01*
G01D02*
Y334722D01*
G01Y338323D02*
Y339520D01*
G01X1653361Y315500D02*
X1651141Y317720D01*
G01D02*
Y334722D01*
G01Y338323D02*
Y339520D01*
G01Y343121D02*
Y344318D01*
G01Y347919D02*
Y349441D01*
G01Y343121D02*
Y344318D01*
G01Y347919D02*
Y349441D01*
G01X1718482Y221538D02*
X1712374Y215430D01*
G01X1713058Y213779D02*
X1719166Y219887D01*
G01X1713058Y213779D02*
X1719166Y219887D01*
G01X1718482Y221538D02*
X1712374Y215430D01*
G01X1714425Y211004D02*
X1720556Y217135D01*
G01X1715109Y209353D02*
X1721240Y215484D01*
G01X1720556Y217135D02*
X1766074D01*
G01X1769675D02*
X1770872D01*
G01X1721240Y215484D02*
X1798979D01*
G01X1715109Y209353D02*
X1721240Y215484D01*
G01X1714425Y211004D02*
X1720556Y217135D01*
G01X1721240Y215484D02*
X1798979D01*
G01X1720556Y217135D02*
X1766074D01*
G01X1721240Y215484D02*
X1798979D01*
G01X1769675Y217135D02*
X1770872D01*
G01X1721240Y215484D02*
X1798979D01*
G01X1764607Y221538D02*
X1754036D01*
G01X1750435D02*
X1749018D01*
G01X1745417D02*
X1744220D01*
G01X1740619D02*
X1739422D01*
G01X1735821D02*
X1718482D01*
G01X1719166Y219887D02*
X1765291D01*
G01X1776125Y233056D02*
X1764607Y221538D01*
G01X1765291Y219887D02*
X1777776Y232372D01*
G01X1765291Y219887D02*
X1777776Y232372D01*
G01X1776125Y233056D02*
X1764607Y221538D01*
G01X1719166Y219887D02*
X1765291D01*
G01X1764607Y221538D02*
X1754036D01*
G01X1719166Y219887D02*
X1765291D01*
G01X1750435Y221538D02*
X1749018D01*
G01X1719166Y219887D02*
X1765291D01*
G01X1745417Y221538D02*
X1744220D01*
G01X1719166Y219887D02*
X1765291D01*
G01X1740619Y221538D02*
X1739422D01*
G01X1719166Y219887D02*
X1765291D01*
G01X1735821Y221538D02*
X1718482D01*
G01X1717445Y224037D02*
X1727509D01*
G01X1716761Y225688D02*
X1726825D01*
G01X1727509Y224037D02*
X1731786Y228314D01*
G01X1726825Y225688D02*
X1730135Y228998D01*
G01X1731786Y228314D02*
Y237759D01*
G01X1730135Y228998D02*
Y238443D01*
G01X1731786Y237759D02*
X1734885Y240858D01*
G01X1730135Y238443D02*
X1734201Y242509D01*
G01X1734885Y240858D02*
X1756085D01*
G01X1734201Y242509D02*
X1756769D01*
G01X1756085Y240858D02*
X1757229Y239714D01*
G01X1756769Y242509D02*
X1758880Y240398D01*
G01X1757229Y239714D02*
Y238111D01*
G01X1758880Y240398D02*
Y238111D01*
G01X1716761Y225688D02*
X1726825D01*
G01X1717445Y224037D02*
X1727509D01*
G01X1726825Y225688D02*
X1730135Y228998D01*
G01X1727509Y224037D02*
X1731786Y228314D01*
G01X1730135Y228998D02*
Y238443D01*
G01X1731786Y228314D02*
Y237759D01*
G01X1730135Y238443D02*
X1734201Y242509D01*
G01X1731786Y237759D02*
X1734885Y240858D01*
G01X1734201Y242509D02*
X1756769D01*
G01X1734885Y240858D02*
X1756085D01*
G01X1756769Y242509D02*
X1758880Y240398D01*
G01X1756085Y240858D02*
X1757229Y239714D01*
G01X1758880Y240398D02*
Y238111D01*
G01X1757229Y239714D02*
Y238111D01*
G01X1794266Y246659D02*
X1772519D01*
G01X1768918D02*
X1767721D01*
G01X1764120D02*
X1762923D01*
G01X1759322D02*
X1758125D01*
G01X1754524D02*
X1732418D01*
G01X1794950Y245008D02*
X1733102D01*
G01X1732418Y246659D02*
X1726833Y241074D01*
G01X1733102Y245008D02*
X1727517Y239423D01*
G01X1726833Y241074D02*
X1721431D01*
G01X1717830D02*
X1714986D01*
G01X1727517Y239423D02*
X1715670D01*
G01D02*
X1712603Y236356D01*
G01D02*
Y225189D01*
G01X1794950Y245008D02*
X1733102D01*
G01X1794266Y246659D02*
X1772519D01*
G01X1794950Y245008D02*
X1733102D01*
G01X1768918Y246659D02*
X1767721D01*
G01X1794950Y245008D02*
X1733102D01*
G01X1764120Y246659D02*
X1762923D01*
G01X1794950Y245008D02*
X1733102D01*
G01X1759322Y246659D02*
X1758125D01*
G01X1794950Y245008D02*
X1733102D01*
G01X1754524Y246659D02*
X1732418D01*
G01X1733102Y245008D02*
X1727517Y239423D01*
G01X1732418Y246659D02*
X1726833Y241074D01*
G01X1727517Y239423D02*
X1715670D01*
G01X1726833Y241074D02*
X1721431D01*
G01X1727517Y239423D02*
X1715670D01*
G01X1717830Y241074D02*
X1714986D01*
G01X1715670Y239423D02*
X1712603Y236356D01*
G01D02*
Y225189D01*
G01X1841277Y-10906D02*
X1830561Y-21622D01*
G01X1839626Y-10222D02*
X1829877Y-19971D01*
G01X1839626Y-10222D02*
X1829877Y-19971D01*
G01X1841277Y-10906D02*
X1830561Y-21622D01*
G01X1838115Y1551D02*
X1832551D01*
G01X1838799Y-100D02*
X1833235D01*
G01X1832551Y1551D02*
X1821773Y-9227D01*
G01X1833235Y-100D02*
X1822457Y-10878D01*
G01X1838799Y-100D02*
X1833235D01*
G01X1838115Y1551D02*
X1832551D01*
G01X1833235Y-100D02*
X1822457Y-10878D01*
G01X1832551Y1551D02*
X1821773Y-9227D01*
G01X1774473Y217135D02*
X1798295D01*
G01D02*
X1813956Y232796D01*
G01X1798979Y215484D02*
X1815607Y232112D01*
G01X1774473Y217135D02*
X1798295D01*
G01X1798979Y215484D02*
X1815607Y232112D01*
G01X1798295Y217135D02*
X1813956Y232796D01*
G01X1776125Y237313D02*
Y233056D01*
G01X1777776Y232372D02*
Y237313D01*
G01Y232372D02*
Y237313D01*
G01X1776125D02*
Y233056D01*
G01X1813956Y232796D02*
Y248824D01*
G01X1815607Y232112D02*
Y248823D01*
G01Y232112D02*
Y248823D01*
G01X1813956Y232796D02*
Y248824D01*
G01X1795058D02*
Y247451D01*
G01X1796709Y248823D02*
Y246767D01*
G01X1795058Y247451D02*
X1794266Y246659D01*
G01X1796709Y246767D02*
X1794950Y245008D01*
G01X1796709Y248823D02*
Y246767D01*
G01X1795058Y248824D02*
Y247451D01*
G01X1796709Y246767D02*
X1794950Y245008D01*
G01X1795058Y247451D02*
X1794266Y246659D01*
G01X1899006Y-17661D02*
X1889207D01*
G01X1899006Y-16010D02*
X1889891D01*
G01X1889207Y-17661D02*
X1886279Y-14733D01*
G01X1889891Y-16010D02*
X1887930Y-14049D01*
G01X1886279Y-14733D02*
Y-1289D01*
G01X1887930Y-14049D02*
Y-605D01*
G01X1886279Y-1289D02*
X1876088Y8902D01*
G01X1887930Y-605D02*
X1876772Y10553D01*
G01X1876088Y8902D02*
X1855900D01*
G01X1876772Y10553D02*
X1855216D01*
G01X1855900Y8902D02*
X1852188Y5190D01*
G01X1855216Y10553D02*
X1851504Y6841D01*
G01X1852188Y5190D02*
X1849490D01*
G01X1851504Y6841D02*
X1848806D01*
G01X1849490Y5190D02*
X1841277Y-3023D01*
G01X1848806Y6841D02*
X1839626Y-2339D01*
G01X1841277Y-3023D02*
Y-10906D01*
G01X1839626Y-2339D02*
Y-10222D01*
G01X1899006Y-16010D02*
X1889891D01*
G01X1899006Y-17661D02*
X1889207D01*
G01X1889891Y-16010D02*
X1887930Y-14049D01*
G01X1889207Y-17661D02*
X1886279Y-14733D01*
G01X1887930Y-14049D02*
Y-605D01*
G01X1886279Y-14733D02*
Y-1289D01*
G01X1887930Y-605D02*
X1876772Y10553D01*
G01X1886279Y-1289D02*
X1876088Y8902D01*
G01X1876772Y10553D02*
X1855216D01*
G01X1876088Y8902D02*
X1855900D01*
G01X1855216Y10553D02*
X1851504Y6841D01*
G01X1855900Y8902D02*
X1852188Y5190D01*
G01X1851504Y6841D02*
X1848806D01*
G01X1852188Y5190D02*
X1849490D01*
G01X1848806Y6841D02*
X1839626Y-2339D01*
G01X1849490Y5190D02*
X1841277Y-3023D01*
G01X1839626Y-2339D02*
Y-10222D01*
G01X1841277Y-3023D02*
Y-10906D01*
G01X1869937Y14412D02*
Y15340D01*
G01X1868286Y12848D02*
Y14656D01*
G01X1869937Y15340D02*
X1867293Y17984D01*
G01X1868286Y14656D02*
X1866609Y16333D01*
G01X1867293Y17984D02*
X1856333D01*
G01X1866609Y16333D02*
X1857017D01*
G01X1856333Y17984D02*
X1849341Y10992D01*
G01X1857017Y16333D02*
X1850025Y9341D01*
G01X1849341Y10992D02*
X1847556D01*
G01X1850025Y9341D02*
X1848240D01*
G01X1847556Y10992D02*
X1838115Y1551D01*
G01X1848240Y9341D02*
X1838799Y-100D01*
G01X1868286Y12848D02*
Y14656D01*
G01X1869937Y14412D02*
Y15340D01*
G01X1868286Y14656D02*
X1866609Y16333D01*
G01X1869937Y15340D02*
X1867293Y17984D01*
G01X1866609Y16333D02*
X1857017D01*
G01X1867293Y17984D02*
X1856333D01*
G01X1857017Y16333D02*
X1850025Y9341D01*
G01X1856333Y17984D02*
X1849341Y10992D01*
G01X1850025Y9341D02*
X1848240D01*
G01X1849341Y10992D02*
X1847556D01*
G01X1848240Y9341D02*
X1838799Y-100D01*
G01X1847556Y10992D02*
X1838115Y1551D01*
M02*
